G04 ================== begin FILE IDENTIFICATION RECORD ==================*
G04 Layout Name:  15968-1a.brd*
G04 Film Name:    NOTICE*
G04 File Format:  Gerber RS274X*
G04 File Origin:  Cadence Allegro 16.5-S058*
G04 Origin Date:  Fri Oct 14 10:23:35 2016*
G04 *
G04 Layer:  MANUFACTURING/THERMAL*
G04 *
G04 Offset:    (0.00 0.00)*
G04 Mirror:    No*
G04 Mode:      Positive*
G04 Rotation:  0*
G04 FullContactRelief:  No*
G04 UndefLineWidth:     6.00*
G04 ================== end FILE IDENTIFICATION RECORD ====================*
%FSLAX35Y35*MOIN*%
%IR0*IPPOS*OFA0.00000B0.00000*MIA0B0*SFA1.00000B1.00000*%
%ADD10C,.004*%
%ADD11C,.006*%
%ADD12C,.0033*%
%ADD13C,.008*%
%ADD14C,.0055*%
G75*
%LPD*%
G75*
G36*
G01X301800Y213890D02*
G02X352500Y214150I25558J-40503D01*
G01X341350Y192820D01*
X312850D01*
X301800Y213890D01*
G37*
G36*
G01X298620Y274980D02*
X307300D01*
G03X341410Y274970I17058J11442D01*
G01X348960D01*
X338090Y253970D01*
X309590D01*
X298620Y274980D01*
G37*
G36*
G01X301800Y213890D02*
G02X352500Y214150I25558J-40503D01*
G01X341350Y192820D01*
X312850D01*
X301800Y213890D01*
G37*
G36*
G01X298620Y274980D02*
X307300D01*
G03X341410Y274970I17058J11442D01*
G01X348960D01*
X338090Y253970D01*
X309590D01*
X298620Y274980D01*
G37*
G54D10*
G01X820594Y153868D02*
X808594Y155868D01*
G01X820009Y224740D02*
Y167889D01*
G01X820594Y161868D02*
Y141868D01*
G01X808594Y155868D02*
Y151868D01*
G01D02*
X820594Y153868D01*
G01X790009Y177889D02*
Y207889D01*
G01X796594Y153868D02*
X820594D01*
G01X770009Y177889D02*
X790009D01*
G01X820009Y167889D02*
X770009D01*
G01D02*
Y177889D01*
G01X820594Y153868D02*
X808594Y155868D01*
G01X820009Y224740D02*
Y167889D01*
G01X820594Y161868D02*
Y141868D01*
G01X808594Y155868D02*
Y151868D01*
G01D02*
X820594Y153868D01*
G01X790009Y177889D02*
Y207889D01*
G01X796594Y153868D02*
X820594D01*
G01X770009Y177889D02*
X790009D01*
G01X820009Y167889D02*
X770009D01*
G01D02*
Y177889D01*
G01X810005Y234744D02*
X810009Y234740D01*
G01Y297889D02*
Y234740D01*
G01D02*
X820009Y224740D01*
G01X790009Y257889D02*
Y287889D01*
G01Y217889D02*
Y247889D01*
G01X770009Y257889D02*
X790009D01*
G01X770009Y247889D02*
Y257889D01*
G01X790009Y247889D02*
X770009D01*
G01Y217889D02*
X790009D01*
G01X770009Y207889D02*
Y217889D01*
G01X790009Y207889D02*
X770009D01*
G01X810005Y234744D02*
X810009Y234740D01*
G01Y297889D02*
Y234740D01*
G01D02*
X820009Y224740D01*
G01X790009Y257889D02*
Y287889D01*
G01Y217889D02*
Y247889D01*
G01X770009Y257889D02*
X790009D01*
G01X770009Y247889D02*
Y257889D01*
G01X790009Y247889D02*
X770009D01*
G01Y217889D02*
X790009D01*
G01X770009Y207889D02*
Y217889D01*
G01X790009Y207889D02*
X770009D01*
G01X810514Y319548D02*
Y299548D01*
G01X822514Y305548D02*
Y309548D01*
G01X810514Y307548D02*
X822514Y305548D01*
G01Y309548D02*
X810514Y307548D01*
G01D02*
X850514D01*
G01X770009Y297889D02*
X810009D01*
G01X770009Y287889D02*
Y297889D01*
G01X790009Y287889D02*
X770009D01*
G01X810514Y319548D02*
Y299548D01*
G01X822514Y305548D02*
Y309548D01*
G01X810514Y307548D02*
X822514Y305548D01*
G01Y309548D02*
X810514Y307548D01*
G01D02*
X850514D01*
G01X770009Y297889D02*
X810009D01*
G01X770009Y287889D02*
Y297889D01*
G01X790009Y287889D02*
X770009D01*
G01X890009Y167889D02*
Y177889D01*
G01X870009D02*
Y207889D01*
G01X890009Y177889D02*
X870009D01*
G01X852594Y151868D02*
Y155868D01*
G01X840009Y167889D02*
X890009D01*
G01X840009Y225249D02*
Y167889D01*
G01X859454Y153868D02*
X840594D01*
G01X852594Y155868D02*
X840594Y153868D01*
G01Y141868D02*
Y161868D01*
G01Y153868D02*
X852594Y151868D01*
G01X890009Y167889D02*
Y177889D01*
G01X870009D02*
Y207889D01*
G01X890009Y177889D02*
X870009D01*
G01X852594Y151868D02*
Y155868D01*
G01X840009Y167889D02*
X890009D01*
G01X840009Y225249D02*
Y167889D01*
G01X859454Y153868D02*
X840594D01*
G01X852594Y155868D02*
X840594Y153868D01*
G01Y141868D02*
Y161868D01*
G01Y153868D02*
X852594Y151868D01*
G01X895009Y217889D02*
X961000D01*
G01X845009Y225249D02*
X961000D01*
G01X890009Y247889D02*
Y257889D01*
G01Y207889D02*
X890000Y217800D01*
G01X870009Y257889D02*
Y287889D01*
G01X890009Y257889D02*
X870009D01*
G01Y247889D02*
X890009D01*
G01X870009Y217889D02*
Y247889D01*
G01X890009Y217889D02*
X870009D01*
G01Y207889D02*
X890009D01*
G01X850009Y297889D02*
Y235249D01*
G01D02*
X840009Y225249D01*
G01X895009Y217889D02*
X961000D01*
G01X845009Y225249D02*
X961000D01*
G01X890009Y247889D02*
Y257889D01*
G01Y207889D02*
X890000Y217800D01*
G01X870009Y257889D02*
Y287889D01*
G01X890009Y257889D02*
X870009D01*
G01Y247889D02*
X890009D01*
G01X870009Y217889D02*
Y247889D01*
G01X890009Y217889D02*
X870009D01*
G01Y207889D02*
X890009D01*
G01X850009Y297889D02*
Y235249D01*
G01D02*
X840009Y225249D01*
G01X890009Y287889D02*
Y297889D01*
G01X870009Y287889D02*
X890009D01*
G01X850514Y319548D02*
Y299548D01*
G01Y307548D02*
X859374D01*
G01X838514Y309548D02*
Y305548D01*
G01X850514Y307548D02*
X838514Y309548D01*
G01Y305548D02*
X850514Y307548D01*
G01X890009Y297889D02*
X850009D01*
G01X890009Y287889D02*
Y297889D01*
G01X870009Y287889D02*
X890009D01*
G01X850514Y319548D02*
Y299548D01*
G01Y307548D02*
X859374D01*
G01X838514Y309548D02*
Y305548D01*
G01X850514Y307548D02*
X838514Y309548D01*
G01Y305548D02*
X850514Y307548D01*
G01X890009Y297889D02*
X850009D01*
G01X954000Y237249D02*
X956000Y225249D01*
X958000Y237249D01*
X954000D01*
G01X956000Y249249D02*
Y225249D01*
G01X958000Y205889D02*
X956000Y217889D01*
X954000Y205889D01*
X958000D01*
G01X956000Y193889D02*
Y217889D01*
G01X954000Y237249D02*
X956000Y225249D01*
X958000Y237249D01*
X954000D01*
G01X956000Y249249D02*
Y225249D01*
G01X958000Y205889D02*
X956000Y217889D01*
X954000Y205889D01*
X958000D01*
G01X956000Y193889D02*
Y217889D01*
G01X1121654Y169388D02*
Y232028D01*
G01X1133654Y149388D02*
Y153388D01*
G01X1121654Y151388D02*
X1133654Y149388D01*
G01Y153388D02*
X1121654Y151388D01*
G01D02*
X1161654D01*
G01X1121654Y163388D02*
Y143388D01*
G01X1101654Y209388D02*
Y179388D01*
G01D02*
X1081654D01*
G01Y169388D02*
X1121654D01*
G01X1081654Y179388D02*
Y169388D01*
G01X1121654D02*
Y232028D01*
G01X1133654Y149388D02*
Y153388D01*
G01X1121654Y151388D02*
X1133654Y149388D01*
G01Y153388D02*
X1121654Y151388D01*
G01D02*
X1161654D01*
G01X1121654Y163388D02*
Y143388D01*
G01X1101654Y209388D02*
Y179388D01*
G01D02*
X1081654D01*
G01Y169388D02*
X1121654D01*
G01X1081654Y179388D02*
Y169388D01*
G01X1131654Y242028D02*
Y299388D01*
G01X1121654Y232028D02*
X1131654Y242028D01*
G01X1101654Y289388D02*
Y259388D01*
G01Y249388D02*
Y219388D01*
G01X1081654Y249388D02*
X1101654D01*
G01X1081654Y259388D02*
Y249388D01*
G01X1101654Y259388D02*
X1081654D01*
G01Y209388D02*
X1101654D01*
G01X1081654Y219388D02*
Y209388D01*
G01X1101654Y219388D02*
X1081654D01*
G01X1131654Y242028D02*
Y299388D01*
G01X1121654Y232028D02*
X1131654Y242028D01*
G01X1101654Y289388D02*
Y259388D01*
G01Y249388D02*
Y219388D01*
G01X1081654Y249388D02*
X1101654D01*
G01X1081654Y259388D02*
Y249388D01*
G01X1101654Y259388D02*
X1081654D01*
G01Y209388D02*
X1101654D01*
G01X1081654Y219388D02*
Y209388D01*
G01X1101654Y219388D02*
X1081654D01*
G01X1119654Y321388D02*
Y317388D01*
G01X1131654Y319388D02*
X1119654Y321388D01*
G01Y317388D02*
X1131654Y319388D01*
G01Y327388D02*
Y307388D01*
G01X1107654Y319388D02*
X1131654D01*
G01Y299388D02*
X1081654D01*
G01Y289388D02*
X1101654D01*
G01X1081654Y299388D02*
Y289388D01*
G01X1119654Y321388D02*
Y317388D01*
G01X1131654Y319388D02*
X1119654Y321388D01*
G01Y317388D02*
X1131654Y319388D01*
G01Y327388D02*
Y307388D01*
G01X1107654Y319388D02*
X1131654D01*
G01Y299388D02*
X1081654D01*
G01Y289388D02*
X1101654D01*
G01X1081654Y299388D02*
Y289388D01*
G01X1201654Y179388D02*
Y169388D01*
G01X1181654Y179388D02*
X1201654D01*
G01X1181654Y209388D02*
Y179388D01*
G01X1161654Y169388D02*
Y232537D01*
G01X1201654Y169388D02*
X1161654D01*
G01X1149654Y153388D02*
Y149388D01*
G01X1161654Y151388D02*
X1149654Y153388D01*
G01Y149388D02*
X1161654Y151388D01*
G01D02*
X1170514D01*
G01X1161654Y163388D02*
Y143388D01*
G01X1201654Y179388D02*
Y169388D01*
G01X1181654Y179388D02*
X1201654D01*
G01X1181654Y209388D02*
Y179388D01*
G01X1161654Y169388D02*
Y232537D01*
G01X1201654Y169388D02*
X1161654D01*
G01X1149654Y153388D02*
Y149388D01*
G01X1161654Y151388D02*
X1149654Y153388D01*
G01Y149388D02*
X1161654Y151388D01*
G01D02*
X1170514D01*
G01X1161654Y163388D02*
Y143388D01*
G01X1201654Y259388D02*
Y249388D01*
G01Y219388D02*
Y209388D01*
G01Y249388D02*
X1181654D01*
G01Y259388D02*
X1201654D01*
G01X1181654Y289388D02*
Y259388D01*
G01X1201654Y209388D02*
X1181654D01*
G01Y219388D02*
X1201654D01*
G01X1181654Y249388D02*
Y219388D01*
G01X1161658Y232533D02*
X1161654Y232537D01*
G01X1151654Y242537D02*
Y299388D01*
G01X1161654Y232537D02*
X1151654Y242537D01*
G01X1201654Y259388D02*
Y249388D01*
G01Y219388D02*
Y209388D01*
G01Y249388D02*
X1181654D01*
G01Y259388D02*
X1201654D01*
G01X1181654Y289388D02*
Y259388D01*
G01X1201654Y209388D02*
X1181654D01*
G01Y219388D02*
X1201654D01*
G01X1181654Y249388D02*
Y219388D01*
G01X1161658Y232533D02*
X1161654Y232537D01*
G01X1151654Y242537D02*
Y299388D01*
G01X1161654Y232537D02*
X1151654Y242537D01*
G01X1201654Y299388D02*
Y289388D01*
G01X1163654Y317388D02*
Y321388D01*
G01X1201654Y289388D02*
X1181654D01*
G01X1170514Y319388D02*
X1151654D01*
G01D02*
X1163654Y317388D01*
G01Y321388D02*
X1151654Y319388D01*
G01Y307388D02*
Y327388D01*
G01Y299388D02*
X1201654D01*
G01D02*
Y289388D01*
G01X1163654Y317388D02*
Y321388D01*
G01X1201654Y289388D02*
X1181654D01*
G01X1170514Y319388D02*
X1151654D01*
G01D02*
X1163654Y317388D01*
G01Y321388D02*
X1151654Y319388D01*
G01Y307388D02*
Y327388D01*
G01Y299388D02*
X1201654D01*
G54D11*
G01X4300Y524700D02*
X4250D01*
G01X4300D02*
X4250D01*
G01X54300Y770700D02*
X54250D01*
G01X54300D02*
X54250D01*
G01X332370Y221310D02*
X388140D01*
G01X285090Y269970D02*
X280090D01*
Y243970D01*
X285090D01*
G01Y248970D02*
X304590D01*
X293590Y269970D01*
X285090D01*
Y274970D01*
X298590D01*
X309590Y253970D01*
X338090D01*
X349090Y274970D01*
X362590D01*
Y269970D01*
X354090D01*
X343090Y248970D01*
X362590D01*
G01X285090D02*
Y243970D01*
X362590D01*
Y248970D01*
G01X288350Y208820D02*
X283350D01*
Y182820D01*
X288350D01*
G01Y187820D02*
X307850D01*
X296850Y208820D01*
X288350D01*
Y213820D01*
X301850D01*
X312850Y192820D01*
X341350D01*
X352350Y213820D01*
X365850D01*
Y208820D01*
X357350D01*
X346350Y187820D01*
X365850D01*
G01X288350D02*
Y182820D01*
X365850D01*
Y187820D01*
G01X332370Y221310D02*
X388140D01*
G01X285090Y269970D02*
X280090D01*
Y243970D01*
X285090D01*
G01Y248970D02*
X304590D01*
X293590Y269970D01*
X285090D01*
Y274970D01*
X298590D01*
X309590Y253970D01*
X338090D01*
X349090Y274970D01*
X362590D01*
Y269970D01*
X354090D01*
X343090Y248970D01*
X362590D01*
G01X285090D02*
Y243970D01*
X362590D01*
Y248970D01*
G01X288350Y208820D02*
X283350D01*
Y182820D01*
X288350D01*
G01Y187820D02*
X307850D01*
X296850Y208820D01*
X288350D01*
Y213820D01*
X301850D01*
X312850Y192820D01*
X341350D01*
X352350Y213820D01*
X365850D01*
Y208820D01*
X357350D01*
X346350Y187820D01*
X365850D01*
G01X288350D02*
Y182820D01*
X365850D01*
Y187820D01*
G01X329290Y266000D02*
X387990D01*
G01X346210Y275010D02*
X387990D01*
G01X329590Y306830D02*
X341590Y308830D01*
X329590Y310830D01*
Y306830D01*
G01X339890Y308830D02*
X341590D01*
G01X315090Y310830D02*
X303090Y308830D01*
X315090Y306830D01*
Y310830D01*
G01X306290Y308830D02*
X303090D01*
G01X339590D02*
X304090D01*
G01X283590Y340830D02*
X278590D01*
Y314830D01*
X283590D01*
G01Y319830D02*
Y314830D01*
X361090D01*
Y319830D01*
G01X283590D02*
X303090D01*
X292090Y340830D01*
X283590D01*
Y345830D01*
X297090D01*
X308090Y324830D01*
X336590D01*
X347590Y345830D01*
X361090D01*
Y340830D01*
X352590D01*
X341590Y319830D01*
X361090D01*
G01X329290Y266000D02*
X387990D01*
G01X346210Y275010D02*
X387990D01*
G01X329590Y306830D02*
X341590Y308830D01*
X329590Y310830D01*
Y306830D01*
G01X339890Y308830D02*
X341590D01*
G01X315090Y310830D02*
X303090Y308830D01*
X315090Y306830D01*
Y310830D01*
G01X306290Y308830D02*
X303090D01*
G01X339590D02*
X304090D01*
G01X283590Y340830D02*
X278590D01*
Y314830D01*
X283590D01*
G01Y319830D02*
Y314830D01*
X361090D01*
Y319830D01*
G01X283590D02*
X303090D01*
X292090Y340830D01*
X283590D01*
Y345830D01*
X297090D01*
X308090Y324830D01*
X336590D01*
X347590Y345830D01*
X361090D01*
Y340830D01*
X352590D01*
X341590Y319830D01*
X361090D01*
G01X340590Y350830D02*
X352590Y352830D01*
X340590Y354830D01*
Y350830D01*
G01X334890Y352830D02*
X352590D01*
G01X304090Y354830D02*
X292090Y352830D01*
X304090Y350830D01*
Y354830D01*
G01X311290Y352830D02*
X292090D01*
G01X340590Y350830D02*
X352590Y352830D01*
X340590Y354830D01*
Y350830D01*
G01X334890Y352830D02*
X352590D01*
G01X304090Y354830D02*
X292090Y352830D01*
X304090Y350830D01*
Y354830D01*
G01X311290Y352830D02*
X292090D01*
G01X385140Y233310D02*
X383140Y221310D01*
X381140Y233310D01*
X385140D01*
G01X383140Y237850D02*
Y221310D01*
G01X385140Y202130D02*
X383140Y214130D01*
X381140Y202130D01*
X385140D01*
G01X383140Y197250D02*
Y214130D01*
G01X357370D02*
X388140D01*
G01X384990Y254000D02*
X382990Y266000D01*
X380990Y254000D01*
X384990D01*
G01X382990Y250500D02*
Y266000D01*
G01X362590Y269970D02*
X367590D01*
Y243970D01*
X362590D01*
G01X365850Y208820D02*
X370850D01*
Y182820D01*
X365850D01*
G01X385140Y233310D02*
X383140Y221310D01*
X381140Y233310D01*
X385140D01*
G01X383140Y237850D02*
Y221310D01*
G01X385140Y202130D02*
X383140Y214130D01*
X381140Y202130D01*
X385140D01*
G01X383140Y197250D02*
Y214130D01*
G01X357370D02*
X388140D01*
G01X384990Y254000D02*
X382990Y266000D01*
X380990Y254000D01*
X384990D01*
G01X382990Y250500D02*
Y266000D01*
G01X362590Y269970D02*
X367590D01*
Y243970D01*
X362590D01*
G01X365850Y208820D02*
X370850D01*
Y182820D01*
X365850D01*
G01X384990Y287010D02*
X382990Y275010D01*
X380990Y287010D01*
X384990D01*
G01X382990Y275010D02*
Y290150D01*
G01X361090Y340830D02*
X366090D01*
Y314830D01*
X361090D01*
G01X384990Y287010D02*
X382990Y275010D01*
X380990Y287010D01*
X384990D01*
G01X382990Y275010D02*
Y290150D01*
G01X361090Y340830D02*
X366090D01*
Y314830D01*
X361090D01*
G01X849500Y-12451D02*
X821000Y-12500D01*
G01X849500Y-12451D02*
X821000Y-12500D01*
G01X931340Y624629D02*
X820000D01*
G01X931340D02*
X820000D01*
G01X846340Y725829D02*
X820000D01*
G01X846340D02*
X820000D01*
G01X849500Y-12500D02*
Y59500D01*
X893500D01*
Y-12500D01*
X849500D01*
G01X837503Y-14472D02*
X849500Y-12451D01*
X837497Y-10472D01*
X837503Y-14472D01*
G01X903500Y-12500D02*
X944500D01*
G01X849500D02*
Y59500D01*
X893500D01*
Y-12500D01*
X849500D01*
G01X837503Y-14472D02*
X849500Y-12451D01*
X837497Y-10472D01*
X837503Y-14472D01*
G01X903500Y-12500D02*
X944500D01*
G01X903500Y59500D02*
X944500D01*
G01X878500Y67000D02*
X893500Y69500D01*
X878500Y72000D01*
Y67000D01*
G01X901475Y69500D02*
X893500D01*
G01X864500Y72000D02*
X849500Y69500D01*
X864500Y67000D01*
Y72000D01*
G01X893500Y69500D02*
X849500D01*
G01X893500Y64500D02*
Y79500D01*
G01X849500Y64500D02*
Y79500D01*
G01X903500Y59500D02*
X944500D01*
G01X878500Y67000D02*
X893500Y69500D01*
X878500Y72000D01*
Y67000D01*
G01X901475Y69500D02*
X893500D01*
G01X864500Y72000D02*
X849500Y69500D01*
X864500Y67000D01*
Y72000D01*
G01X893500Y69500D02*
X849500D01*
G01X893500Y64500D02*
Y79500D01*
G01X849500Y64500D02*
Y79500D01*
G01X827500Y639629D02*
X830000Y624629D01*
X832500Y639629D01*
X827500D01*
G01X830000Y661875D02*
Y624629D01*
G01X827500Y639629D02*
X830000Y624629D01*
X832500Y639629D01*
X827500D01*
G01X830000Y661875D02*
Y624629D01*
G01X832500Y710829D02*
X830000Y725829D01*
X827500Y710829D01*
X832500D01*
G01X830000Y693125D02*
Y725829D01*
G01X832500Y710829D02*
X830000Y725829D01*
X827500Y710829D01*
X832500D01*
G01X830000Y693125D02*
Y725829D01*
G01X932000Y2500D02*
X934500Y-12500D01*
X937000Y2500D01*
X932000D01*
G01X934500Y11875D02*
Y-12500D01*
G01X932000Y2500D02*
X934500Y-12500D01*
X937000Y2500D01*
X932000D01*
G01X934500Y11875D02*
Y-12500D01*
G01X937000Y44500D02*
X934500Y59500D01*
X932000Y44500D01*
X937000D01*
G01X934500Y43125D02*
Y59500D01*
G01X937000Y44500D02*
X934500Y59500D01*
X932000Y44500D01*
X937000D01*
G01X934500Y43125D02*
Y59500D01*
G01X1114953Y628479D02*
X1131500Y617000D01*
X1132500D01*
G01X1119916Y626861D02*
X1114953Y628479D01*
X1118206Y624397D01*
X1119916Y626861D01*
G01X1114953Y628479D02*
X1131500Y617000D01*
X1132500D01*
G01X1119916Y626861D02*
X1114953Y628479D01*
X1118206Y624397D01*
X1119916Y626861D01*
G01X1156654Y242537D02*
X1274500D01*
G01X1206654Y249388D02*
X1274500D01*
G01X1156654Y242537D02*
X1274500D01*
G01X1206654Y249388D02*
X1274500D01*
G01X1267500Y261388D02*
X1269500Y249388D01*
X1271500Y261388D01*
X1267500D01*
G01X1269500Y277200D02*
Y249388D01*
G01X1271500Y230537D02*
X1269500Y242537D01*
X1267500Y230537D01*
X1271500D01*
G01X1269500Y218537D02*
Y242537D01*
G01X1267500Y261388D02*
X1269500Y249388D01*
X1271500Y261388D01*
X1267500D01*
G01X1269500Y277200D02*
Y249388D01*
G01X1271500Y230537D02*
X1269500Y242537D01*
X1267500Y230537D01*
X1271500D01*
G01X1269500Y218537D02*
Y242537D01*
G01X0Y716000D02*
Y-69500D01*
G01D02*
X694500D01*
G01X0Y716000D02*
Y-69500D01*
G01D02*
X694500D01*
G01X11750Y-48833D02*
X12417Y-49250D01*
X13167Y-49500D01*
X13833D01*
X14500Y-49250D01*
X15000Y-48833D01*
X15250Y-48250D01*
X15083Y-47667D01*
X14667Y-47167D01*
X13917Y-46833D01*
X12917Y-46667D01*
X12333Y-46333D01*
X12083Y-45750D01*
X12250Y-45167D01*
X12667Y-44750D01*
X13250Y-44500D01*
X13833D01*
X14417Y-44667D01*
X14917Y-45083D01*
G01X19100Y-46167D02*
Y-49500D01*
G01Y-44833D02*
X18933Y-44750D01*
Y-44583D01*
X19100Y-44500D01*
X19267Y-44583D01*
Y-44750D01*
X19100Y-44833D01*
G01X24700Y-49500D02*
Y-44500D01*
G01X28883Y-49500D02*
Y-44500D01*
G01X31550Y-46167D02*
X28883Y-48083D01*
G01X29967Y-47333D02*
X31717Y-49500D01*
G01X34650Y-48917D02*
X35067Y-49250D01*
X35650Y-49500D01*
X36150D01*
X36650Y-49333D01*
X36983Y-49083D01*
X37150Y-48750D01*
X37067Y-48250D01*
X36733Y-48000D01*
X35233Y-47500D01*
X34900Y-46917D01*
X35067Y-46500D01*
X35400Y-46250D01*
X35900Y-46167D01*
X36400Y-46250D01*
X36900Y-46500D01*
G01X42833Y-46583D02*
X42250Y-46250D01*
X41750Y-46167D01*
X41083Y-46333D01*
X40583Y-46667D01*
X40250Y-47250D01*
X40167Y-47833D01*
X40250Y-48417D01*
X40583Y-48917D01*
X41083Y-49333D01*
X41750Y-49500D01*
X42333Y-49333D01*
X42833Y-49000D01*
G01X45933Y-49500D02*
Y-46167D01*
G01Y-46833D02*
X46350Y-46500D01*
X46767Y-46250D01*
X47350Y-46167D01*
X47767Y-46250D01*
X48267Y-46500D01*
G01X51450Y-47250D02*
X54117D01*
X53867Y-46667D01*
X53450Y-46333D01*
X52867Y-46167D01*
X52283Y-46250D01*
X51783Y-46500D01*
X51450Y-47083D01*
X51283Y-47583D01*
Y-48083D01*
X51450Y-48583D01*
X51867Y-49083D01*
X52367Y-49417D01*
X52950Y-49500D01*
X53533Y-49333D01*
X54117Y-48833D01*
G01X57050Y-47250D02*
X59717D01*
X59467Y-46667D01*
X59050Y-46333D01*
X58467Y-46167D01*
X57883Y-46250D01*
X57383Y-46500D01*
X57050Y-47083D01*
X56883Y-47583D01*
Y-48083D01*
X57050Y-48583D01*
X57467Y-49083D01*
X57967Y-49417D01*
X58550Y-49500D01*
X59133Y-49333D01*
X59717Y-48833D01*
G01X62483Y-49500D02*
Y-46167D01*
G01Y-47000D02*
X62817Y-46583D01*
X63317Y-46250D01*
X63983Y-46167D01*
X64567Y-46250D01*
X65067Y-46583D01*
X65317Y-47167D01*
Y-49500D01*
G01X11750Y-3833D02*
X12417Y-4250D01*
X13167Y-4500D01*
X13833D01*
X14500Y-4250D01*
X15000Y-3833D01*
X15250Y-3250D01*
X15083Y-2667D01*
X14667Y-2167D01*
X13917Y-1833D01*
X12917Y-1667D01*
X12333Y-1333D01*
X12083Y-750D01*
X12250Y-167D01*
X12667Y250D01*
X13250Y500D01*
X13833D01*
X14417Y333D01*
X14917Y-83D01*
G01X19100Y-4500D02*
X18600Y-4417D01*
X18100Y-4083D01*
X17767Y-3500D01*
X17600Y-2833D01*
X17767Y-2167D01*
X18100Y-1583D01*
X18600Y-1250D01*
X19100Y-1167D01*
X19600Y-1250D01*
X20100Y-1583D01*
X20433Y-2167D01*
X20517Y-2833D01*
X20433Y-3500D01*
X20100Y-4083D01*
X19600Y-4417D01*
X19100Y-4500D01*
G01X24700D02*
Y500D01*
G01X31800D02*
Y-4500D01*
G01Y-3750D02*
X31467Y-4167D01*
X30967Y-4417D01*
X30383Y-4500D01*
X29717Y-4333D01*
X29217Y-3917D01*
X28883Y-3417D01*
X28800Y-2833D01*
X28883Y-2250D01*
X29217Y-1750D01*
X29717Y-1333D01*
X30383Y-1167D01*
X30967Y-1250D01*
X31383Y-1417D01*
X31800Y-1750D01*
G01X34650Y-2250D02*
X37317D01*
X37067Y-1667D01*
X36650Y-1333D01*
X36067Y-1167D01*
X35483Y-1250D01*
X34983Y-1500D01*
X34650Y-2083D01*
X34483Y-2583D01*
Y-3083D01*
X34650Y-3583D01*
X35067Y-4083D01*
X35567Y-4417D01*
X36150Y-4500D01*
X36733Y-4333D01*
X37317Y-3833D01*
G01X40333Y-4500D02*
Y-1167D01*
G01Y-1833D02*
X40750Y-1500D01*
X41167Y-1250D01*
X41750Y-1167D01*
X42167Y-1250D01*
X42667Y-1500D01*
G01X50200Y-4500D02*
Y-1167D01*
G01Y-2083D02*
X50450Y-1667D01*
X50867Y-1333D01*
X51450Y-1167D01*
X52033Y-1333D01*
X52450Y-1667D01*
X52700Y-2083D01*
Y-4500D01*
G01Y-2083D02*
X52950Y-1667D01*
X53367Y-1333D01*
X53950Y-1167D01*
X54533Y-1333D01*
X54950Y-1667D01*
X55200Y-2167D01*
Y-4500D01*
G01X59800D02*
Y-1167D01*
G01Y-1750D02*
X59467Y-1417D01*
X58967Y-1250D01*
X58383Y-1167D01*
X57800Y-1333D01*
X57300Y-1667D01*
X56967Y-2167D01*
X56800Y-2833D01*
X56967Y-3500D01*
X57300Y-4000D01*
X57800Y-4333D01*
X58383Y-4500D01*
X58967Y-4417D01*
X59467Y-4167D01*
X59800Y-3833D01*
G01X62650Y-3917D02*
X63067Y-4250D01*
X63650Y-4500D01*
X64150D01*
X64650Y-4333D01*
X64983Y-4083D01*
X65150Y-3750D01*
X65067Y-3250D01*
X64733Y-3000D01*
X63233Y-2500D01*
X62900Y-1917D01*
X63067Y-1500D01*
X63400Y-1250D01*
X63900Y-1167D01*
X64400Y-1250D01*
X64900Y-1500D01*
G01X68083Y-4500D02*
Y500D01*
G01X70750Y-1167D02*
X68083Y-3083D01*
G01X69167Y-2333D02*
X70917Y-4500D01*
G01X0Y-24500D02*
X694500D01*
G01X0Y19500D02*
X694500D01*
G01X11750Y-48833D02*
X12417Y-49250D01*
X13167Y-49500D01*
X13833D01*
X14500Y-49250D01*
X15000Y-48833D01*
X15250Y-48250D01*
X15083Y-47667D01*
X14667Y-47167D01*
X13917Y-46833D01*
X12917Y-46667D01*
X12333Y-46333D01*
X12083Y-45750D01*
X12250Y-45167D01*
X12667Y-44750D01*
X13250Y-44500D01*
X13833D01*
X14417Y-44667D01*
X14917Y-45083D01*
G01X19100Y-46167D02*
Y-49500D01*
G01Y-44833D02*
X18933Y-44750D01*
Y-44583D01*
X19100Y-44500D01*
X19267Y-44583D01*
Y-44750D01*
X19100Y-44833D01*
G01X24700Y-49500D02*
Y-44500D01*
G01X28883Y-49500D02*
Y-44500D01*
G01X31550Y-46167D02*
X28883Y-48083D01*
G01X29967Y-47333D02*
X31717Y-49500D01*
G01X34650Y-48917D02*
X35067Y-49250D01*
X35650Y-49500D01*
X36150D01*
X36650Y-49333D01*
X36983Y-49083D01*
X37150Y-48750D01*
X37067Y-48250D01*
X36733Y-48000D01*
X35233Y-47500D01*
X34900Y-46917D01*
X35067Y-46500D01*
X35400Y-46250D01*
X35900Y-46167D01*
X36400Y-46250D01*
X36900Y-46500D01*
G01X42833Y-46583D02*
X42250Y-46250D01*
X41750Y-46167D01*
X41083Y-46333D01*
X40583Y-46667D01*
X40250Y-47250D01*
X40167Y-47833D01*
X40250Y-48417D01*
X40583Y-48917D01*
X41083Y-49333D01*
X41750Y-49500D01*
X42333Y-49333D01*
X42833Y-49000D01*
G01X45933Y-49500D02*
Y-46167D01*
G01Y-46833D02*
X46350Y-46500D01*
X46767Y-46250D01*
X47350Y-46167D01*
X47767Y-46250D01*
X48267Y-46500D01*
G01X51450Y-47250D02*
X54117D01*
X53867Y-46667D01*
X53450Y-46333D01*
X52867Y-46167D01*
X52283Y-46250D01*
X51783Y-46500D01*
X51450Y-47083D01*
X51283Y-47583D01*
Y-48083D01*
X51450Y-48583D01*
X51867Y-49083D01*
X52367Y-49417D01*
X52950Y-49500D01*
X53533Y-49333D01*
X54117Y-48833D01*
G01X57050Y-47250D02*
X59717D01*
X59467Y-46667D01*
X59050Y-46333D01*
X58467Y-46167D01*
X57883Y-46250D01*
X57383Y-46500D01*
X57050Y-47083D01*
X56883Y-47583D01*
Y-48083D01*
X57050Y-48583D01*
X57467Y-49083D01*
X57967Y-49417D01*
X58550Y-49500D01*
X59133Y-49333D01*
X59717Y-48833D01*
G01X62483Y-49500D02*
Y-46167D01*
G01Y-47000D02*
X62817Y-46583D01*
X63317Y-46250D01*
X63983Y-46167D01*
X64567Y-46250D01*
X65067Y-46583D01*
X65317Y-47167D01*
Y-49500D01*
G01X11750Y-3833D02*
X12417Y-4250D01*
X13167Y-4500D01*
X13833D01*
X14500Y-4250D01*
X15000Y-3833D01*
X15250Y-3250D01*
X15083Y-2667D01*
X14667Y-2167D01*
X13917Y-1833D01*
X12917Y-1667D01*
X12333Y-1333D01*
X12083Y-750D01*
X12250Y-167D01*
X12667Y250D01*
X13250Y500D01*
X13833D01*
X14417Y333D01*
X14917Y-83D01*
G01X19100Y-4500D02*
X18600Y-4417D01*
X18100Y-4083D01*
X17767Y-3500D01*
X17600Y-2833D01*
X17767Y-2167D01*
X18100Y-1583D01*
X18600Y-1250D01*
X19100Y-1167D01*
X19600Y-1250D01*
X20100Y-1583D01*
X20433Y-2167D01*
X20517Y-2833D01*
X20433Y-3500D01*
X20100Y-4083D01*
X19600Y-4417D01*
X19100Y-4500D01*
G01X24700D02*
Y500D01*
G01X31800D02*
Y-4500D01*
G01Y-3750D02*
X31467Y-4167D01*
X30967Y-4417D01*
X30383Y-4500D01*
X29717Y-4333D01*
X29217Y-3917D01*
X28883Y-3417D01*
X28800Y-2833D01*
X28883Y-2250D01*
X29217Y-1750D01*
X29717Y-1333D01*
X30383Y-1167D01*
X30967Y-1250D01*
X31383Y-1417D01*
X31800Y-1750D01*
G01X34650Y-2250D02*
X37317D01*
X37067Y-1667D01*
X36650Y-1333D01*
X36067Y-1167D01*
X35483Y-1250D01*
X34983Y-1500D01*
X34650Y-2083D01*
X34483Y-2583D01*
Y-3083D01*
X34650Y-3583D01*
X35067Y-4083D01*
X35567Y-4417D01*
X36150Y-4500D01*
X36733Y-4333D01*
X37317Y-3833D01*
G01X40333Y-4500D02*
Y-1167D01*
G01Y-1833D02*
X40750Y-1500D01*
X41167Y-1250D01*
X41750Y-1167D01*
X42167Y-1250D01*
X42667Y-1500D01*
G01X50200Y-4500D02*
Y-1167D01*
G01Y-2083D02*
X50450Y-1667D01*
X50867Y-1333D01*
X51450Y-1167D01*
X52033Y-1333D01*
X52450Y-1667D01*
X52700Y-2083D01*
Y-4500D01*
G01Y-2083D02*
X52950Y-1667D01*
X53367Y-1333D01*
X53950Y-1167D01*
X54533Y-1333D01*
X54950Y-1667D01*
X55200Y-2167D01*
Y-4500D01*
G01X59800D02*
Y-1167D01*
G01Y-1750D02*
X59467Y-1417D01*
X58967Y-1250D01*
X58383Y-1167D01*
X57800Y-1333D01*
X57300Y-1667D01*
X56967Y-2167D01*
X56800Y-2833D01*
X56967Y-3500D01*
X57300Y-4000D01*
X57800Y-4333D01*
X58383Y-4500D01*
X58967Y-4417D01*
X59467Y-4167D01*
X59800Y-3833D01*
G01X62650Y-3917D02*
X63067Y-4250D01*
X63650Y-4500D01*
X64150D01*
X64650Y-4333D01*
X64983Y-4083D01*
X65150Y-3750D01*
X65067Y-3250D01*
X64733Y-3000D01*
X63233Y-2500D01*
X62900Y-1917D01*
X63067Y-1500D01*
X63400Y-1250D01*
X63900Y-1167D01*
X64400Y-1250D01*
X64900Y-1500D01*
G01X68083Y-4500D02*
Y500D01*
G01X70750Y-1167D02*
X68083Y-3083D01*
G01X69167Y-2333D02*
X70917Y-4500D01*
G01X0Y-24500D02*
X694500D01*
G01X0Y19500D02*
X694500D01*
G01X15167Y64000D02*
X11833D01*
Y69000D01*
X15167D01*
G01X13833Y66583D02*
X11833D01*
G01X19100Y69000D02*
Y64000D01*
G01X17933Y67333D02*
X20267D01*
G01X26033Y66917D02*
X25450Y67250D01*
X24950Y67333D01*
X24283Y67167D01*
X23783Y66833D01*
X23450Y66250D01*
X23367Y65667D01*
X23450Y65083D01*
X23783Y64583D01*
X24283Y64167D01*
X24950Y64000D01*
X25533Y64167D01*
X26033Y64500D01*
G01X28883Y64000D02*
Y69000D01*
G01Y66583D02*
X29300Y67000D01*
X29717Y67250D01*
X30383Y67333D01*
X30883Y67250D01*
X31467Y66917D01*
X31717Y66417D01*
Y64000D01*
G01X15167D02*
X11833D01*
Y69000D01*
X15167D01*
G01X13833Y66583D02*
X11833D01*
G01X19100Y69000D02*
Y64000D01*
G01X17933Y67333D02*
X20267D01*
G01X26033Y66917D02*
X25450Y67250D01*
X24950Y67333D01*
X24283Y67167D01*
X23783Y66833D01*
X23450Y66250D01*
X23367Y65667D01*
X23450Y65083D01*
X23783Y64583D01*
X24283Y64167D01*
X24950Y64000D01*
X25533Y64167D01*
X26033Y64500D01*
G01X28883Y64000D02*
Y69000D01*
G01Y66583D02*
X29300Y67000D01*
X29717Y67250D01*
X30383Y67333D01*
X30883Y67250D01*
X31467Y66917D01*
X31717Y66417D01*
Y64000D01*
G01X15167Y111500D02*
X11833D01*
Y116500D01*
X15167D01*
G01X13833Y114083D02*
X11833D01*
G01X17850Y114833D02*
X20350Y111500D01*
G01Y114833D02*
X17850Y111500D01*
G01X24700Y116500D02*
Y111500D01*
G01X23533Y114833D02*
X25867D01*
G01X29050Y113750D02*
X31717D01*
X31467Y114333D01*
X31050Y114667D01*
X30467Y114833D01*
X29883Y114750D01*
X29383Y114500D01*
X29050Y113917D01*
X28883Y113417D01*
Y112917D01*
X29050Y112417D01*
X29467Y111917D01*
X29967Y111583D01*
X30550Y111500D01*
X31133Y111667D01*
X31717Y112167D01*
G01X34733Y111500D02*
Y114833D01*
G01Y114167D02*
X35150Y114500D01*
X35567Y114750D01*
X36150Y114833D01*
X36567Y114750D01*
X37067Y114500D01*
G01X40083Y111500D02*
Y114833D01*
G01Y114000D02*
X40417Y114417D01*
X40917Y114750D01*
X41583Y114833D01*
X42167Y114750D01*
X42667Y114417D01*
X42917Y113833D01*
Y111500D01*
G01X48600D02*
Y114833D01*
G01Y114250D02*
X48267Y114583D01*
X47767Y114750D01*
X47183Y114833D01*
X46600Y114667D01*
X46100Y114333D01*
X45767Y113833D01*
X45600Y113167D01*
X45767Y112500D01*
X46100Y112000D01*
X46600Y111667D01*
X47183Y111500D01*
X47767Y111583D01*
X48267Y111833D01*
X48600Y112167D01*
G01X52700Y111500D02*
Y116500D01*
G01X63900Y111500D02*
Y116500D01*
G01X71000Y111500D02*
Y114833D01*
G01Y114250D02*
X70667Y114583D01*
X70167Y114750D01*
X69583Y114833D01*
X69000Y114667D01*
X68500Y114333D01*
X68167Y113833D01*
X68000Y113167D01*
X68167Y112500D01*
X68500Y112000D01*
X69000Y111667D01*
X69583Y111500D01*
X70167Y111583D01*
X70667Y111833D01*
X71000Y112167D01*
G01X73350Y110000D02*
X73850Y109833D01*
X74517Y110000D01*
X74933Y110333D01*
X75267Y110750D01*
X75767Y112083D01*
X76850Y114833D01*
G01X74183D02*
X75767Y112083D01*
G01X79450Y113750D02*
X82117D01*
X81867Y114333D01*
X81450Y114667D01*
X80867Y114833D01*
X80283Y114750D01*
X79783Y114500D01*
X79450Y113917D01*
X79283Y113417D01*
Y112917D01*
X79450Y112417D01*
X79867Y111917D01*
X80367Y111583D01*
X80950Y111500D01*
X81533Y111667D01*
X82117Y112167D01*
G01X85133Y111500D02*
Y114833D01*
G01Y114167D02*
X85550Y114500D01*
X85967Y114750D01*
X86550Y114833D01*
X86967Y114750D01*
X87467Y114500D01*
G01X15333Y146083D02*
X14833Y146333D01*
X14250Y146500D01*
X13583D01*
X12833Y146250D01*
X12250Y145833D01*
X11833Y145333D01*
X11500Y144500D01*
X11417Y143750D01*
X11583Y143000D01*
X11833Y142500D01*
X12333Y142000D01*
X12917Y141667D01*
X13500Y141500D01*
X14083D01*
X14667Y141667D01*
X15167Y141917D01*
X15583Y142250D01*
G01X19100Y141500D02*
X18600Y141583D01*
X18100Y141917D01*
X17767Y142500D01*
X17600Y143167D01*
X17767Y143833D01*
X18100Y144417D01*
X18600Y144750D01*
X19100Y144833D01*
X19600Y144750D01*
X20100Y144417D01*
X20433Y143833D01*
X20517Y143167D01*
X20433Y142500D01*
X20100Y141917D01*
X19600Y141583D01*
X19100Y141500D01*
G01X23200Y139833D02*
Y144833D01*
G01Y144083D02*
X23617Y144500D01*
X24033Y144750D01*
X24700Y144833D01*
X25283Y144750D01*
X25867Y144333D01*
X26117Y143750D01*
X26200Y143167D01*
X26117Y142583D01*
X25867Y142000D01*
X25367Y141667D01*
X24700Y141500D01*
X24117Y141583D01*
X23533Y141833D01*
X23200Y142167D01*
G01X28800Y139833D02*
Y144833D01*
G01Y144083D02*
X29217Y144500D01*
X29633Y144750D01*
X30300Y144833D01*
X30883Y144750D01*
X31467Y144333D01*
X31717Y143750D01*
X31800Y143167D01*
X31717Y142583D01*
X31467Y142000D01*
X30967Y141667D01*
X30300Y141500D01*
X29717Y141583D01*
X29133Y141833D01*
X28800Y142167D01*
G01X34650Y143750D02*
X37317D01*
X37067Y144333D01*
X36650Y144667D01*
X36067Y144833D01*
X35483Y144750D01*
X34983Y144500D01*
X34650Y143917D01*
X34483Y143417D01*
Y142917D01*
X34650Y142417D01*
X35067Y141917D01*
X35567Y141583D01*
X36150Y141500D01*
X36733Y141667D01*
X37317Y142167D01*
G01X40333Y141500D02*
Y144833D01*
G01Y144167D02*
X40750Y144500D01*
X41167Y144750D01*
X41750Y144833D01*
X42167Y144750D01*
X42667Y144500D01*
G01X51033Y141500D02*
Y146500D01*
X53033D01*
X53700Y146250D01*
X54200Y145667D01*
X54367Y145000D01*
X54200Y144333D01*
X53783Y143833D01*
X53033Y143583D01*
X51033D01*
G01X58300Y141500D02*
Y146500D01*
G01X65400Y141500D02*
Y144833D01*
G01Y144250D02*
X65067Y144583D01*
X64567Y144750D01*
X63983Y144833D01*
X63400Y144667D01*
X62900Y144333D01*
X62567Y143833D01*
X62400Y143167D01*
X62567Y142500D01*
X62900Y142000D01*
X63400Y141667D01*
X63983Y141500D01*
X64567Y141583D01*
X65067Y141833D01*
X65400Y142167D01*
G01X69500Y146500D02*
Y141500D01*
G01X68333Y144833D02*
X70667D01*
G01X75100D02*
Y141500D01*
G01Y146167D02*
X74933Y146250D01*
Y146417D01*
X75100Y146500D01*
X75267Y146417D01*
Y146250D01*
X75100Y146167D01*
G01X79283Y141500D02*
Y144833D01*
G01Y144000D02*
X79617Y144417D01*
X80117Y144750D01*
X80783Y144833D01*
X81367Y144750D01*
X81867Y144417D01*
X82117Y143833D01*
Y141500D01*
G01X85133Y140250D02*
X85717Y139917D01*
X86383Y139833D01*
X86967Y139917D01*
X87467Y140333D01*
X87800Y140917D01*
Y144833D01*
G01Y144167D02*
X87467Y144500D01*
X86967Y144750D01*
X86383Y144833D01*
X85717Y144667D01*
X85300Y144333D01*
X84967Y143750D01*
X84800Y143167D01*
X84883Y142667D01*
X85217Y142083D01*
X85717Y141667D01*
X86383Y141500D01*
X86883Y141583D01*
X87467Y141917D01*
X87800Y142250D01*
G01X1500Y175500D02*
X694500D01*
G01X0Y105500D02*
X694500D01*
G01X0Y120500D02*
X694500D01*
G01X15167Y111500D02*
X11833D01*
Y116500D01*
X15167D01*
G01X13833Y114083D02*
X11833D01*
G01X17850Y114833D02*
X20350Y111500D01*
G01Y114833D02*
X17850Y111500D01*
G01X24700Y116500D02*
Y111500D01*
G01X23533Y114833D02*
X25867D01*
G01X29050Y113750D02*
X31717D01*
X31467Y114333D01*
X31050Y114667D01*
X30467Y114833D01*
X29883Y114750D01*
X29383Y114500D01*
X29050Y113917D01*
X28883Y113417D01*
Y112917D01*
X29050Y112417D01*
X29467Y111917D01*
X29967Y111583D01*
X30550Y111500D01*
X31133Y111667D01*
X31717Y112167D01*
G01X34733Y111500D02*
Y114833D01*
G01Y114167D02*
X35150Y114500D01*
X35567Y114750D01*
X36150Y114833D01*
X36567Y114750D01*
X37067Y114500D01*
G01X40083Y111500D02*
Y114833D01*
G01Y114000D02*
X40417Y114417D01*
X40917Y114750D01*
X41583Y114833D01*
X42167Y114750D01*
X42667Y114417D01*
X42917Y113833D01*
Y111500D01*
G01X48600D02*
Y114833D01*
G01Y114250D02*
X48267Y114583D01*
X47767Y114750D01*
X47183Y114833D01*
X46600Y114667D01*
X46100Y114333D01*
X45767Y113833D01*
X45600Y113167D01*
X45767Y112500D01*
X46100Y112000D01*
X46600Y111667D01*
X47183Y111500D01*
X47767Y111583D01*
X48267Y111833D01*
X48600Y112167D01*
G01X52700Y111500D02*
Y116500D01*
G01X63900Y111500D02*
Y116500D01*
G01X71000Y111500D02*
Y114833D01*
G01Y114250D02*
X70667Y114583D01*
X70167Y114750D01*
X69583Y114833D01*
X69000Y114667D01*
X68500Y114333D01*
X68167Y113833D01*
X68000Y113167D01*
X68167Y112500D01*
X68500Y112000D01*
X69000Y111667D01*
X69583Y111500D01*
X70167Y111583D01*
X70667Y111833D01*
X71000Y112167D01*
G01X73350Y110000D02*
X73850Y109833D01*
X74517Y110000D01*
X74933Y110333D01*
X75267Y110750D01*
X75767Y112083D01*
X76850Y114833D01*
G01X74183D02*
X75767Y112083D01*
G01X79450Y113750D02*
X82117D01*
X81867Y114333D01*
X81450Y114667D01*
X80867Y114833D01*
X80283Y114750D01*
X79783Y114500D01*
X79450Y113917D01*
X79283Y113417D01*
Y112917D01*
X79450Y112417D01*
X79867Y111917D01*
X80367Y111583D01*
X80950Y111500D01*
X81533Y111667D01*
X82117Y112167D01*
G01X85133Y111500D02*
Y114833D01*
G01Y114167D02*
X85550Y114500D01*
X85967Y114750D01*
X86550Y114833D01*
X86967Y114750D01*
X87467Y114500D01*
G01X15333Y146083D02*
X14833Y146333D01*
X14250Y146500D01*
X13583D01*
X12833Y146250D01*
X12250Y145833D01*
X11833Y145333D01*
X11500Y144500D01*
X11417Y143750D01*
X11583Y143000D01*
X11833Y142500D01*
X12333Y142000D01*
X12917Y141667D01*
X13500Y141500D01*
X14083D01*
X14667Y141667D01*
X15167Y141917D01*
X15583Y142250D01*
G01X19100Y141500D02*
X18600Y141583D01*
X18100Y141917D01*
X17767Y142500D01*
X17600Y143167D01*
X17767Y143833D01*
X18100Y144417D01*
X18600Y144750D01*
X19100Y144833D01*
X19600Y144750D01*
X20100Y144417D01*
X20433Y143833D01*
X20517Y143167D01*
X20433Y142500D01*
X20100Y141917D01*
X19600Y141583D01*
X19100Y141500D01*
G01X23200Y139833D02*
Y144833D01*
G01Y144083D02*
X23617Y144500D01*
X24033Y144750D01*
X24700Y144833D01*
X25283Y144750D01*
X25867Y144333D01*
X26117Y143750D01*
X26200Y143167D01*
X26117Y142583D01*
X25867Y142000D01*
X25367Y141667D01*
X24700Y141500D01*
X24117Y141583D01*
X23533Y141833D01*
X23200Y142167D01*
G01X28800Y139833D02*
Y144833D01*
G01Y144083D02*
X29217Y144500D01*
X29633Y144750D01*
X30300Y144833D01*
X30883Y144750D01*
X31467Y144333D01*
X31717Y143750D01*
X31800Y143167D01*
X31717Y142583D01*
X31467Y142000D01*
X30967Y141667D01*
X30300Y141500D01*
X29717Y141583D01*
X29133Y141833D01*
X28800Y142167D01*
G01X34650Y143750D02*
X37317D01*
X37067Y144333D01*
X36650Y144667D01*
X36067Y144833D01*
X35483Y144750D01*
X34983Y144500D01*
X34650Y143917D01*
X34483Y143417D01*
Y142917D01*
X34650Y142417D01*
X35067Y141917D01*
X35567Y141583D01*
X36150Y141500D01*
X36733Y141667D01*
X37317Y142167D01*
G01X40333Y141500D02*
Y144833D01*
G01Y144167D02*
X40750Y144500D01*
X41167Y144750D01*
X41750Y144833D01*
X42167Y144750D01*
X42667Y144500D01*
G01X51033Y141500D02*
Y146500D01*
X53033D01*
X53700Y146250D01*
X54200Y145667D01*
X54367Y145000D01*
X54200Y144333D01*
X53783Y143833D01*
X53033Y143583D01*
X51033D01*
G01X58300Y141500D02*
Y146500D01*
G01X65400Y141500D02*
Y144833D01*
G01Y144250D02*
X65067Y144583D01*
X64567Y144750D01*
X63983Y144833D01*
X63400Y144667D01*
X62900Y144333D01*
X62567Y143833D01*
X62400Y143167D01*
X62567Y142500D01*
X62900Y142000D01*
X63400Y141667D01*
X63983Y141500D01*
X64567Y141583D01*
X65067Y141833D01*
X65400Y142167D01*
G01X69500Y146500D02*
Y141500D01*
G01X68333Y144833D02*
X70667D01*
G01X75100D02*
Y141500D01*
G01Y146167D02*
X74933Y146250D01*
Y146417D01*
X75100Y146500D01*
X75267Y146417D01*
Y146250D01*
X75100Y146167D01*
G01X79283Y141500D02*
Y144833D01*
G01Y144000D02*
X79617Y144417D01*
X80117Y144750D01*
X80783Y144833D01*
X81367Y144750D01*
X81867Y144417D01*
X82117Y143833D01*
Y141500D01*
G01X85133Y140250D02*
X85717Y139917D01*
X86383Y139833D01*
X86967Y139917D01*
X87467Y140333D01*
X87800Y140917D01*
Y144833D01*
G01Y144167D02*
X87467Y144500D01*
X86967Y144750D01*
X86383Y144833D01*
X85717Y144667D01*
X85300Y144333D01*
X84967Y143750D01*
X84800Y143167D01*
X84883Y142667D01*
X85217Y142083D01*
X85717Y141667D01*
X86383Y141500D01*
X86883Y141583D01*
X87467Y141917D01*
X87800Y142250D01*
G01X1500Y175500D02*
X694500D01*
G01X0Y105500D02*
X694500D01*
G01X0Y120500D02*
X694500D01*
G01X11667Y459000D02*
Y464000D01*
X13333D01*
X14000Y463750D01*
X14500Y463417D01*
X14917Y462917D01*
X15250Y462333D01*
X15333Y461500D01*
X15250Y460667D01*
X14917Y460083D01*
X14500Y459583D01*
X14000Y459250D01*
X13333Y459000D01*
X11667D01*
G01X17933D02*
Y462333D01*
G01Y461667D02*
X18350Y462000D01*
X18767Y462250D01*
X19350Y462333D01*
X19767Y462250D01*
X20267Y462000D01*
G01X24700Y462333D02*
Y459000D01*
G01Y463667D02*
X24533Y463750D01*
Y463917D01*
X24700Y464000D01*
X24867Y463917D01*
Y463750D01*
X24700Y463667D01*
G01X30300Y459000D02*
Y464000D01*
G01X35900Y459000D02*
Y464000D01*
G01X11667Y459000D02*
Y464000D01*
X13333D01*
X14000Y463750D01*
X14500Y463417D01*
X14917Y462917D01*
X15250Y462333D01*
X15333Y461500D01*
X15250Y460667D01*
X14917Y460083D01*
X14500Y459583D01*
X14000Y459250D01*
X13333Y459000D01*
X11667D01*
G01X17933D02*
Y462333D01*
G01Y461667D02*
X18350Y462000D01*
X18767Y462250D01*
X19350Y462333D01*
X19767Y462250D01*
X20267Y462000D01*
G01X24700Y462333D02*
Y459000D01*
G01Y463667D02*
X24533Y463750D01*
Y463917D01*
X24700Y464000D01*
X24867Y463917D01*
Y463750D01*
X24700Y463667D01*
G01X30300Y459000D02*
Y464000D01*
G01X35900Y459000D02*
Y464000D01*
G01X24960Y626740D02*
X26960D01*
G01X25960D02*
Y621740D01*
G01X24960D02*
X26960D01*
G01X30143D02*
Y625073D01*
G01Y624240D02*
X30477Y624657D01*
X30977Y624990D01*
X31643Y625073D01*
X32227Y624990D01*
X32727Y624657D01*
X32977Y624073D01*
Y621740D01*
G01X35743D02*
Y625073D01*
G01Y624240D02*
X36077Y624657D01*
X36577Y624990D01*
X37243Y625073D01*
X37827Y624990D01*
X38327Y624657D01*
X38577Y624073D01*
Y621740D01*
G01X41510Y623990D02*
X44177D01*
X43927Y624573D01*
X43510Y624907D01*
X42927Y625073D01*
X42343Y624990D01*
X41843Y624740D01*
X41510Y624157D01*
X41343Y623657D01*
Y623157D01*
X41510Y622657D01*
X41927Y622157D01*
X42427Y621823D01*
X43010Y621740D01*
X43593Y621907D01*
X44177Y622407D01*
G01X47193Y621740D02*
Y625073D01*
G01Y624407D02*
X47610Y624740D01*
X48027Y624990D01*
X48610Y625073D01*
X49027Y624990D01*
X49527Y624740D01*
G01X59560Y621740D02*
Y626740D01*
G01X66660Y621740D02*
Y625073D01*
G01Y624490D02*
X66327Y624823D01*
X65827Y624990D01*
X65243Y625073D01*
X64660Y624907D01*
X64160Y624573D01*
X63827Y624073D01*
X63660Y623407D01*
X63827Y622740D01*
X64160Y622240D01*
X64660Y621907D01*
X65243Y621740D01*
X65827Y621823D01*
X66327Y622073D01*
X66660Y622407D01*
G01X69010Y620240D02*
X69510Y620073D01*
X70177Y620240D01*
X70593Y620573D01*
X70927Y620990D01*
X71427Y622323D01*
X72510Y625073D01*
G01X69843D02*
X71427Y622323D01*
G01X75110Y623990D02*
X77777D01*
X77527Y624573D01*
X77110Y624907D01*
X76527Y625073D01*
X75943Y624990D01*
X75443Y624740D01*
X75110Y624157D01*
X74943Y623657D01*
Y623157D01*
X75110Y622657D01*
X75527Y622157D01*
X76027Y621823D01*
X76610Y621740D01*
X77193Y621907D01*
X77777Y622407D01*
G01X80793Y621740D02*
Y625073D01*
G01Y624407D02*
X81210Y624740D01*
X81627Y624990D01*
X82210Y625073D01*
X82627Y624990D01*
X83127Y624740D01*
G01X0Y599000D02*
X694500D01*
G01X-1000Y654000D02*
X694500D01*
G01X24960Y626740D02*
X26960D01*
G01X25960D02*
Y621740D01*
G01X24960D02*
X26960D01*
G01X30143D02*
Y625073D01*
G01Y624240D02*
X30477Y624657D01*
X30977Y624990D01*
X31643Y625073D01*
X32227Y624990D01*
X32727Y624657D01*
X32977Y624073D01*
Y621740D01*
G01X35743D02*
Y625073D01*
G01Y624240D02*
X36077Y624657D01*
X36577Y624990D01*
X37243Y625073D01*
X37827Y624990D01*
X38327Y624657D01*
X38577Y624073D01*
Y621740D01*
G01X41510Y623990D02*
X44177D01*
X43927Y624573D01*
X43510Y624907D01*
X42927Y625073D01*
X42343Y624990D01*
X41843Y624740D01*
X41510Y624157D01*
X41343Y623657D01*
Y623157D01*
X41510Y622657D01*
X41927Y622157D01*
X42427Y621823D01*
X43010Y621740D01*
X43593Y621907D01*
X44177Y622407D01*
G01X47193Y621740D02*
Y625073D01*
G01Y624407D02*
X47610Y624740D01*
X48027Y624990D01*
X48610Y625073D01*
X49027Y624990D01*
X49527Y624740D01*
G01X59560Y621740D02*
Y626740D01*
G01X66660Y621740D02*
Y625073D01*
G01Y624490D02*
X66327Y624823D01*
X65827Y624990D01*
X65243Y625073D01*
X64660Y624907D01*
X64160Y624573D01*
X63827Y624073D01*
X63660Y623407D01*
X63827Y622740D01*
X64160Y622240D01*
X64660Y621907D01*
X65243Y621740D01*
X65827Y621823D01*
X66327Y622073D01*
X66660Y622407D01*
G01X69010Y620240D02*
X69510Y620073D01*
X70177Y620240D01*
X70593Y620573D01*
X70927Y620990D01*
X71427Y622323D01*
X72510Y625073D01*
G01X69843D02*
X71427Y622323D01*
G01X75110Y623990D02*
X77777D01*
X77527Y624573D01*
X77110Y624907D01*
X76527Y625073D01*
X75943Y624990D01*
X75443Y624740D01*
X75110Y624157D01*
X74943Y623657D01*
Y623157D01*
X75110Y622657D01*
X75527Y622157D01*
X76027Y621823D01*
X76610Y621740D01*
X77193Y621907D01*
X77777Y622407D01*
G01X80793Y621740D02*
Y625073D01*
G01Y624407D02*
X81210Y624740D01*
X81627Y624990D01*
X82210Y625073D01*
X82627Y624990D01*
X83127Y624740D01*
G01X0Y599000D02*
X694500D01*
G01X-1000Y654000D02*
X694500D01*
G01X9917Y693667D02*
X10417Y694167D01*
X11000Y694417D01*
X11667Y694500D01*
X12500Y694333D01*
X13083Y693917D01*
X13250Y693417D01*
X13167Y692917D01*
X12833Y692500D01*
X11167Y691667D01*
X10417Y691083D01*
X9917Y690250D01*
X9750Y689500D01*
X13250D01*
G01X17100Y689333D02*
X16933Y689417D01*
Y689583D01*
X17100Y689667D01*
X17267Y689583D01*
Y689417D01*
X17100Y689333D01*
G01X22700Y694500D02*
Y689500D01*
G01X20783Y694500D02*
X24617D01*
G01X28300Y689500D02*
X27800Y689583D01*
X27300Y689917D01*
X26967Y690500D01*
X26800Y691167D01*
X26967Y691833D01*
X27300Y692417D01*
X27800Y692750D01*
X28300Y692833D01*
X28800Y692750D01*
X29300Y692417D01*
X29633Y691833D01*
X29717Y691167D01*
X29633Y690500D01*
X29300Y689917D01*
X28800Y689583D01*
X28300Y689500D01*
G01X33900D02*
Y694500D01*
G01X38250Y691750D02*
X40917D01*
X40667Y692333D01*
X40250Y692667D01*
X39667Y692833D01*
X39083Y692750D01*
X38583Y692500D01*
X38250Y691917D01*
X38083Y691417D01*
Y690917D01*
X38250Y690417D01*
X38667Y689917D01*
X39167Y689583D01*
X39750Y689500D01*
X40333Y689667D01*
X40917Y690167D01*
G01X43933Y689500D02*
Y692833D01*
G01Y692167D02*
X44350Y692500D01*
X44767Y692750D01*
X45350Y692833D01*
X45767Y692750D01*
X46267Y692500D01*
G01X52200Y689500D02*
Y692833D01*
G01Y692250D02*
X51867Y692583D01*
X51367Y692750D01*
X50783Y692833D01*
X50200Y692667D01*
X49700Y692333D01*
X49367Y691833D01*
X49200Y691167D01*
X49367Y690500D01*
X49700Y690000D01*
X50200Y689667D01*
X50783Y689500D01*
X51367Y689583D01*
X51867Y689833D01*
X52200Y690167D01*
G01X54883Y689500D02*
Y692833D01*
G01Y692000D02*
X55217Y692417D01*
X55717Y692750D01*
X56383Y692833D01*
X56967Y692750D01*
X57467Y692417D01*
X57717Y691833D01*
Y689500D01*
G01X63233Y692417D02*
X62650Y692750D01*
X62150Y692833D01*
X61483Y692667D01*
X60983Y692333D01*
X60650Y691750D01*
X60567Y691167D01*
X60650Y690583D01*
X60983Y690083D01*
X61483Y689667D01*
X62150Y689500D01*
X62733Y689667D01*
X63233Y690000D01*
G01X66250Y691750D02*
X68917D01*
X68667Y692333D01*
X68250Y692667D01*
X67667Y692833D01*
X67083Y692750D01*
X66583Y692500D01*
X66250Y691917D01*
X66083Y691417D01*
Y690917D01*
X66250Y690417D01*
X66667Y689917D01*
X67167Y689583D01*
X67750Y689500D01*
X68333Y689667D01*
X68917Y690167D01*
G01X78700Y694500D02*
Y689500D01*
G01X77533Y692833D02*
X79867D01*
G01X85800Y689500D02*
Y692833D01*
G01Y692250D02*
X85467Y692583D01*
X84967Y692750D01*
X84383Y692833D01*
X83800Y692667D01*
X83300Y692333D01*
X82967Y691833D01*
X82800Y691167D01*
X82967Y690500D01*
X83300Y690000D01*
X83800Y689667D01*
X84383Y689500D01*
X84967Y689583D01*
X85467Y689833D01*
X85800Y690167D01*
G01X88400Y689500D02*
Y694500D01*
G01Y692000D02*
X88817Y692500D01*
X89317Y692750D01*
X89817Y692833D01*
X90567Y692667D01*
X91067Y692333D01*
X91400Y691750D01*
Y691083D01*
X91233Y690417D01*
X90900Y689917D01*
X90317Y689583D01*
X89817Y689500D01*
X89317Y689583D01*
X88817Y689833D01*
X88400Y690250D01*
G01X95500Y689500D02*
Y694500D01*
G01X99850Y691750D02*
X102517D01*
X102267Y692333D01*
X101850Y692667D01*
X101267Y692833D01*
X100683Y692750D01*
X100183Y692500D01*
X99850Y691917D01*
X99683Y691417D01*
Y690917D01*
X99850Y690417D01*
X100267Y689917D01*
X100767Y689583D01*
X101350Y689500D01*
X101933Y689667D01*
X102517Y690167D01*
G01X106700Y689333D02*
X106533Y689417D01*
Y689583D01*
X106700Y689667D01*
X106867Y689583D01*
Y689417D01*
X106700Y689333D01*
G01Y691583D02*
X106533Y691667D01*
Y691833D01*
X106700Y691917D01*
X106867Y691833D01*
Y691667D01*
X106700Y691583D01*
G01X0Y679000D02*
X694500D01*
G01X0Y850500D02*
Y709000D01*
X694500D01*
Y850500D01*
G01X9917Y693667D02*
X10417Y694167D01*
X11000Y694417D01*
X11667Y694500D01*
X12500Y694333D01*
X13083Y693917D01*
X13250Y693417D01*
X13167Y692917D01*
X12833Y692500D01*
X11167Y691667D01*
X10417Y691083D01*
X9917Y690250D01*
X9750Y689500D01*
X13250D01*
G01X17100Y689333D02*
X16933Y689417D01*
Y689583D01*
X17100Y689667D01*
X17267Y689583D01*
Y689417D01*
X17100Y689333D01*
G01X22700Y694500D02*
Y689500D01*
G01X20783Y694500D02*
X24617D01*
G01X28300Y689500D02*
X27800Y689583D01*
X27300Y689917D01*
X26967Y690500D01*
X26800Y691167D01*
X26967Y691833D01*
X27300Y692417D01*
X27800Y692750D01*
X28300Y692833D01*
X28800Y692750D01*
X29300Y692417D01*
X29633Y691833D01*
X29717Y691167D01*
X29633Y690500D01*
X29300Y689917D01*
X28800Y689583D01*
X28300Y689500D01*
G01X33900D02*
Y694500D01*
G01X38250Y691750D02*
X40917D01*
X40667Y692333D01*
X40250Y692667D01*
X39667Y692833D01*
X39083Y692750D01*
X38583Y692500D01*
X38250Y691917D01*
X38083Y691417D01*
Y690917D01*
X38250Y690417D01*
X38667Y689917D01*
X39167Y689583D01*
X39750Y689500D01*
X40333Y689667D01*
X40917Y690167D01*
G01X43933Y689500D02*
Y692833D01*
G01Y692167D02*
X44350Y692500D01*
X44767Y692750D01*
X45350Y692833D01*
X45767Y692750D01*
X46267Y692500D01*
G01X52200Y689500D02*
Y692833D01*
G01Y692250D02*
X51867Y692583D01*
X51367Y692750D01*
X50783Y692833D01*
X50200Y692667D01*
X49700Y692333D01*
X49367Y691833D01*
X49200Y691167D01*
X49367Y690500D01*
X49700Y690000D01*
X50200Y689667D01*
X50783Y689500D01*
X51367Y689583D01*
X51867Y689833D01*
X52200Y690167D01*
G01X54883Y689500D02*
Y692833D01*
G01Y692000D02*
X55217Y692417D01*
X55717Y692750D01*
X56383Y692833D01*
X56967Y692750D01*
X57467Y692417D01*
X57717Y691833D01*
Y689500D01*
G01X63233Y692417D02*
X62650Y692750D01*
X62150Y692833D01*
X61483Y692667D01*
X60983Y692333D01*
X60650Y691750D01*
X60567Y691167D01*
X60650Y690583D01*
X60983Y690083D01*
X61483Y689667D01*
X62150Y689500D01*
X62733Y689667D01*
X63233Y690000D01*
G01X66250Y691750D02*
X68917D01*
X68667Y692333D01*
X68250Y692667D01*
X67667Y692833D01*
X67083Y692750D01*
X66583Y692500D01*
X66250Y691917D01*
X66083Y691417D01*
Y690917D01*
X66250Y690417D01*
X66667Y689917D01*
X67167Y689583D01*
X67750Y689500D01*
X68333Y689667D01*
X68917Y690167D01*
G01X78700Y694500D02*
Y689500D01*
G01X77533Y692833D02*
X79867D01*
G01X85800Y689500D02*
Y692833D01*
G01Y692250D02*
X85467Y692583D01*
X84967Y692750D01*
X84383Y692833D01*
X83800Y692667D01*
X83300Y692333D01*
X82967Y691833D01*
X82800Y691167D01*
X82967Y690500D01*
X83300Y690000D01*
X83800Y689667D01*
X84383Y689500D01*
X84967Y689583D01*
X85467Y689833D01*
X85800Y690167D01*
G01X88400Y689500D02*
Y694500D01*
G01Y692000D02*
X88817Y692500D01*
X89317Y692750D01*
X89817Y692833D01*
X90567Y692667D01*
X91067Y692333D01*
X91400Y691750D01*
Y691083D01*
X91233Y690417D01*
X90900Y689917D01*
X90317Y689583D01*
X89817Y689500D01*
X89317Y689583D01*
X88817Y689833D01*
X88400Y690250D01*
G01X95500Y689500D02*
Y694500D01*
G01X99850Y691750D02*
X102517D01*
X102267Y692333D01*
X101850Y692667D01*
X101267Y692833D01*
X100683Y692750D01*
X100183Y692500D01*
X99850Y691917D01*
X99683Y691417D01*
Y690917D01*
X99850Y690417D01*
X100267Y689917D01*
X100767Y689583D01*
X101350Y689500D01*
X101933Y689667D01*
X102517Y690167D01*
G01X106700Y689333D02*
X106533Y689417D01*
Y689583D01*
X106700Y689667D01*
X106867Y689583D01*
Y689417D01*
X106700Y689333D01*
G01Y691583D02*
X106533Y691667D01*
Y691833D01*
X106700Y691917D01*
X106867Y691833D01*
Y691667D01*
X106700Y691583D01*
G01X0Y679000D02*
X694500D01*
G01X0Y850500D02*
Y709000D01*
X694500D01*
Y850500D01*
G01X7000Y832500D02*
Y837500D01*
X6000Y836500D01*
G01Y832500D02*
X8000D01*
G01X12600Y832333D02*
X12433Y832417D01*
Y832583D01*
X12600Y832667D01*
X12767Y832583D01*
Y832417D01*
X12600Y832333D01*
G01X16450Y833167D02*
X17117Y832750D01*
X17867Y832500D01*
X18533D01*
X19200Y832750D01*
X19700Y833167D01*
X19950Y833750D01*
X19783Y834333D01*
X19367Y834833D01*
X18617Y835167D01*
X17617Y835333D01*
X17033Y835667D01*
X16783Y836250D01*
X16950Y836833D01*
X17367Y837250D01*
X17950Y837500D01*
X18533D01*
X19117Y837333D01*
X19617Y836917D01*
G01X22300Y830833D02*
Y835833D01*
G01Y835083D02*
X22717Y835500D01*
X23133Y835750D01*
X23800Y835833D01*
X24383Y835750D01*
X24967Y835333D01*
X25217Y834750D01*
X25300Y834167D01*
X25217Y833583D01*
X24967Y833000D01*
X24467Y832667D01*
X23800Y832500D01*
X23217Y832583D01*
X22633Y832833D01*
X22300Y833167D01*
G01X28150Y834750D02*
X30817D01*
X30567Y835333D01*
X30150Y835667D01*
X29567Y835833D01*
X28983Y835750D01*
X28483Y835500D01*
X28150Y834917D01*
X27983Y834417D01*
Y833917D01*
X28150Y833417D01*
X28567Y832917D01*
X29067Y832583D01*
X29650Y832500D01*
X30233Y832667D01*
X30817Y833167D01*
G01X36333Y835417D02*
X35750Y835750D01*
X35250Y835833D01*
X34583Y835667D01*
X34083Y835333D01*
X33750Y834750D01*
X33667Y834167D01*
X33750Y833583D01*
X34083Y833083D01*
X34583Y832667D01*
X35250Y832500D01*
X35833Y832667D01*
X36333Y833000D01*
G01X40600Y835833D02*
Y832500D01*
G01Y837167D02*
X40433Y837250D01*
Y837417D01*
X40600Y837500D01*
X40767Y837417D01*
Y837250D01*
X40600Y837167D01*
G01X45700Y832500D02*
Y836750D01*
X45867Y837167D01*
X46200Y837417D01*
X46700Y837500D01*
X47200Y837333D01*
X47450Y836917D01*
G01X46450Y835500D02*
X44783D01*
G01X51800Y835833D02*
Y832500D01*
G01Y837167D02*
X51633Y837250D01*
Y837417D01*
X51800Y837500D01*
X51967Y837417D01*
Y837250D01*
X51800Y837167D01*
G01X58733Y835417D02*
X58150Y835750D01*
X57650Y835833D01*
X56983Y835667D01*
X56483Y835333D01*
X56150Y834750D01*
X56067Y834167D01*
X56150Y833583D01*
X56483Y833083D01*
X56983Y832667D01*
X57650Y832500D01*
X58233Y832667D01*
X58733Y833000D01*
G01X64500Y832500D02*
Y835833D01*
G01Y835250D02*
X64167Y835583D01*
X63667Y835750D01*
X63083Y835833D01*
X62500Y835667D01*
X62000Y835333D01*
X61667Y834833D01*
X61500Y834167D01*
X61667Y833500D01*
X62000Y833000D01*
X62500Y832667D01*
X63083Y832500D01*
X63667Y832583D01*
X64167Y832833D01*
X64500Y833167D01*
G01X68600Y837500D02*
Y832500D01*
G01X67433Y835833D02*
X69767D01*
G01X74200D02*
Y832500D01*
G01Y837167D02*
X74033Y837250D01*
Y837417D01*
X74200Y837500D01*
X74367Y837417D01*
Y837250D01*
X74200Y837167D01*
G01X79800Y832500D02*
X79300Y832583D01*
X78800Y832917D01*
X78467Y833500D01*
X78300Y834167D01*
X78467Y834833D01*
X78800Y835417D01*
X79300Y835750D01*
X79800Y835833D01*
X80300Y835750D01*
X80800Y835417D01*
X81133Y834833D01*
X81217Y834167D01*
X81133Y833500D01*
X80800Y832917D01*
X80300Y832583D01*
X79800Y832500D01*
G01X83983D02*
Y835833D01*
G01Y835000D02*
X84317Y835417D01*
X84817Y835750D01*
X85483Y835833D01*
X86067Y835750D01*
X86567Y835417D01*
X86817Y834833D01*
Y832500D01*
G01X98100Y837500D02*
Y832500D01*
G01Y833250D02*
X97767Y832833D01*
X97267Y832583D01*
X96683Y832500D01*
X96017Y832667D01*
X95517Y833083D01*
X95183Y833583D01*
X95100Y834167D01*
X95183Y834750D01*
X95517Y835250D01*
X96017Y835667D01*
X96683Y835833D01*
X97267Y835750D01*
X97683Y835583D01*
X98100Y835250D01*
G01X102200Y832500D02*
X101700Y832583D01*
X101200Y832917D01*
X100867Y833500D01*
X100700Y834167D01*
X100867Y834833D01*
X101200Y835417D01*
X101700Y835750D01*
X102200Y835833D01*
X102700Y835750D01*
X103200Y835417D01*
X103533Y834833D01*
X103617Y834167D01*
X103533Y833500D01*
X103200Y832917D01*
X102700Y832583D01*
X102200Y832500D01*
G01X109133Y835417D02*
X108550Y835750D01*
X108050Y835833D01*
X107383Y835667D01*
X106883Y835333D01*
X106550Y834750D01*
X106467Y834167D01*
X106550Y833583D01*
X106883Y833083D01*
X107383Y832667D01*
X108050Y832500D01*
X108633Y832667D01*
X109133Y833000D01*
G01X111983Y835833D02*
Y833500D01*
X112317Y832917D01*
X112817Y832583D01*
X113400Y832500D01*
X113983Y832583D01*
X114483Y832917D01*
X114817Y833500D01*
G01Y832500D02*
Y835833D01*
G01X116500Y832500D02*
Y835833D01*
G01Y834917D02*
X116750Y835333D01*
X117167Y835667D01*
X117750Y835833D01*
X118333Y835667D01*
X118750Y835333D01*
X119000Y834917D01*
Y832500D01*
G01Y834917D02*
X119250Y835333D01*
X119667Y835667D01*
X120250Y835833D01*
X120833Y835667D01*
X121250Y835333D01*
X121500Y834833D01*
Y832500D01*
G01X123350Y834750D02*
X126017D01*
X125767Y835333D01*
X125350Y835667D01*
X124767Y835833D01*
X124183Y835750D01*
X123683Y835500D01*
X123350Y834917D01*
X123183Y834417D01*
Y833917D01*
X123350Y833417D01*
X123767Y832917D01*
X124267Y832583D01*
X124850Y832500D01*
X125433Y832667D01*
X126017Y833167D01*
G01X128783Y832500D02*
Y835833D01*
G01Y835000D02*
X129117Y835417D01*
X129617Y835750D01*
X130283Y835833D01*
X130867Y835750D01*
X131367Y835417D01*
X131617Y834833D01*
Y832500D01*
G01X135800Y837500D02*
Y832500D01*
G01X134633Y835833D02*
X136967D01*
G01X141400Y832333D02*
X141233Y832417D01*
Y832583D01*
X141400Y832667D01*
X141567Y832583D01*
Y832417D01*
X141400Y832333D01*
G01Y834583D02*
X141233Y834667D01*
Y834833D01*
X141400Y834917D01*
X141567Y834833D01*
Y834667D01*
X141400Y834583D01*
G01X0Y820500D02*
X694500D01*
G01X0Y850500D02*
X694500D01*
G01X7000Y832500D02*
Y837500D01*
X6000Y836500D01*
G01Y832500D02*
X8000D01*
G01X12600Y832333D02*
X12433Y832417D01*
Y832583D01*
X12600Y832667D01*
X12767Y832583D01*
Y832417D01*
X12600Y832333D01*
G01X16450Y833167D02*
X17117Y832750D01*
X17867Y832500D01*
X18533D01*
X19200Y832750D01*
X19700Y833167D01*
X19950Y833750D01*
X19783Y834333D01*
X19367Y834833D01*
X18617Y835167D01*
X17617Y835333D01*
X17033Y835667D01*
X16783Y836250D01*
X16950Y836833D01*
X17367Y837250D01*
X17950Y837500D01*
X18533D01*
X19117Y837333D01*
X19617Y836917D01*
G01X22300Y830833D02*
Y835833D01*
G01Y835083D02*
X22717Y835500D01*
X23133Y835750D01*
X23800Y835833D01*
X24383Y835750D01*
X24967Y835333D01*
X25217Y834750D01*
X25300Y834167D01*
X25217Y833583D01*
X24967Y833000D01*
X24467Y832667D01*
X23800Y832500D01*
X23217Y832583D01*
X22633Y832833D01*
X22300Y833167D01*
G01X28150Y834750D02*
X30817D01*
X30567Y835333D01*
X30150Y835667D01*
X29567Y835833D01*
X28983Y835750D01*
X28483Y835500D01*
X28150Y834917D01*
X27983Y834417D01*
Y833917D01*
X28150Y833417D01*
X28567Y832917D01*
X29067Y832583D01*
X29650Y832500D01*
X30233Y832667D01*
X30817Y833167D01*
G01X36333Y835417D02*
X35750Y835750D01*
X35250Y835833D01*
X34583Y835667D01*
X34083Y835333D01*
X33750Y834750D01*
X33667Y834167D01*
X33750Y833583D01*
X34083Y833083D01*
X34583Y832667D01*
X35250Y832500D01*
X35833Y832667D01*
X36333Y833000D01*
G01X40600Y835833D02*
Y832500D01*
G01Y837167D02*
X40433Y837250D01*
Y837417D01*
X40600Y837500D01*
X40767Y837417D01*
Y837250D01*
X40600Y837167D01*
G01X45700Y832500D02*
Y836750D01*
X45867Y837167D01*
X46200Y837417D01*
X46700Y837500D01*
X47200Y837333D01*
X47450Y836917D01*
G01X46450Y835500D02*
X44783D01*
G01X51800Y835833D02*
Y832500D01*
G01Y837167D02*
X51633Y837250D01*
Y837417D01*
X51800Y837500D01*
X51967Y837417D01*
Y837250D01*
X51800Y837167D01*
G01X58733Y835417D02*
X58150Y835750D01*
X57650Y835833D01*
X56983Y835667D01*
X56483Y835333D01*
X56150Y834750D01*
X56067Y834167D01*
X56150Y833583D01*
X56483Y833083D01*
X56983Y832667D01*
X57650Y832500D01*
X58233Y832667D01*
X58733Y833000D01*
G01X64500Y832500D02*
Y835833D01*
G01Y835250D02*
X64167Y835583D01*
X63667Y835750D01*
X63083Y835833D01*
X62500Y835667D01*
X62000Y835333D01*
X61667Y834833D01*
X61500Y834167D01*
X61667Y833500D01*
X62000Y833000D01*
X62500Y832667D01*
X63083Y832500D01*
X63667Y832583D01*
X64167Y832833D01*
X64500Y833167D01*
G01X68600Y837500D02*
Y832500D01*
G01X67433Y835833D02*
X69767D01*
G01X74200D02*
Y832500D01*
G01Y837167D02*
X74033Y837250D01*
Y837417D01*
X74200Y837500D01*
X74367Y837417D01*
Y837250D01*
X74200Y837167D01*
G01X79800Y832500D02*
X79300Y832583D01*
X78800Y832917D01*
X78467Y833500D01*
X78300Y834167D01*
X78467Y834833D01*
X78800Y835417D01*
X79300Y835750D01*
X79800Y835833D01*
X80300Y835750D01*
X80800Y835417D01*
X81133Y834833D01*
X81217Y834167D01*
X81133Y833500D01*
X80800Y832917D01*
X80300Y832583D01*
X79800Y832500D01*
G01X83983D02*
Y835833D01*
G01Y835000D02*
X84317Y835417D01*
X84817Y835750D01*
X85483Y835833D01*
X86067Y835750D01*
X86567Y835417D01*
X86817Y834833D01*
Y832500D01*
G01X98100Y837500D02*
Y832500D01*
G01Y833250D02*
X97767Y832833D01*
X97267Y832583D01*
X96683Y832500D01*
X96017Y832667D01*
X95517Y833083D01*
X95183Y833583D01*
X95100Y834167D01*
X95183Y834750D01*
X95517Y835250D01*
X96017Y835667D01*
X96683Y835833D01*
X97267Y835750D01*
X97683Y835583D01*
X98100Y835250D01*
G01X102200Y832500D02*
X101700Y832583D01*
X101200Y832917D01*
X100867Y833500D01*
X100700Y834167D01*
X100867Y834833D01*
X101200Y835417D01*
X101700Y835750D01*
X102200Y835833D01*
X102700Y835750D01*
X103200Y835417D01*
X103533Y834833D01*
X103617Y834167D01*
X103533Y833500D01*
X103200Y832917D01*
X102700Y832583D01*
X102200Y832500D01*
G01X109133Y835417D02*
X108550Y835750D01*
X108050Y835833D01*
X107383Y835667D01*
X106883Y835333D01*
X106550Y834750D01*
X106467Y834167D01*
X106550Y833583D01*
X106883Y833083D01*
X107383Y832667D01*
X108050Y832500D01*
X108633Y832667D01*
X109133Y833000D01*
G01X111983Y835833D02*
Y833500D01*
X112317Y832917D01*
X112817Y832583D01*
X113400Y832500D01*
X113983Y832583D01*
X114483Y832917D01*
X114817Y833500D01*
G01Y832500D02*
Y835833D01*
G01X116500Y832500D02*
Y835833D01*
G01Y834917D02*
X116750Y835333D01*
X117167Y835667D01*
X117750Y835833D01*
X118333Y835667D01*
X118750Y835333D01*
X119000Y834917D01*
Y832500D01*
G01Y834917D02*
X119250Y835333D01*
X119667Y835667D01*
X120250Y835833D01*
X120833Y835667D01*
X121250Y835333D01*
X121500Y834833D01*
Y832500D01*
G01X123350Y834750D02*
X126017D01*
X125767Y835333D01*
X125350Y835667D01*
X124767Y835833D01*
X124183Y835750D01*
X123683Y835500D01*
X123350Y834917D01*
X123183Y834417D01*
Y833917D01*
X123350Y833417D01*
X123767Y832917D01*
X124267Y832583D01*
X124850Y832500D01*
X125433Y832667D01*
X126017Y833167D01*
G01X128783Y832500D02*
Y835833D01*
G01Y835000D02*
X129117Y835417D01*
X129617Y835750D01*
X130283Y835833D01*
X130867Y835750D01*
X131367Y835417D01*
X131617Y834833D01*
Y832500D01*
G01X135800Y837500D02*
Y832500D01*
G01X134633Y835833D02*
X136967D01*
G01X141400Y832333D02*
X141233Y832417D01*
Y832583D01*
X141400Y832667D01*
X141567Y832583D01*
Y832417D01*
X141400Y832333D01*
G01Y834583D02*
X141233Y834667D01*
Y834833D01*
X141400Y834917D01*
X141567Y834833D01*
Y834667D01*
X141400Y834583D01*
G01X0Y820500D02*
X694500D01*
G01X0Y850500D02*
X694500D01*
G01X103500Y679000D02*
Y-69500D01*
G01Y679000D02*
Y-69500D01*
G01Y-9500D02*
X694500D01*
G01X103500Y-54500D02*
X694500D01*
G01X103500Y-9500D02*
X694500D01*
G01X103500Y-54500D02*
X694500D01*
G01X103500Y60500D02*
X694500D01*
G01X103500D02*
X694500D01*
G01X105000Y364500D02*
X694500D01*
G01X105000D02*
X694500D01*
G01X103500Y449000D02*
X694500D01*
G01X104000Y464000D02*
X694500D01*
G01X103500Y424000D02*
X694500D01*
G01X103500Y449000D02*
X694500D01*
G01X104000Y464000D02*
X694500D01*
G01X103500Y424000D02*
X694500D01*
G01X103500Y614000D02*
X694500D01*
G01X103500Y584000D02*
X694500D01*
G01X103500Y629000D02*
X694500D01*
G01X103500Y614000D02*
X694500D01*
G01X103500Y584000D02*
X694500D01*
G01X103500Y629000D02*
X694500D01*
G01X34000Y663333D02*
Y668333D01*
G01Y667583D02*
X34417Y668000D01*
X34833Y668250D01*
X35500Y668333D01*
X36083Y668250D01*
X36667Y667833D01*
X36917Y667250D01*
X37000Y666667D01*
X36917Y666083D01*
X36667Y665500D01*
X36167Y665167D01*
X35500Y665000D01*
X34917Y665083D01*
X34333Y665333D01*
X34000Y665667D01*
G01X39933Y665000D02*
Y668333D01*
G01Y667667D02*
X40350Y668000D01*
X40767Y668250D01*
X41350Y668333D01*
X41767Y668250D01*
X42267Y668000D01*
G01X46700Y665000D02*
X46200Y665083D01*
X45700Y665417D01*
X45367Y666000D01*
X45200Y666667D01*
X45367Y667333D01*
X45700Y667917D01*
X46200Y668250D01*
X46700Y668333D01*
X47200Y668250D01*
X47700Y667917D01*
X48033Y667333D01*
X48117Y666667D01*
X48033Y666000D01*
X47700Y665417D01*
X47200Y665083D01*
X46700Y665000D01*
G01X53633Y667917D02*
X53050Y668250D01*
X52550Y668333D01*
X51883Y668167D01*
X51383Y667833D01*
X51050Y667250D01*
X50967Y666667D01*
X51050Y666083D01*
X51383Y665583D01*
X51883Y665167D01*
X52550Y665000D01*
X53133Y665167D01*
X53633Y665500D01*
G01X56650Y667250D02*
X59317D01*
X59067Y667833D01*
X58650Y668167D01*
X58067Y668333D01*
X57483Y668250D01*
X56983Y668000D01*
X56650Y667417D01*
X56483Y666917D01*
Y666417D01*
X56650Y665917D01*
X57067Y665417D01*
X57567Y665083D01*
X58150Y665000D01*
X58733Y665167D01*
X59317Y665667D01*
G01X62250Y665583D02*
X62667Y665250D01*
X63250Y665000D01*
X63750D01*
X64250Y665167D01*
X64583Y665417D01*
X64750Y665750D01*
X64667Y666250D01*
X64333Y666500D01*
X62833Y667000D01*
X62500Y667583D01*
X62667Y668000D01*
X63000Y668250D01*
X63500Y668333D01*
X64000Y668250D01*
X64500Y668000D01*
G01X67850Y665583D02*
X68267Y665250D01*
X68850Y665000D01*
X69350D01*
X69850Y665167D01*
X70183Y665417D01*
X70350Y665750D01*
X70267Y666250D01*
X69933Y666500D01*
X68433Y667000D01*
X68100Y667583D01*
X68267Y668000D01*
X68600Y668250D01*
X69100Y668333D01*
X69600Y668250D01*
X70100Y668000D01*
G01X67000Y725433D02*
X66833Y725517D01*
Y725683D01*
X67000Y725767D01*
X67167Y725683D01*
Y725517D01*
X67000Y725433D01*
G01Y734433D02*
X66833Y734517D01*
Y734683D01*
X67000Y734767D01*
X67167Y734683D01*
Y734517D01*
X67000Y734433D01*
G01X71000Y729600D02*
X73000D01*
G01X72000D02*
Y724600D01*
G01X71000D02*
X73000D01*
G01X75933D02*
Y729600D01*
X77933D01*
X78600Y729350D01*
X79100Y728767D01*
X79267Y728100D01*
X79100Y727433D01*
X78683Y726933D01*
X77933Y726683D01*
X75933D01*
G01X85033Y729183D02*
X84533Y729433D01*
X83950Y729600D01*
X83283D01*
X82533Y729350D01*
X81950Y728933D01*
X81533Y728433D01*
X81200Y727600D01*
X81117Y726850D01*
X81283Y726100D01*
X81533Y725600D01*
X82033Y725100D01*
X82617Y724767D01*
X83200Y724600D01*
X83783D01*
X84367Y724767D01*
X84867Y725017D01*
X85283Y725350D01*
G01X87717Y726267D02*
X89883D01*
G01X92733Y729600D02*
Y724600D01*
X96067D01*
G01X98917Y726267D02*
X101083D01*
G01X105600Y724600D02*
Y729600D01*
X104600Y728600D01*
G01Y724600D02*
X106600D01*
G01X111200Y729600D02*
X110533Y729433D01*
X110033Y729017D01*
X109700Y728517D01*
X109450Y727850D01*
X109367Y727100D01*
X109450Y726350D01*
X109700Y725683D01*
X110033Y725183D01*
X110533Y724767D01*
X111200Y724600D01*
X111867Y724767D01*
X112367Y725183D01*
X112700Y725683D01*
X112950Y726350D01*
X113033Y727100D01*
X112950Y727850D01*
X112700Y728517D01*
X112367Y729017D01*
X111867Y729433D01*
X111200Y729600D01*
G01X115383Y725183D02*
X115967Y724767D01*
X116633Y724600D01*
X117300Y724767D01*
X117883Y725267D01*
X118300Y726017D01*
X118467Y726767D01*
Y727683D01*
X118300Y728433D01*
X117883Y729100D01*
X117383Y729433D01*
X116800Y729600D01*
X116133Y729433D01*
X115633Y729100D01*
X115300Y728600D01*
X115133Y727933D01*
X115300Y727350D01*
X115717Y726767D01*
X116217Y726433D01*
X116800Y726350D01*
X117467Y726517D01*
X117967Y726933D01*
X118467Y727683D01*
G01X126250Y725267D02*
X126917Y724850D01*
X127667Y724600D01*
X128333D01*
X129000Y724850D01*
X129500Y725267D01*
X129750Y725850D01*
X129583Y726433D01*
X129167Y726933D01*
X128417Y727267D01*
X127417Y727433D01*
X126833Y727767D01*
X126583Y728350D01*
X126750Y728933D01*
X127167Y729350D01*
X127750Y729600D01*
X128333D01*
X128917Y729433D01*
X129417Y729017D01*
G01X132100Y722933D02*
Y727933D01*
G01Y727183D02*
X132517Y727600D01*
X132933Y727850D01*
X133600Y727933D01*
X134183Y727850D01*
X134767Y727433D01*
X135017Y726850D01*
X135100Y726267D01*
X135017Y725683D01*
X134767Y725100D01*
X134267Y724767D01*
X133600Y724600D01*
X133017Y724683D01*
X132433Y724933D01*
X132100Y725267D01*
G01X137950Y726850D02*
X140617D01*
X140367Y727433D01*
X139950Y727767D01*
X139367Y727933D01*
X138783Y727850D01*
X138283Y727600D01*
X137950Y727017D01*
X137783Y726517D01*
Y726017D01*
X137950Y725517D01*
X138367Y725017D01*
X138867Y724683D01*
X139450Y724600D01*
X140033Y724767D01*
X140617Y725267D01*
G01X146133Y727517D02*
X145550Y727850D01*
X145050Y727933D01*
X144383Y727767D01*
X143883Y727433D01*
X143550Y726850D01*
X143467Y726267D01*
X143550Y725683D01*
X143883Y725183D01*
X144383Y724767D01*
X145050Y724600D01*
X145633Y724767D01*
X146133Y725100D01*
G01X150400Y727933D02*
Y724600D01*
G01Y729267D02*
X150233Y729350D01*
Y729517D01*
X150400Y729600D01*
X150567Y729517D01*
Y729350D01*
X150400Y729267D01*
G01X155500Y724600D02*
Y728850D01*
X155667Y729267D01*
X156000Y729517D01*
X156500Y729600D01*
X157000Y729433D01*
X157250Y729017D01*
G01X156250Y727600D02*
X154583D01*
G01X161600Y727933D02*
Y724600D01*
G01Y729267D02*
X161433Y729350D01*
Y729517D01*
X161600Y729600D01*
X161767Y729517D01*
Y729350D01*
X161600Y729267D01*
G01X168533Y727517D02*
X167950Y727850D01*
X167450Y727933D01*
X166783Y727767D01*
X166283Y727433D01*
X165950Y726850D01*
X165867Y726267D01*
X165950Y725683D01*
X166283Y725183D01*
X166783Y724767D01*
X167450Y724600D01*
X168033Y724767D01*
X168533Y725100D01*
G01X174300Y724600D02*
Y727933D01*
G01Y727350D02*
X173967Y727683D01*
X173467Y727850D01*
X172883Y727933D01*
X172300Y727767D01*
X171800Y727433D01*
X171467Y726933D01*
X171300Y726267D01*
X171467Y725600D01*
X171800Y725100D01*
X172300Y724767D01*
X172883Y724600D01*
X173467Y724683D01*
X173967Y724933D01*
X174300Y725267D01*
G01X178400Y729600D02*
Y724600D01*
G01X177233Y727933D02*
X179567D01*
G01X184000D02*
Y724600D01*
G01Y729267D02*
X183833Y729350D01*
Y729517D01*
X184000Y729600D01*
X184167Y729517D01*
Y729350D01*
X184000Y729267D01*
G01X189600Y724600D02*
X189100Y724683D01*
X188600Y725017D01*
X188267Y725600D01*
X188100Y726267D01*
X188267Y726933D01*
X188600Y727517D01*
X189100Y727850D01*
X189600Y727933D01*
X190100Y727850D01*
X190600Y727517D01*
X190933Y726933D01*
X191017Y726267D01*
X190933Y725600D01*
X190600Y725017D01*
X190100Y724683D01*
X189600Y724600D01*
G01X193783D02*
Y727933D01*
G01Y727100D02*
X194117Y727517D01*
X194617Y727850D01*
X195283Y727933D01*
X195867Y727850D01*
X196367Y727517D01*
X196617Y726933D01*
Y724600D01*
G01X205900D02*
Y728850D01*
X206067Y729267D01*
X206400Y729517D01*
X206900Y729600D01*
X207400Y729433D01*
X207650Y729017D01*
G01X206650Y727600D02*
X204983D01*
G01X212000Y724600D02*
X211500Y724683D01*
X211000Y725017D01*
X210667Y725600D01*
X210500Y726267D01*
X210667Y726933D01*
X211000Y727517D01*
X211500Y727850D01*
X212000Y727933D01*
X212500Y727850D01*
X213000Y727517D01*
X213333Y726933D01*
X213417Y726267D01*
X213333Y725600D01*
X213000Y725017D01*
X212500Y724683D01*
X212000Y724600D01*
G01X216433D02*
Y727933D01*
G01Y727267D02*
X216850Y727600D01*
X217267Y727850D01*
X217850Y727933D01*
X218267Y727850D01*
X218767Y727600D01*
G01X227133Y724600D02*
Y729600D01*
X229217D01*
X229883Y729350D01*
X230300Y729017D01*
X230467Y728350D01*
X230300Y727683D01*
X229800Y727267D01*
X229217Y727017D01*
X227133D01*
G01X229217D02*
X230467Y724600D01*
G01X233150Y726850D02*
X235817D01*
X235567Y727433D01*
X235150Y727767D01*
X234567Y727933D01*
X233983Y727850D01*
X233483Y727600D01*
X233150Y727017D01*
X232983Y726517D01*
Y726017D01*
X233150Y725517D01*
X233567Y725017D01*
X234067Y724683D01*
X234650Y724600D01*
X235233Y724767D01*
X235817Y725267D01*
G01X238750Y725183D02*
X239167Y724850D01*
X239750Y724600D01*
X240250D01*
X240750Y724767D01*
X241083Y725017D01*
X241250Y725350D01*
X241167Y725850D01*
X240833Y726100D01*
X239333Y726600D01*
X239000Y727183D01*
X239167Y727600D01*
X239500Y727850D01*
X240000Y727933D01*
X240500Y727850D01*
X241000Y727600D01*
G01X245600Y727933D02*
Y724600D01*
G01Y729267D02*
X245433Y729350D01*
Y729517D01*
X245600Y729600D01*
X245767Y729517D01*
Y729350D01*
X245600Y729267D01*
G01X249783Y724600D02*
Y727933D01*
G01Y727100D02*
X250117Y727517D01*
X250617Y727850D01*
X251283Y727933D01*
X251867Y727850D01*
X252367Y727517D01*
X252617Y726933D01*
Y724600D01*
G01X261400Y729600D02*
X263400D01*
G01X262400D02*
Y724600D01*
G01X261400D02*
X263400D01*
G01X265500D02*
Y727933D01*
G01Y727017D02*
X265750Y727433D01*
X266167Y727767D01*
X266750Y727933D01*
X267333Y727767D01*
X267750Y727433D01*
X268000Y727017D01*
Y724600D01*
G01Y727017D02*
X268250Y727433D01*
X268667Y727767D01*
X269250Y727933D01*
X269833Y727767D01*
X270250Y727433D01*
X270500Y726933D01*
Y724600D01*
G01X272100Y722933D02*
Y727933D01*
G01Y727183D02*
X272517Y727600D01*
X272933Y727850D01*
X273600Y727933D01*
X274183Y727850D01*
X274767Y727433D01*
X275017Y726850D01*
X275100Y726267D01*
X275017Y725683D01*
X274767Y725100D01*
X274267Y724767D01*
X273600Y724600D01*
X273017Y724683D01*
X272433Y724933D01*
X272100Y725267D01*
G01X278033Y724600D02*
Y727933D01*
G01Y727267D02*
X278450Y727600D01*
X278867Y727850D01*
X279450Y727933D01*
X279867Y727850D01*
X280367Y727600D01*
G01X283550Y726850D02*
X286217D01*
X285967Y727433D01*
X285550Y727767D01*
X284967Y727933D01*
X284383Y727850D01*
X283883Y727600D01*
X283550Y727017D01*
X283383Y726517D01*
Y726017D01*
X283550Y725517D01*
X283967Y725017D01*
X284467Y724683D01*
X285050Y724600D01*
X285633Y724767D01*
X286217Y725267D01*
G01X289233Y723350D02*
X289817Y723017D01*
X290483Y722933D01*
X291067Y723017D01*
X291567Y723433D01*
X291900Y724017D01*
Y727933D01*
G01Y727267D02*
X291567Y727600D01*
X291067Y727850D01*
X290483Y727933D01*
X289817Y727767D01*
X289400Y727433D01*
X289067Y726850D01*
X288900Y726267D01*
X288983Y725767D01*
X289317Y725183D01*
X289817Y724767D01*
X290483Y724600D01*
X290983Y724683D01*
X291567Y725017D01*
X291900Y725350D01*
G01X294583Y724600D02*
Y727933D01*
G01Y727100D02*
X294917Y727517D01*
X295417Y727850D01*
X296083Y727933D01*
X296667Y727850D01*
X297167Y727517D01*
X297417Y726933D01*
Y724600D01*
G01X303100D02*
Y727933D01*
G01Y727350D02*
X302767Y727683D01*
X302267Y727850D01*
X301683Y727933D01*
X301100Y727767D01*
X300600Y727433D01*
X300267Y726933D01*
X300100Y726267D01*
X300267Y725600D01*
X300600Y725100D01*
X301100Y724767D01*
X301683Y724600D01*
X302267Y724683D01*
X302767Y724933D01*
X303100Y725267D01*
G01X307200Y729600D02*
Y724600D01*
G01X306033Y727933D02*
X308367D01*
G01X311550Y726850D02*
X314217D01*
X313967Y727433D01*
X313550Y727767D01*
X312967Y727933D01*
X312383Y727850D01*
X311883Y727600D01*
X311550Y727017D01*
X311383Y726517D01*
Y726017D01*
X311550Y725517D01*
X311967Y725017D01*
X312467Y724683D01*
X313050Y724600D01*
X313633Y724767D01*
X314217Y725267D01*
G01X319900Y729600D02*
Y724600D01*
G01Y725350D02*
X319567Y724933D01*
X319067Y724683D01*
X318483Y724600D01*
X317817Y724767D01*
X317317Y725183D01*
X316983Y725683D01*
X316900Y726267D01*
X316983Y726850D01*
X317317Y727350D01*
X317817Y727767D01*
X318483Y727933D01*
X319067Y727850D01*
X319483Y727683D01*
X319900Y727350D01*
G01X328017Y724600D02*
Y729600D01*
X331183D01*
G01X330017Y727183D02*
X328017D01*
G01X336700Y724600D02*
Y727933D01*
G01Y727350D02*
X336367Y727683D01*
X335867Y727850D01*
X335283Y727933D01*
X334700Y727767D01*
X334200Y727433D01*
X333867Y726933D01*
X333700Y726267D01*
X333867Y725600D01*
X334200Y725100D01*
X334700Y724767D01*
X335283Y724600D01*
X335867Y724683D01*
X336367Y724933D01*
X336700Y725267D01*
G01X339300Y724600D02*
Y729600D01*
G01Y727100D02*
X339717Y727600D01*
X340217Y727850D01*
X340717Y727933D01*
X341467Y727767D01*
X341967Y727433D01*
X342300Y726850D01*
Y726183D01*
X342133Y725517D01*
X341800Y725017D01*
X341217Y724683D01*
X340717Y724600D01*
X340217Y724683D01*
X339717Y724933D01*
X339300Y725350D01*
G01X345233Y724600D02*
Y727933D01*
G01Y727267D02*
X345650Y727600D01*
X346067Y727850D01*
X346650Y727933D01*
X347067Y727850D01*
X347567Y727600D01*
G01X352000Y727933D02*
Y724600D01*
G01Y729267D02*
X351833Y729350D01*
Y729517D01*
X352000Y729600D01*
X352167Y729517D01*
Y729350D01*
X352000Y729267D01*
G01X358933Y727517D02*
X358350Y727850D01*
X357850Y727933D01*
X357183Y727767D01*
X356683Y727433D01*
X356350Y726850D01*
X356267Y726267D01*
X356350Y725683D01*
X356683Y725183D01*
X357183Y724767D01*
X357850Y724600D01*
X358433Y724767D01*
X358933Y725100D01*
G01X362783Y722933D02*
X361950Y723767D01*
X361533Y724600D01*
Y727933D01*
X361950Y728767D01*
X362783Y729600D01*
G01X367133Y724600D02*
Y729600D01*
X369133D01*
X369800Y729350D01*
X370300Y728767D01*
X370467Y728100D01*
X370300Y727433D01*
X369883Y726933D01*
X369133Y726683D01*
X367133D01*
G01X373233Y724600D02*
Y727933D01*
G01Y727267D02*
X373650Y727600D01*
X374067Y727850D01*
X374650Y727933D01*
X375067Y727850D01*
X375567Y727600D01*
G01X378750Y726850D02*
X381417D01*
X381167Y727433D01*
X380750Y727767D01*
X380167Y727933D01*
X379583Y727850D01*
X379083Y727600D01*
X378750Y727017D01*
X378583Y726517D01*
Y726017D01*
X378750Y725517D01*
X379167Y725017D01*
X379667Y724683D01*
X380250Y724600D01*
X380833Y724767D01*
X381417Y725267D01*
G01X384100Y722933D02*
Y727933D01*
G01Y727183D02*
X384517Y727600D01*
X384933Y727850D01*
X385600Y727933D01*
X386183Y727850D01*
X386767Y727433D01*
X387017Y726850D01*
X387100Y726267D01*
X387017Y725683D01*
X386767Y725100D01*
X386267Y724767D01*
X385600Y724600D01*
X385017Y724683D01*
X384433Y724933D01*
X384100Y725267D01*
G01X390033Y724600D02*
Y727933D01*
G01Y727267D02*
X390450Y727600D01*
X390867Y727850D01*
X391450Y727933D01*
X391867Y727850D01*
X392367Y727600D01*
G01X395550Y726850D02*
X398217D01*
X397967Y727433D01*
X397550Y727767D01*
X396967Y727933D01*
X396383Y727850D01*
X395883Y727600D01*
X395550Y727017D01*
X395383Y726517D01*
Y726017D01*
X395550Y725517D01*
X395967Y725017D01*
X396467Y724683D01*
X397050Y724600D01*
X397633Y724767D01*
X398217Y725267D01*
G01X401233Y723350D02*
X401817Y723017D01*
X402483Y722933D01*
X403067Y723017D01*
X403567Y723433D01*
X403900Y724017D01*
Y727933D01*
G01Y727267D02*
X403567Y727600D01*
X403067Y727850D01*
X402483Y727933D01*
X401817Y727767D01*
X401400Y727433D01*
X401067Y726850D01*
X400900Y726267D01*
X400983Y725767D01*
X401317Y725183D01*
X401817Y724767D01*
X402483Y724600D01*
X402983Y724683D01*
X403567Y725017D01*
X403900Y725350D01*
G01X408417Y722933D02*
X409250Y723767D01*
X409667Y724600D01*
Y727933D01*
X409250Y728767D01*
X408417Y729600D01*
G01X418700Y724600D02*
Y728850D01*
X418867Y729267D01*
X419200Y729517D01*
X419700Y729600D01*
X420200Y729433D01*
X420450Y729017D01*
G01X419450Y727600D02*
X417783D01*
G01X424800Y724600D02*
X424300Y724683D01*
X423800Y725017D01*
X423467Y725600D01*
X423300Y726267D01*
X423467Y726933D01*
X423800Y727517D01*
X424300Y727850D01*
X424800Y727933D01*
X425300Y727850D01*
X425800Y727517D01*
X426133Y726933D01*
X426217Y726267D01*
X426133Y725600D01*
X425800Y725017D01*
X425300Y724683D01*
X424800Y724600D01*
G01X429233D02*
Y727933D01*
G01Y727267D02*
X429650Y727600D01*
X430067Y727850D01*
X430650Y727933D01*
X431067Y727850D01*
X431567Y727600D01*
G01X439433Y724600D02*
Y729600D01*
X441600Y725433D01*
X443767Y729600D01*
Y724600D01*
G01X445783Y727933D02*
Y725600D01*
X446117Y725017D01*
X446617Y724683D01*
X447200Y724600D01*
X447783Y724683D01*
X448283Y725017D01*
X448617Y725600D01*
G01Y724600D02*
Y727933D01*
G01X452800Y724600D02*
Y729600D01*
G01X458400D02*
Y724600D01*
G01X457233Y727933D02*
X459567D01*
G01X464000D02*
Y724600D01*
G01Y729267D02*
X463833Y729350D01*
Y729517D01*
X464000Y729600D01*
X464167Y729517D01*
Y729350D01*
X464000Y729267D01*
G01X469600Y724600D02*
Y729600D01*
G01X476700Y724600D02*
Y727933D01*
G01Y727350D02*
X476367Y727683D01*
X475867Y727850D01*
X475283Y727933D01*
X474700Y727767D01*
X474200Y727433D01*
X473867Y726933D01*
X473700Y726267D01*
X473867Y725600D01*
X474200Y725100D01*
X474700Y724767D01*
X475283Y724600D01*
X475867Y724683D01*
X476367Y724933D01*
X476700Y725267D01*
G01X479050Y723100D02*
X479550Y722933D01*
X480217Y723100D01*
X480633Y723433D01*
X480967Y723850D01*
X481467Y725183D01*
X482550Y727933D01*
G01X479883D02*
X481467Y725183D01*
G01X485150Y726850D02*
X487817D01*
X487567Y727433D01*
X487150Y727767D01*
X486567Y727933D01*
X485983Y727850D01*
X485483Y727600D01*
X485150Y727017D01*
X484983Y726517D01*
Y726017D01*
X485150Y725517D01*
X485567Y725017D01*
X486067Y724683D01*
X486650Y724600D01*
X487233Y724767D01*
X487817Y725267D01*
G01X490833Y724600D02*
Y727933D01*
G01Y727267D02*
X491250Y727600D01*
X491667Y727850D01*
X492250Y727933D01*
X492667Y727850D01*
X493167Y727600D01*
G01X501533Y724600D02*
Y729600D01*
X503533D01*
X504200Y729350D01*
X504700Y728767D01*
X504867Y728100D01*
X504700Y727433D01*
X504283Y726933D01*
X503533Y726683D01*
X501533D01*
G01X507633Y724600D02*
Y727933D01*
G01Y727267D02*
X508050Y727600D01*
X508467Y727850D01*
X509050Y727933D01*
X509467Y727850D01*
X509967Y727600D01*
G01X514400Y727933D02*
Y724600D01*
G01Y729267D02*
X514233Y729350D01*
Y729517D01*
X514400Y729600D01*
X514567Y729517D01*
Y729350D01*
X514400Y729267D01*
G01X518583Y724600D02*
Y727933D01*
G01Y727100D02*
X518917Y727517D01*
X519417Y727850D01*
X520083Y727933D01*
X520667Y727850D01*
X521167Y727517D01*
X521417Y726933D01*
Y724600D01*
G01X525600Y729600D02*
Y724600D01*
G01X524433Y727933D02*
X526767D01*
G01X529950Y726850D02*
X532617D01*
X532367Y727433D01*
X531950Y727767D01*
X531367Y727933D01*
X530783Y727850D01*
X530283Y727600D01*
X529950Y727017D01*
X529783Y726517D01*
Y726017D01*
X529950Y725517D01*
X530367Y725017D01*
X530867Y724683D01*
X531450Y724600D01*
X532033Y724767D01*
X532617Y725267D01*
G01X538300Y729600D02*
Y724600D01*
G01Y725350D02*
X537967Y724933D01*
X537467Y724683D01*
X536883Y724600D01*
X536217Y724767D01*
X535717Y725183D01*
X535383Y725683D01*
X535300Y726267D01*
X535383Y726850D01*
X535717Y727350D01*
X536217Y727767D01*
X536883Y727933D01*
X537467Y727850D01*
X537883Y727683D01*
X538300Y727350D01*
G01X548667Y727267D02*
X549000Y727517D01*
X549250Y727933D01*
X549417Y728517D01*
X549250Y729017D01*
X548917Y729350D01*
X548333Y729600D01*
X546083D01*
Y724600D01*
X548833D01*
X549417Y724933D01*
X549750Y725433D01*
X549917Y726017D01*
X549750Y726600D01*
X549250Y727100D01*
X548667Y727267D01*
X546083D01*
G01X553600Y724600D02*
X553100Y724683D01*
X552600Y725017D01*
X552267Y725600D01*
X552100Y726267D01*
X552267Y726933D01*
X552600Y727517D01*
X553100Y727850D01*
X553600Y727933D01*
X554100Y727850D01*
X554600Y727517D01*
X554933Y726933D01*
X555017Y726267D01*
X554933Y725600D01*
X554600Y725017D01*
X554100Y724683D01*
X553600Y724600D01*
G01X560700D02*
Y727933D01*
G01Y727350D02*
X560367Y727683D01*
X559867Y727850D01*
X559283Y727933D01*
X558700Y727767D01*
X558200Y727433D01*
X557867Y726933D01*
X557700Y726267D01*
X557867Y725600D01*
X558200Y725100D01*
X558700Y724767D01*
X559283Y724600D01*
X559867Y724683D01*
X560367Y724933D01*
X560700Y725267D01*
G01X563633Y724600D02*
Y727933D01*
G01Y727267D02*
X564050Y727600D01*
X564467Y727850D01*
X565050Y727933D01*
X565467Y727850D01*
X565967Y727600D01*
G01X571900Y729600D02*
Y724600D01*
G01Y725350D02*
X571567Y724933D01*
X571067Y724683D01*
X570483Y724600D01*
X569817Y724767D01*
X569317Y725183D01*
X568983Y725683D01*
X568900Y726267D01*
X568983Y726850D01*
X569317Y727350D01*
X569817Y727767D01*
X570483Y727933D01*
X571067Y727850D01*
X571483Y727683D01*
X571900Y727350D01*
G01X574750Y725183D02*
X575167Y724850D01*
X575750Y724600D01*
X576250D01*
X576750Y724767D01*
X577083Y725017D01*
X577250Y725350D01*
X577167Y725850D01*
X576833Y726100D01*
X575333Y726600D01*
X575000Y727183D01*
X575167Y727600D01*
X575500Y727850D01*
X576000Y727933D01*
X576500Y727850D01*
X577000Y727600D01*
G01X71000Y738600D02*
X73000D01*
G01X72000D02*
Y733600D01*
G01X71000D02*
X73000D01*
G01X75933D02*
Y738600D01*
X77933D01*
X78600Y738350D01*
X79100Y737767D01*
X79267Y737100D01*
X79100Y736433D01*
X78683Y735933D01*
X77933Y735683D01*
X75933D01*
G01X85033Y738183D02*
X84533Y738433D01*
X83950Y738600D01*
X83283D01*
X82533Y738350D01*
X81950Y737933D01*
X81533Y737433D01*
X81200Y736600D01*
X81117Y735850D01*
X81283Y735100D01*
X81533Y734600D01*
X82033Y734100D01*
X82617Y733767D01*
X83200Y733600D01*
X83783D01*
X84367Y733767D01*
X84867Y734017D01*
X85283Y734350D01*
G01X87717Y735267D02*
X89883D01*
G01X92233Y733600D02*
Y738600D01*
X94400Y734433D01*
X96567Y738600D01*
Y733600D01*
G01X98417D02*
Y738600D01*
X101583D01*
G01X100417Y736183D02*
X98417D01*
G01X104517Y735267D02*
X106683D01*
G01X111200Y733600D02*
Y738600D01*
X110200Y737600D01*
G01Y733600D02*
X112200D01*
G01X114967Y734350D02*
X115467Y733933D01*
X116050Y733683D01*
X116800Y733600D01*
X117550Y733767D01*
X118133Y734100D01*
X118550Y734683D01*
X118633Y735350D01*
X118467Y736017D01*
X118050Y736433D01*
X117467Y736767D01*
X116883Y736850D01*
X116300Y736767D01*
X115550Y736433D01*
X115800Y738600D01*
X118050D01*
G01X122400D02*
X121733Y738433D01*
X121233Y738017D01*
X120900Y737517D01*
X120650Y736850D01*
X120567Y736100D01*
X120650Y735350D01*
X120900Y734683D01*
X121233Y734183D01*
X121733Y733767D01*
X122400Y733600D01*
X123067Y733767D01*
X123567Y734183D01*
X123900Y734683D01*
X124150Y735350D01*
X124233Y736100D01*
X124150Y736850D01*
X123900Y737517D01*
X123567Y738017D01*
X123067Y738433D01*
X122400Y738600D01*
G01X131433Y733600D02*
Y738600D01*
X133600Y734433D01*
X135767Y738600D01*
Y733600D01*
G01X137950Y735850D02*
X140617D01*
X140367Y736433D01*
X139950Y736767D01*
X139367Y736933D01*
X138783Y736850D01*
X138283Y736600D01*
X137950Y736017D01*
X137783Y735517D01*
Y735017D01*
X137950Y734517D01*
X138367Y734017D01*
X138867Y733683D01*
X139450Y733600D01*
X140033Y733767D01*
X140617Y734267D01*
G01X144800Y738600D02*
Y733600D01*
G01X143633Y736933D02*
X145967D01*
G01X151900Y733600D02*
Y736933D01*
G01Y736350D02*
X151567Y736683D01*
X151067Y736850D01*
X150483Y736933D01*
X149900Y736767D01*
X149400Y736433D01*
X149067Y735933D01*
X148900Y735267D01*
X149067Y734600D01*
X149400Y734100D01*
X149900Y733767D01*
X150483Y733600D01*
X151067Y733683D01*
X151567Y733933D01*
X151900Y734267D01*
G01X156000Y733600D02*
Y738600D01*
G01X165617Y733600D02*
Y738600D01*
X168783D01*
G01X167617Y736183D02*
X165617D01*
G01X172800Y733600D02*
X172300Y733683D01*
X171800Y734017D01*
X171467Y734600D01*
X171300Y735267D01*
X171467Y735933D01*
X171800Y736517D01*
X172300Y736850D01*
X172800Y736933D01*
X173300Y736850D01*
X173800Y736517D01*
X174133Y735933D01*
X174217Y735267D01*
X174133Y734600D01*
X173800Y734017D01*
X173300Y733683D01*
X172800Y733600D01*
G01X178400Y736933D02*
Y733600D01*
G01Y738267D02*
X178233Y738350D01*
Y738517D01*
X178400Y738600D01*
X178567Y738517D01*
Y738350D01*
X178400Y738267D01*
G01X184000Y733600D02*
Y738600D01*
G01X194700Y733600D02*
Y737850D01*
X194867Y738267D01*
X195200Y738517D01*
X195700Y738600D01*
X196200Y738433D01*
X196450Y738017D01*
G01X195450Y736600D02*
X193783D01*
G01X200800Y733600D02*
X200300Y733683D01*
X199800Y734017D01*
X199467Y734600D01*
X199300Y735267D01*
X199467Y735933D01*
X199800Y736517D01*
X200300Y736850D01*
X200800Y736933D01*
X201300Y736850D01*
X201800Y736517D01*
X202133Y735933D01*
X202217Y735267D01*
X202133Y734600D01*
X201800Y734017D01*
X201300Y733683D01*
X200800Y733600D01*
G01X205233D02*
Y736933D01*
G01Y736267D02*
X205650Y736600D01*
X206067Y736850D01*
X206650Y736933D01*
X207067Y736850D01*
X207567Y736600D01*
G01X215933Y733600D02*
Y738600D01*
X217933D01*
X218600Y738350D01*
X219100Y737767D01*
X219267Y737100D01*
X219100Y736433D01*
X218683Y735933D01*
X217933Y735683D01*
X215933D01*
G01X222033Y733600D02*
Y736933D01*
G01Y736267D02*
X222450Y736600D01*
X222867Y736850D01*
X223450Y736933D01*
X223867Y736850D01*
X224367Y736600D01*
G01X228800Y736933D02*
Y733600D01*
G01Y738267D02*
X228633Y738350D01*
Y738517D01*
X228800Y738600D01*
X228967Y738517D01*
Y738350D01*
X228800Y738267D01*
G01X232983Y733600D02*
Y736933D01*
G01Y736100D02*
X233317Y736517D01*
X233817Y736850D01*
X234483Y736933D01*
X235067Y736850D01*
X235567Y736517D01*
X235817Y735933D01*
Y733600D01*
G01X240000Y738600D02*
Y733600D01*
G01X238833Y736933D02*
X241167D01*
G01X244350Y735850D02*
X247017D01*
X246767Y736433D01*
X246350Y736767D01*
X245767Y736933D01*
X245183Y736850D01*
X244683Y736600D01*
X244350Y736017D01*
X244183Y735517D01*
Y735017D01*
X244350Y734517D01*
X244767Y734017D01*
X245267Y733683D01*
X245850Y733600D01*
X246433Y733767D01*
X247017Y734267D01*
G01X252700Y738600D02*
Y733600D01*
G01Y734350D02*
X252367Y733933D01*
X251867Y733683D01*
X251283Y733600D01*
X250617Y733767D01*
X250117Y734183D01*
X249783Y734683D01*
X249700Y735267D01*
X249783Y735850D01*
X250117Y736350D01*
X250617Y736767D01*
X251283Y736933D01*
X251867Y736850D01*
X252283Y736683D01*
X252700Y736350D01*
G01X259900Y738600D02*
X261067Y733600D01*
X262400Y738600D01*
X263733Y733600D01*
X264900Y738600D01*
G01X268000Y736933D02*
Y733600D01*
G01Y738267D02*
X267833Y738350D01*
Y738517D01*
X268000Y738600D01*
X268167Y738517D01*
Y738350D01*
X268000Y738267D01*
G01X272433Y733600D02*
Y736933D01*
G01Y736267D02*
X272850Y736600D01*
X273267Y736850D01*
X273850Y736933D01*
X274267Y736850D01*
X274767Y736600D01*
G01X279200Y736933D02*
Y733600D01*
G01Y738267D02*
X279033Y738350D01*
Y738517D01*
X279200Y738600D01*
X279367Y738517D01*
Y738350D01*
X279200Y738267D01*
G01X283383Y733600D02*
Y736933D01*
G01Y736100D02*
X283717Y736517D01*
X284217Y736850D01*
X284883Y736933D01*
X285467Y736850D01*
X285967Y736517D01*
X286217Y735933D01*
Y733600D01*
G01X289233Y732350D02*
X289817Y732017D01*
X290483Y731933D01*
X291067Y732017D01*
X291567Y732433D01*
X291900Y733017D01*
Y736933D01*
G01Y736267D02*
X291567Y736600D01*
X291067Y736850D01*
X290483Y736933D01*
X289817Y736767D01*
X289400Y736433D01*
X289067Y735850D01*
X288900Y735267D01*
X288983Y734767D01*
X289317Y734183D01*
X289817Y733767D01*
X290483Y733600D01*
X290983Y733683D01*
X291567Y734017D01*
X291900Y734350D01*
G01X299517Y733600D02*
X301600Y738600D01*
X303683Y733600D01*
G01X302933Y735350D02*
X300267D01*
G01X305700Y731933D02*
Y736933D01*
G01Y736183D02*
X306117Y736600D01*
X306533Y736850D01*
X307200Y736933D01*
X307783Y736850D01*
X308367Y736433D01*
X308617Y735850D01*
X308700Y735267D01*
X308617Y734683D01*
X308367Y734100D01*
X307867Y733767D01*
X307200Y733600D01*
X306617Y733683D01*
X306033Y733933D01*
X305700Y734267D01*
G01X311300Y731933D02*
Y736933D01*
G01Y736183D02*
X311717Y736600D01*
X312133Y736850D01*
X312800Y736933D01*
X313383Y736850D01*
X313967Y736433D01*
X314217Y735850D01*
X314300Y735267D01*
X314217Y734683D01*
X313967Y734100D01*
X313467Y733767D01*
X312800Y733600D01*
X312217Y733683D01*
X311633Y733933D01*
X311300Y734267D01*
G01X318400Y733600D02*
Y738600D01*
G01X324000Y736933D02*
Y733600D01*
G01Y738267D02*
X323833Y738350D01*
Y738517D01*
X324000Y738600D01*
X324167Y738517D01*
Y738350D01*
X324000Y738267D01*
G01X330933Y736517D02*
X330350Y736850D01*
X329850Y736933D01*
X329183Y736767D01*
X328683Y736433D01*
X328350Y735850D01*
X328267Y735267D01*
X328350Y734683D01*
X328683Y734183D01*
X329183Y733767D01*
X329850Y733600D01*
X330433Y733767D01*
X330933Y734100D01*
G01X336700Y733600D02*
Y736933D01*
G01Y736350D02*
X336367Y736683D01*
X335867Y736850D01*
X335283Y736933D01*
X334700Y736767D01*
X334200Y736433D01*
X333867Y735933D01*
X333700Y735267D01*
X333867Y734600D01*
X334200Y734100D01*
X334700Y733767D01*
X335283Y733600D01*
X335867Y733683D01*
X336367Y733933D01*
X336700Y734267D01*
G01X340800Y738600D02*
Y733600D01*
G01X339633Y736933D02*
X341967D01*
G01X346400D02*
Y733600D01*
G01Y738267D02*
X346233Y738350D01*
Y738517D01*
X346400Y738600D01*
X346567Y738517D01*
Y738350D01*
X346400Y738267D01*
G01X352000Y733600D02*
X351500Y733683D01*
X351000Y734017D01*
X350667Y734600D01*
X350500Y735267D01*
X350667Y735933D01*
X351000Y736517D01*
X351500Y736850D01*
X352000Y736933D01*
X352500Y736850D01*
X353000Y736517D01*
X353333Y735933D01*
X353417Y735267D01*
X353333Y734600D01*
X353000Y734017D01*
X352500Y733683D01*
X352000Y733600D01*
G01X356183D02*
Y736933D01*
G01Y736100D02*
X356517Y736517D01*
X357017Y736850D01*
X357683Y736933D01*
X358267Y736850D01*
X358767Y736517D01*
X359017Y735933D01*
Y733600D01*
G01X361950Y734183D02*
X362367Y733850D01*
X362950Y733600D01*
X363450D01*
X363950Y733767D01*
X364283Y734017D01*
X364450Y734350D01*
X364367Y734850D01*
X364033Y735100D01*
X362533Y735600D01*
X362200Y736183D01*
X362367Y736600D01*
X362700Y736850D01*
X363200Y736933D01*
X363700Y736850D01*
X364200Y736600D01*
G01X34000Y663333D02*
Y668333D01*
G01Y667583D02*
X34417Y668000D01*
X34833Y668250D01*
X35500Y668333D01*
X36083Y668250D01*
X36667Y667833D01*
X36917Y667250D01*
X37000Y666667D01*
X36917Y666083D01*
X36667Y665500D01*
X36167Y665167D01*
X35500Y665000D01*
X34917Y665083D01*
X34333Y665333D01*
X34000Y665667D01*
G01X39933Y665000D02*
Y668333D01*
G01Y667667D02*
X40350Y668000D01*
X40767Y668250D01*
X41350Y668333D01*
X41767Y668250D01*
X42267Y668000D01*
G01X46700Y665000D02*
X46200Y665083D01*
X45700Y665417D01*
X45367Y666000D01*
X45200Y666667D01*
X45367Y667333D01*
X45700Y667917D01*
X46200Y668250D01*
X46700Y668333D01*
X47200Y668250D01*
X47700Y667917D01*
X48033Y667333D01*
X48117Y666667D01*
X48033Y666000D01*
X47700Y665417D01*
X47200Y665083D01*
X46700Y665000D01*
G01X53633Y667917D02*
X53050Y668250D01*
X52550Y668333D01*
X51883Y668167D01*
X51383Y667833D01*
X51050Y667250D01*
X50967Y666667D01*
X51050Y666083D01*
X51383Y665583D01*
X51883Y665167D01*
X52550Y665000D01*
X53133Y665167D01*
X53633Y665500D01*
G01X56650Y667250D02*
X59317D01*
X59067Y667833D01*
X58650Y668167D01*
X58067Y668333D01*
X57483Y668250D01*
X56983Y668000D01*
X56650Y667417D01*
X56483Y666917D01*
Y666417D01*
X56650Y665917D01*
X57067Y665417D01*
X57567Y665083D01*
X58150Y665000D01*
X58733Y665167D01*
X59317Y665667D01*
G01X62250Y665583D02*
X62667Y665250D01*
X63250Y665000D01*
X63750D01*
X64250Y665167D01*
X64583Y665417D01*
X64750Y665750D01*
X64667Y666250D01*
X64333Y666500D01*
X62833Y667000D01*
X62500Y667583D01*
X62667Y668000D01*
X63000Y668250D01*
X63500Y668333D01*
X64000Y668250D01*
X64500Y668000D01*
G01X67850Y665583D02*
X68267Y665250D01*
X68850Y665000D01*
X69350D01*
X69850Y665167D01*
X70183Y665417D01*
X70350Y665750D01*
X70267Y666250D01*
X69933Y666500D01*
X68433Y667000D01*
X68100Y667583D01*
X68267Y668000D01*
X68600Y668250D01*
X69100Y668333D01*
X69600Y668250D01*
X70100Y668000D01*
G01X67000Y725433D02*
X66833Y725517D01*
Y725683D01*
X67000Y725767D01*
X67167Y725683D01*
Y725517D01*
X67000Y725433D01*
G01Y734433D02*
X66833Y734517D01*
Y734683D01*
X67000Y734767D01*
X67167Y734683D01*
Y734517D01*
X67000Y734433D01*
G01X71000Y729600D02*
X73000D01*
G01X72000D02*
Y724600D01*
G01X71000D02*
X73000D01*
G01X75933D02*
Y729600D01*
X77933D01*
X78600Y729350D01*
X79100Y728767D01*
X79267Y728100D01*
X79100Y727433D01*
X78683Y726933D01*
X77933Y726683D01*
X75933D01*
G01X85033Y729183D02*
X84533Y729433D01*
X83950Y729600D01*
X83283D01*
X82533Y729350D01*
X81950Y728933D01*
X81533Y728433D01*
X81200Y727600D01*
X81117Y726850D01*
X81283Y726100D01*
X81533Y725600D01*
X82033Y725100D01*
X82617Y724767D01*
X83200Y724600D01*
X83783D01*
X84367Y724767D01*
X84867Y725017D01*
X85283Y725350D01*
G01X87717Y726267D02*
X89883D01*
G01X92733Y729600D02*
Y724600D01*
X96067D01*
G01X98917Y726267D02*
X101083D01*
G01X105600Y724600D02*
Y729600D01*
X104600Y728600D01*
G01Y724600D02*
X106600D01*
G01X111200Y729600D02*
X110533Y729433D01*
X110033Y729017D01*
X109700Y728517D01*
X109450Y727850D01*
X109367Y727100D01*
X109450Y726350D01*
X109700Y725683D01*
X110033Y725183D01*
X110533Y724767D01*
X111200Y724600D01*
X111867Y724767D01*
X112367Y725183D01*
X112700Y725683D01*
X112950Y726350D01*
X113033Y727100D01*
X112950Y727850D01*
X112700Y728517D01*
X112367Y729017D01*
X111867Y729433D01*
X111200Y729600D01*
G01X115383Y725183D02*
X115967Y724767D01*
X116633Y724600D01*
X117300Y724767D01*
X117883Y725267D01*
X118300Y726017D01*
X118467Y726767D01*
Y727683D01*
X118300Y728433D01*
X117883Y729100D01*
X117383Y729433D01*
X116800Y729600D01*
X116133Y729433D01*
X115633Y729100D01*
X115300Y728600D01*
X115133Y727933D01*
X115300Y727350D01*
X115717Y726767D01*
X116217Y726433D01*
X116800Y726350D01*
X117467Y726517D01*
X117967Y726933D01*
X118467Y727683D01*
G01X126250Y725267D02*
X126917Y724850D01*
X127667Y724600D01*
X128333D01*
X129000Y724850D01*
X129500Y725267D01*
X129750Y725850D01*
X129583Y726433D01*
X129167Y726933D01*
X128417Y727267D01*
X127417Y727433D01*
X126833Y727767D01*
X126583Y728350D01*
X126750Y728933D01*
X127167Y729350D01*
X127750Y729600D01*
X128333D01*
X128917Y729433D01*
X129417Y729017D01*
G01X132100Y722933D02*
Y727933D01*
G01Y727183D02*
X132517Y727600D01*
X132933Y727850D01*
X133600Y727933D01*
X134183Y727850D01*
X134767Y727433D01*
X135017Y726850D01*
X135100Y726267D01*
X135017Y725683D01*
X134767Y725100D01*
X134267Y724767D01*
X133600Y724600D01*
X133017Y724683D01*
X132433Y724933D01*
X132100Y725267D01*
G01X137950Y726850D02*
X140617D01*
X140367Y727433D01*
X139950Y727767D01*
X139367Y727933D01*
X138783Y727850D01*
X138283Y727600D01*
X137950Y727017D01*
X137783Y726517D01*
Y726017D01*
X137950Y725517D01*
X138367Y725017D01*
X138867Y724683D01*
X139450Y724600D01*
X140033Y724767D01*
X140617Y725267D01*
G01X146133Y727517D02*
X145550Y727850D01*
X145050Y727933D01*
X144383Y727767D01*
X143883Y727433D01*
X143550Y726850D01*
X143467Y726267D01*
X143550Y725683D01*
X143883Y725183D01*
X144383Y724767D01*
X145050Y724600D01*
X145633Y724767D01*
X146133Y725100D01*
G01X150400Y727933D02*
Y724600D01*
G01Y729267D02*
X150233Y729350D01*
Y729517D01*
X150400Y729600D01*
X150567Y729517D01*
Y729350D01*
X150400Y729267D01*
G01X155500Y724600D02*
Y728850D01*
X155667Y729267D01*
X156000Y729517D01*
X156500Y729600D01*
X157000Y729433D01*
X157250Y729017D01*
G01X156250Y727600D02*
X154583D01*
G01X161600Y727933D02*
Y724600D01*
G01Y729267D02*
X161433Y729350D01*
Y729517D01*
X161600Y729600D01*
X161767Y729517D01*
Y729350D01*
X161600Y729267D01*
G01X168533Y727517D02*
X167950Y727850D01*
X167450Y727933D01*
X166783Y727767D01*
X166283Y727433D01*
X165950Y726850D01*
X165867Y726267D01*
X165950Y725683D01*
X166283Y725183D01*
X166783Y724767D01*
X167450Y724600D01*
X168033Y724767D01*
X168533Y725100D01*
G01X174300Y724600D02*
Y727933D01*
G01Y727350D02*
X173967Y727683D01*
X173467Y727850D01*
X172883Y727933D01*
X172300Y727767D01*
X171800Y727433D01*
X171467Y726933D01*
X171300Y726267D01*
X171467Y725600D01*
X171800Y725100D01*
X172300Y724767D01*
X172883Y724600D01*
X173467Y724683D01*
X173967Y724933D01*
X174300Y725267D01*
G01X178400Y729600D02*
Y724600D01*
G01X177233Y727933D02*
X179567D01*
G01X184000D02*
Y724600D01*
G01Y729267D02*
X183833Y729350D01*
Y729517D01*
X184000Y729600D01*
X184167Y729517D01*
Y729350D01*
X184000Y729267D01*
G01X189600Y724600D02*
X189100Y724683D01*
X188600Y725017D01*
X188267Y725600D01*
X188100Y726267D01*
X188267Y726933D01*
X188600Y727517D01*
X189100Y727850D01*
X189600Y727933D01*
X190100Y727850D01*
X190600Y727517D01*
X190933Y726933D01*
X191017Y726267D01*
X190933Y725600D01*
X190600Y725017D01*
X190100Y724683D01*
X189600Y724600D01*
G01X193783D02*
Y727933D01*
G01Y727100D02*
X194117Y727517D01*
X194617Y727850D01*
X195283Y727933D01*
X195867Y727850D01*
X196367Y727517D01*
X196617Y726933D01*
Y724600D01*
G01X205900D02*
Y728850D01*
X206067Y729267D01*
X206400Y729517D01*
X206900Y729600D01*
X207400Y729433D01*
X207650Y729017D01*
G01X206650Y727600D02*
X204983D01*
G01X212000Y724600D02*
X211500Y724683D01*
X211000Y725017D01*
X210667Y725600D01*
X210500Y726267D01*
X210667Y726933D01*
X211000Y727517D01*
X211500Y727850D01*
X212000Y727933D01*
X212500Y727850D01*
X213000Y727517D01*
X213333Y726933D01*
X213417Y726267D01*
X213333Y725600D01*
X213000Y725017D01*
X212500Y724683D01*
X212000Y724600D01*
G01X216433D02*
Y727933D01*
G01Y727267D02*
X216850Y727600D01*
X217267Y727850D01*
X217850Y727933D01*
X218267Y727850D01*
X218767Y727600D01*
G01X227133Y724600D02*
Y729600D01*
X229217D01*
X229883Y729350D01*
X230300Y729017D01*
X230467Y728350D01*
X230300Y727683D01*
X229800Y727267D01*
X229217Y727017D01*
X227133D01*
G01X229217D02*
X230467Y724600D01*
G01X233150Y726850D02*
X235817D01*
X235567Y727433D01*
X235150Y727767D01*
X234567Y727933D01*
X233983Y727850D01*
X233483Y727600D01*
X233150Y727017D01*
X232983Y726517D01*
Y726017D01*
X233150Y725517D01*
X233567Y725017D01*
X234067Y724683D01*
X234650Y724600D01*
X235233Y724767D01*
X235817Y725267D01*
G01X238750Y725183D02*
X239167Y724850D01*
X239750Y724600D01*
X240250D01*
X240750Y724767D01*
X241083Y725017D01*
X241250Y725350D01*
X241167Y725850D01*
X240833Y726100D01*
X239333Y726600D01*
X239000Y727183D01*
X239167Y727600D01*
X239500Y727850D01*
X240000Y727933D01*
X240500Y727850D01*
X241000Y727600D01*
G01X245600Y727933D02*
Y724600D01*
G01Y729267D02*
X245433Y729350D01*
Y729517D01*
X245600Y729600D01*
X245767Y729517D01*
Y729350D01*
X245600Y729267D01*
G01X249783Y724600D02*
Y727933D01*
G01Y727100D02*
X250117Y727517D01*
X250617Y727850D01*
X251283Y727933D01*
X251867Y727850D01*
X252367Y727517D01*
X252617Y726933D01*
Y724600D01*
G01X261400Y729600D02*
X263400D01*
G01X262400D02*
Y724600D01*
G01X261400D02*
X263400D01*
G01X265500D02*
Y727933D01*
G01Y727017D02*
X265750Y727433D01*
X266167Y727767D01*
X266750Y727933D01*
X267333Y727767D01*
X267750Y727433D01*
X268000Y727017D01*
Y724600D01*
G01Y727017D02*
X268250Y727433D01*
X268667Y727767D01*
X269250Y727933D01*
X269833Y727767D01*
X270250Y727433D01*
X270500Y726933D01*
Y724600D01*
G01X272100Y722933D02*
Y727933D01*
G01Y727183D02*
X272517Y727600D01*
X272933Y727850D01*
X273600Y727933D01*
X274183Y727850D01*
X274767Y727433D01*
X275017Y726850D01*
X275100Y726267D01*
X275017Y725683D01*
X274767Y725100D01*
X274267Y724767D01*
X273600Y724600D01*
X273017Y724683D01*
X272433Y724933D01*
X272100Y725267D01*
G01X278033Y724600D02*
Y727933D01*
G01Y727267D02*
X278450Y727600D01*
X278867Y727850D01*
X279450Y727933D01*
X279867Y727850D01*
X280367Y727600D01*
G01X283550Y726850D02*
X286217D01*
X285967Y727433D01*
X285550Y727767D01*
X284967Y727933D01*
X284383Y727850D01*
X283883Y727600D01*
X283550Y727017D01*
X283383Y726517D01*
Y726017D01*
X283550Y725517D01*
X283967Y725017D01*
X284467Y724683D01*
X285050Y724600D01*
X285633Y724767D01*
X286217Y725267D01*
G01X289233Y723350D02*
X289817Y723017D01*
X290483Y722933D01*
X291067Y723017D01*
X291567Y723433D01*
X291900Y724017D01*
Y727933D01*
G01Y727267D02*
X291567Y727600D01*
X291067Y727850D01*
X290483Y727933D01*
X289817Y727767D01*
X289400Y727433D01*
X289067Y726850D01*
X288900Y726267D01*
X288983Y725767D01*
X289317Y725183D01*
X289817Y724767D01*
X290483Y724600D01*
X290983Y724683D01*
X291567Y725017D01*
X291900Y725350D01*
G01X294583Y724600D02*
Y727933D01*
G01Y727100D02*
X294917Y727517D01*
X295417Y727850D01*
X296083Y727933D01*
X296667Y727850D01*
X297167Y727517D01*
X297417Y726933D01*
Y724600D01*
G01X303100D02*
Y727933D01*
G01Y727350D02*
X302767Y727683D01*
X302267Y727850D01*
X301683Y727933D01*
X301100Y727767D01*
X300600Y727433D01*
X300267Y726933D01*
X300100Y726267D01*
X300267Y725600D01*
X300600Y725100D01*
X301100Y724767D01*
X301683Y724600D01*
X302267Y724683D01*
X302767Y724933D01*
X303100Y725267D01*
G01X307200Y729600D02*
Y724600D01*
G01X306033Y727933D02*
X308367D01*
G01X311550Y726850D02*
X314217D01*
X313967Y727433D01*
X313550Y727767D01*
X312967Y727933D01*
X312383Y727850D01*
X311883Y727600D01*
X311550Y727017D01*
X311383Y726517D01*
Y726017D01*
X311550Y725517D01*
X311967Y725017D01*
X312467Y724683D01*
X313050Y724600D01*
X313633Y724767D01*
X314217Y725267D01*
G01X319900Y729600D02*
Y724600D01*
G01Y725350D02*
X319567Y724933D01*
X319067Y724683D01*
X318483Y724600D01*
X317817Y724767D01*
X317317Y725183D01*
X316983Y725683D01*
X316900Y726267D01*
X316983Y726850D01*
X317317Y727350D01*
X317817Y727767D01*
X318483Y727933D01*
X319067Y727850D01*
X319483Y727683D01*
X319900Y727350D01*
G01X328017Y724600D02*
Y729600D01*
X331183D01*
G01X330017Y727183D02*
X328017D01*
G01X336700Y724600D02*
Y727933D01*
G01Y727350D02*
X336367Y727683D01*
X335867Y727850D01*
X335283Y727933D01*
X334700Y727767D01*
X334200Y727433D01*
X333867Y726933D01*
X333700Y726267D01*
X333867Y725600D01*
X334200Y725100D01*
X334700Y724767D01*
X335283Y724600D01*
X335867Y724683D01*
X336367Y724933D01*
X336700Y725267D01*
G01X339300Y724600D02*
Y729600D01*
G01Y727100D02*
X339717Y727600D01*
X340217Y727850D01*
X340717Y727933D01*
X341467Y727767D01*
X341967Y727433D01*
X342300Y726850D01*
Y726183D01*
X342133Y725517D01*
X341800Y725017D01*
X341217Y724683D01*
X340717Y724600D01*
X340217Y724683D01*
X339717Y724933D01*
X339300Y725350D01*
G01X345233Y724600D02*
Y727933D01*
G01Y727267D02*
X345650Y727600D01*
X346067Y727850D01*
X346650Y727933D01*
X347067Y727850D01*
X347567Y727600D01*
G01X352000Y727933D02*
Y724600D01*
G01Y729267D02*
X351833Y729350D01*
Y729517D01*
X352000Y729600D01*
X352167Y729517D01*
Y729350D01*
X352000Y729267D01*
G01X358933Y727517D02*
X358350Y727850D01*
X357850Y727933D01*
X357183Y727767D01*
X356683Y727433D01*
X356350Y726850D01*
X356267Y726267D01*
X356350Y725683D01*
X356683Y725183D01*
X357183Y724767D01*
X357850Y724600D01*
X358433Y724767D01*
X358933Y725100D01*
G01X362783Y722933D02*
X361950Y723767D01*
X361533Y724600D01*
Y727933D01*
X361950Y728767D01*
X362783Y729600D01*
G01X367133Y724600D02*
Y729600D01*
X369133D01*
X369800Y729350D01*
X370300Y728767D01*
X370467Y728100D01*
X370300Y727433D01*
X369883Y726933D01*
X369133Y726683D01*
X367133D01*
G01X373233Y724600D02*
Y727933D01*
G01Y727267D02*
X373650Y727600D01*
X374067Y727850D01*
X374650Y727933D01*
X375067Y727850D01*
X375567Y727600D01*
G01X378750Y726850D02*
X381417D01*
X381167Y727433D01*
X380750Y727767D01*
X380167Y727933D01*
X379583Y727850D01*
X379083Y727600D01*
X378750Y727017D01*
X378583Y726517D01*
Y726017D01*
X378750Y725517D01*
X379167Y725017D01*
X379667Y724683D01*
X380250Y724600D01*
X380833Y724767D01*
X381417Y725267D01*
G01X384100Y722933D02*
Y727933D01*
G01Y727183D02*
X384517Y727600D01*
X384933Y727850D01*
X385600Y727933D01*
X386183Y727850D01*
X386767Y727433D01*
X387017Y726850D01*
X387100Y726267D01*
X387017Y725683D01*
X386767Y725100D01*
X386267Y724767D01*
X385600Y724600D01*
X385017Y724683D01*
X384433Y724933D01*
X384100Y725267D01*
G01X390033Y724600D02*
Y727933D01*
G01Y727267D02*
X390450Y727600D01*
X390867Y727850D01*
X391450Y727933D01*
X391867Y727850D01*
X392367Y727600D01*
G01X395550Y726850D02*
X398217D01*
X397967Y727433D01*
X397550Y727767D01*
X396967Y727933D01*
X396383Y727850D01*
X395883Y727600D01*
X395550Y727017D01*
X395383Y726517D01*
Y726017D01*
X395550Y725517D01*
X395967Y725017D01*
X396467Y724683D01*
X397050Y724600D01*
X397633Y724767D01*
X398217Y725267D01*
G01X401233Y723350D02*
X401817Y723017D01*
X402483Y722933D01*
X403067Y723017D01*
X403567Y723433D01*
X403900Y724017D01*
Y727933D01*
G01Y727267D02*
X403567Y727600D01*
X403067Y727850D01*
X402483Y727933D01*
X401817Y727767D01*
X401400Y727433D01*
X401067Y726850D01*
X400900Y726267D01*
X400983Y725767D01*
X401317Y725183D01*
X401817Y724767D01*
X402483Y724600D01*
X402983Y724683D01*
X403567Y725017D01*
X403900Y725350D01*
G01X408417Y722933D02*
X409250Y723767D01*
X409667Y724600D01*
Y727933D01*
X409250Y728767D01*
X408417Y729600D01*
G01X418700Y724600D02*
Y728850D01*
X418867Y729267D01*
X419200Y729517D01*
X419700Y729600D01*
X420200Y729433D01*
X420450Y729017D01*
G01X419450Y727600D02*
X417783D01*
G01X424800Y724600D02*
X424300Y724683D01*
X423800Y725017D01*
X423467Y725600D01*
X423300Y726267D01*
X423467Y726933D01*
X423800Y727517D01*
X424300Y727850D01*
X424800Y727933D01*
X425300Y727850D01*
X425800Y727517D01*
X426133Y726933D01*
X426217Y726267D01*
X426133Y725600D01*
X425800Y725017D01*
X425300Y724683D01*
X424800Y724600D01*
G01X429233D02*
Y727933D01*
G01Y727267D02*
X429650Y727600D01*
X430067Y727850D01*
X430650Y727933D01*
X431067Y727850D01*
X431567Y727600D01*
G01X439433Y724600D02*
Y729600D01*
X441600Y725433D01*
X443767Y729600D01*
Y724600D01*
G01X445783Y727933D02*
Y725600D01*
X446117Y725017D01*
X446617Y724683D01*
X447200Y724600D01*
X447783Y724683D01*
X448283Y725017D01*
X448617Y725600D01*
G01Y724600D02*
Y727933D01*
G01X452800Y724600D02*
Y729600D01*
G01X458400D02*
Y724600D01*
G01X457233Y727933D02*
X459567D01*
G01X464000D02*
Y724600D01*
G01Y729267D02*
X463833Y729350D01*
Y729517D01*
X464000Y729600D01*
X464167Y729517D01*
Y729350D01*
X464000Y729267D01*
G01X469600Y724600D02*
Y729600D01*
G01X476700Y724600D02*
Y727933D01*
G01Y727350D02*
X476367Y727683D01*
X475867Y727850D01*
X475283Y727933D01*
X474700Y727767D01*
X474200Y727433D01*
X473867Y726933D01*
X473700Y726267D01*
X473867Y725600D01*
X474200Y725100D01*
X474700Y724767D01*
X475283Y724600D01*
X475867Y724683D01*
X476367Y724933D01*
X476700Y725267D01*
G01X479050Y723100D02*
X479550Y722933D01*
X480217Y723100D01*
X480633Y723433D01*
X480967Y723850D01*
X481467Y725183D01*
X482550Y727933D01*
G01X479883D02*
X481467Y725183D01*
G01X485150Y726850D02*
X487817D01*
X487567Y727433D01*
X487150Y727767D01*
X486567Y727933D01*
X485983Y727850D01*
X485483Y727600D01*
X485150Y727017D01*
X484983Y726517D01*
Y726017D01*
X485150Y725517D01*
X485567Y725017D01*
X486067Y724683D01*
X486650Y724600D01*
X487233Y724767D01*
X487817Y725267D01*
G01X490833Y724600D02*
Y727933D01*
G01Y727267D02*
X491250Y727600D01*
X491667Y727850D01*
X492250Y727933D01*
X492667Y727850D01*
X493167Y727600D01*
G01X501533Y724600D02*
Y729600D01*
X503533D01*
X504200Y729350D01*
X504700Y728767D01*
X504867Y728100D01*
X504700Y727433D01*
X504283Y726933D01*
X503533Y726683D01*
X501533D01*
G01X507633Y724600D02*
Y727933D01*
G01Y727267D02*
X508050Y727600D01*
X508467Y727850D01*
X509050Y727933D01*
X509467Y727850D01*
X509967Y727600D01*
G01X514400Y727933D02*
Y724600D01*
G01Y729267D02*
X514233Y729350D01*
Y729517D01*
X514400Y729600D01*
X514567Y729517D01*
Y729350D01*
X514400Y729267D01*
G01X518583Y724600D02*
Y727933D01*
G01Y727100D02*
X518917Y727517D01*
X519417Y727850D01*
X520083Y727933D01*
X520667Y727850D01*
X521167Y727517D01*
X521417Y726933D01*
Y724600D01*
G01X525600Y729600D02*
Y724600D01*
G01X524433Y727933D02*
X526767D01*
G01X529950Y726850D02*
X532617D01*
X532367Y727433D01*
X531950Y727767D01*
X531367Y727933D01*
X530783Y727850D01*
X530283Y727600D01*
X529950Y727017D01*
X529783Y726517D01*
Y726017D01*
X529950Y725517D01*
X530367Y725017D01*
X530867Y724683D01*
X531450Y724600D01*
X532033Y724767D01*
X532617Y725267D01*
G01X538300Y729600D02*
Y724600D01*
G01Y725350D02*
X537967Y724933D01*
X537467Y724683D01*
X536883Y724600D01*
X536217Y724767D01*
X535717Y725183D01*
X535383Y725683D01*
X535300Y726267D01*
X535383Y726850D01*
X535717Y727350D01*
X536217Y727767D01*
X536883Y727933D01*
X537467Y727850D01*
X537883Y727683D01*
X538300Y727350D01*
G01X548667Y727267D02*
X549000Y727517D01*
X549250Y727933D01*
X549417Y728517D01*
X549250Y729017D01*
X548917Y729350D01*
X548333Y729600D01*
X546083D01*
Y724600D01*
X548833D01*
X549417Y724933D01*
X549750Y725433D01*
X549917Y726017D01*
X549750Y726600D01*
X549250Y727100D01*
X548667Y727267D01*
X546083D01*
G01X553600Y724600D02*
X553100Y724683D01*
X552600Y725017D01*
X552267Y725600D01*
X552100Y726267D01*
X552267Y726933D01*
X552600Y727517D01*
X553100Y727850D01*
X553600Y727933D01*
X554100Y727850D01*
X554600Y727517D01*
X554933Y726933D01*
X555017Y726267D01*
X554933Y725600D01*
X554600Y725017D01*
X554100Y724683D01*
X553600Y724600D01*
G01X560700D02*
Y727933D01*
G01Y727350D02*
X560367Y727683D01*
X559867Y727850D01*
X559283Y727933D01*
X558700Y727767D01*
X558200Y727433D01*
X557867Y726933D01*
X557700Y726267D01*
X557867Y725600D01*
X558200Y725100D01*
X558700Y724767D01*
X559283Y724600D01*
X559867Y724683D01*
X560367Y724933D01*
X560700Y725267D01*
G01X563633Y724600D02*
Y727933D01*
G01Y727267D02*
X564050Y727600D01*
X564467Y727850D01*
X565050Y727933D01*
X565467Y727850D01*
X565967Y727600D01*
G01X571900Y729600D02*
Y724600D01*
G01Y725350D02*
X571567Y724933D01*
X571067Y724683D01*
X570483Y724600D01*
X569817Y724767D01*
X569317Y725183D01*
X568983Y725683D01*
X568900Y726267D01*
X568983Y726850D01*
X569317Y727350D01*
X569817Y727767D01*
X570483Y727933D01*
X571067Y727850D01*
X571483Y727683D01*
X571900Y727350D01*
G01X574750Y725183D02*
X575167Y724850D01*
X575750Y724600D01*
X576250D01*
X576750Y724767D01*
X577083Y725017D01*
X577250Y725350D01*
X577167Y725850D01*
X576833Y726100D01*
X575333Y726600D01*
X575000Y727183D01*
X575167Y727600D01*
X575500Y727850D01*
X576000Y727933D01*
X576500Y727850D01*
X577000Y727600D01*
G01X71000Y738600D02*
X73000D01*
G01X72000D02*
Y733600D01*
G01X71000D02*
X73000D01*
G01X75933D02*
Y738600D01*
X77933D01*
X78600Y738350D01*
X79100Y737767D01*
X79267Y737100D01*
X79100Y736433D01*
X78683Y735933D01*
X77933Y735683D01*
X75933D01*
G01X85033Y738183D02*
X84533Y738433D01*
X83950Y738600D01*
X83283D01*
X82533Y738350D01*
X81950Y737933D01*
X81533Y737433D01*
X81200Y736600D01*
X81117Y735850D01*
X81283Y735100D01*
X81533Y734600D01*
X82033Y734100D01*
X82617Y733767D01*
X83200Y733600D01*
X83783D01*
X84367Y733767D01*
X84867Y734017D01*
X85283Y734350D01*
G01X87717Y735267D02*
X89883D01*
G01X92233Y733600D02*
Y738600D01*
X94400Y734433D01*
X96567Y738600D01*
Y733600D01*
G01X98417D02*
Y738600D01*
X101583D01*
G01X100417Y736183D02*
X98417D01*
G01X104517Y735267D02*
X106683D01*
G01X111200Y733600D02*
Y738600D01*
X110200Y737600D01*
G01Y733600D02*
X112200D01*
G01X114967Y734350D02*
X115467Y733933D01*
X116050Y733683D01*
X116800Y733600D01*
X117550Y733767D01*
X118133Y734100D01*
X118550Y734683D01*
X118633Y735350D01*
X118467Y736017D01*
X118050Y736433D01*
X117467Y736767D01*
X116883Y736850D01*
X116300Y736767D01*
X115550Y736433D01*
X115800Y738600D01*
X118050D01*
G01X122400D02*
X121733Y738433D01*
X121233Y738017D01*
X120900Y737517D01*
X120650Y736850D01*
X120567Y736100D01*
X120650Y735350D01*
X120900Y734683D01*
X121233Y734183D01*
X121733Y733767D01*
X122400Y733600D01*
X123067Y733767D01*
X123567Y734183D01*
X123900Y734683D01*
X124150Y735350D01*
X124233Y736100D01*
X124150Y736850D01*
X123900Y737517D01*
X123567Y738017D01*
X123067Y738433D01*
X122400Y738600D01*
G01X131433Y733600D02*
Y738600D01*
X133600Y734433D01*
X135767Y738600D01*
Y733600D01*
G01X137950Y735850D02*
X140617D01*
X140367Y736433D01*
X139950Y736767D01*
X139367Y736933D01*
X138783Y736850D01*
X138283Y736600D01*
X137950Y736017D01*
X137783Y735517D01*
Y735017D01*
X137950Y734517D01*
X138367Y734017D01*
X138867Y733683D01*
X139450Y733600D01*
X140033Y733767D01*
X140617Y734267D01*
G01X144800Y738600D02*
Y733600D01*
G01X143633Y736933D02*
X145967D01*
G01X151900Y733600D02*
Y736933D01*
G01Y736350D02*
X151567Y736683D01*
X151067Y736850D01*
X150483Y736933D01*
X149900Y736767D01*
X149400Y736433D01*
X149067Y735933D01*
X148900Y735267D01*
X149067Y734600D01*
X149400Y734100D01*
X149900Y733767D01*
X150483Y733600D01*
X151067Y733683D01*
X151567Y733933D01*
X151900Y734267D01*
G01X156000Y733600D02*
Y738600D01*
G01X165617Y733600D02*
Y738600D01*
X168783D01*
G01X167617Y736183D02*
X165617D01*
G01X172800Y733600D02*
X172300Y733683D01*
X171800Y734017D01*
X171467Y734600D01*
X171300Y735267D01*
X171467Y735933D01*
X171800Y736517D01*
X172300Y736850D01*
X172800Y736933D01*
X173300Y736850D01*
X173800Y736517D01*
X174133Y735933D01*
X174217Y735267D01*
X174133Y734600D01*
X173800Y734017D01*
X173300Y733683D01*
X172800Y733600D01*
G01X178400Y736933D02*
Y733600D01*
G01Y738267D02*
X178233Y738350D01*
Y738517D01*
X178400Y738600D01*
X178567Y738517D01*
Y738350D01*
X178400Y738267D01*
G01X184000Y733600D02*
Y738600D01*
G01X194700Y733600D02*
Y737850D01*
X194867Y738267D01*
X195200Y738517D01*
X195700Y738600D01*
X196200Y738433D01*
X196450Y738017D01*
G01X195450Y736600D02*
X193783D01*
G01X200800Y733600D02*
X200300Y733683D01*
X199800Y734017D01*
X199467Y734600D01*
X199300Y735267D01*
X199467Y735933D01*
X199800Y736517D01*
X200300Y736850D01*
X200800Y736933D01*
X201300Y736850D01*
X201800Y736517D01*
X202133Y735933D01*
X202217Y735267D01*
X202133Y734600D01*
X201800Y734017D01*
X201300Y733683D01*
X200800Y733600D01*
G01X205233D02*
Y736933D01*
G01Y736267D02*
X205650Y736600D01*
X206067Y736850D01*
X206650Y736933D01*
X207067Y736850D01*
X207567Y736600D01*
G01X215933Y733600D02*
Y738600D01*
X217933D01*
X218600Y738350D01*
X219100Y737767D01*
X219267Y737100D01*
X219100Y736433D01*
X218683Y735933D01*
X217933Y735683D01*
X215933D01*
G01X222033Y733600D02*
Y736933D01*
G01Y736267D02*
X222450Y736600D01*
X222867Y736850D01*
X223450Y736933D01*
X223867Y736850D01*
X224367Y736600D01*
G01X228800Y736933D02*
Y733600D01*
G01Y738267D02*
X228633Y738350D01*
Y738517D01*
X228800Y738600D01*
X228967Y738517D01*
Y738350D01*
X228800Y738267D01*
G01X232983Y733600D02*
Y736933D01*
G01Y736100D02*
X233317Y736517D01*
X233817Y736850D01*
X234483Y736933D01*
X235067Y736850D01*
X235567Y736517D01*
X235817Y735933D01*
Y733600D01*
G01X240000Y738600D02*
Y733600D01*
G01X238833Y736933D02*
X241167D01*
G01X244350Y735850D02*
X247017D01*
X246767Y736433D01*
X246350Y736767D01*
X245767Y736933D01*
X245183Y736850D01*
X244683Y736600D01*
X244350Y736017D01*
X244183Y735517D01*
Y735017D01*
X244350Y734517D01*
X244767Y734017D01*
X245267Y733683D01*
X245850Y733600D01*
X246433Y733767D01*
X247017Y734267D01*
G01X252700Y738600D02*
Y733600D01*
G01Y734350D02*
X252367Y733933D01*
X251867Y733683D01*
X251283Y733600D01*
X250617Y733767D01*
X250117Y734183D01*
X249783Y734683D01*
X249700Y735267D01*
X249783Y735850D01*
X250117Y736350D01*
X250617Y736767D01*
X251283Y736933D01*
X251867Y736850D01*
X252283Y736683D01*
X252700Y736350D01*
G01X259900Y738600D02*
X261067Y733600D01*
X262400Y738600D01*
X263733Y733600D01*
X264900Y738600D01*
G01X268000Y736933D02*
Y733600D01*
G01Y738267D02*
X267833Y738350D01*
Y738517D01*
X268000Y738600D01*
X268167Y738517D01*
Y738350D01*
X268000Y738267D01*
G01X272433Y733600D02*
Y736933D01*
G01Y736267D02*
X272850Y736600D01*
X273267Y736850D01*
X273850Y736933D01*
X274267Y736850D01*
X274767Y736600D01*
G01X279200Y736933D02*
Y733600D01*
G01Y738267D02*
X279033Y738350D01*
Y738517D01*
X279200Y738600D01*
X279367Y738517D01*
Y738350D01*
X279200Y738267D01*
G01X283383Y733600D02*
Y736933D01*
G01Y736100D02*
X283717Y736517D01*
X284217Y736850D01*
X284883Y736933D01*
X285467Y736850D01*
X285967Y736517D01*
X286217Y735933D01*
Y733600D01*
G01X289233Y732350D02*
X289817Y732017D01*
X290483Y731933D01*
X291067Y732017D01*
X291567Y732433D01*
X291900Y733017D01*
Y736933D01*
G01Y736267D02*
X291567Y736600D01*
X291067Y736850D01*
X290483Y736933D01*
X289817Y736767D01*
X289400Y736433D01*
X289067Y735850D01*
X288900Y735267D01*
X288983Y734767D01*
X289317Y734183D01*
X289817Y733767D01*
X290483Y733600D01*
X290983Y733683D01*
X291567Y734017D01*
X291900Y734350D01*
G01X299517Y733600D02*
X301600Y738600D01*
X303683Y733600D01*
G01X302933Y735350D02*
X300267D01*
G01X305700Y731933D02*
Y736933D01*
G01Y736183D02*
X306117Y736600D01*
X306533Y736850D01*
X307200Y736933D01*
X307783Y736850D01*
X308367Y736433D01*
X308617Y735850D01*
X308700Y735267D01*
X308617Y734683D01*
X308367Y734100D01*
X307867Y733767D01*
X307200Y733600D01*
X306617Y733683D01*
X306033Y733933D01*
X305700Y734267D01*
G01X311300Y731933D02*
Y736933D01*
G01Y736183D02*
X311717Y736600D01*
X312133Y736850D01*
X312800Y736933D01*
X313383Y736850D01*
X313967Y736433D01*
X314217Y735850D01*
X314300Y735267D01*
X314217Y734683D01*
X313967Y734100D01*
X313467Y733767D01*
X312800Y733600D01*
X312217Y733683D01*
X311633Y733933D01*
X311300Y734267D01*
G01X318400Y733600D02*
Y738600D01*
G01X324000Y736933D02*
Y733600D01*
G01Y738267D02*
X323833Y738350D01*
Y738517D01*
X324000Y738600D01*
X324167Y738517D01*
Y738350D01*
X324000Y738267D01*
G01X330933Y736517D02*
X330350Y736850D01*
X329850Y736933D01*
X329183Y736767D01*
X328683Y736433D01*
X328350Y735850D01*
X328267Y735267D01*
X328350Y734683D01*
X328683Y734183D01*
X329183Y733767D01*
X329850Y733600D01*
X330433Y733767D01*
X330933Y734100D01*
G01X336700Y733600D02*
Y736933D01*
G01Y736350D02*
X336367Y736683D01*
X335867Y736850D01*
X335283Y736933D01*
X334700Y736767D01*
X334200Y736433D01*
X333867Y735933D01*
X333700Y735267D01*
X333867Y734600D01*
X334200Y734100D01*
X334700Y733767D01*
X335283Y733600D01*
X335867Y733683D01*
X336367Y733933D01*
X336700Y734267D01*
G01X340800Y738600D02*
Y733600D01*
G01X339633Y736933D02*
X341967D01*
G01X346400D02*
Y733600D01*
G01Y738267D02*
X346233Y738350D01*
Y738517D01*
X346400Y738600D01*
X346567Y738517D01*
Y738350D01*
X346400Y738267D01*
G01X352000Y733600D02*
X351500Y733683D01*
X351000Y734017D01*
X350667Y734600D01*
X350500Y735267D01*
X350667Y735933D01*
X351000Y736517D01*
X351500Y736850D01*
X352000Y736933D01*
X352500Y736850D01*
X353000Y736517D01*
X353333Y735933D01*
X353417Y735267D01*
X353333Y734600D01*
X353000Y734017D01*
X352500Y733683D01*
X352000Y733600D01*
G01X356183D02*
Y736933D01*
G01Y736100D02*
X356517Y736517D01*
X357017Y736850D01*
X357683Y736933D01*
X358267Y736850D01*
X358767Y736517D01*
X359017Y735933D01*
Y733600D01*
G01X361950Y734183D02*
X362367Y733850D01*
X362950Y733600D01*
X363450D01*
X363950Y733767D01*
X364283Y734017D01*
X364450Y734350D01*
X364367Y734850D01*
X364033Y735100D01*
X362533Y735600D01*
X362200Y736183D01*
X362367Y736600D01*
X362700Y736850D01*
X363200Y736933D01*
X363700Y736850D01*
X364200Y736600D01*
G01X57000Y802500D02*
X59000D01*
G01X58000D02*
Y797500D01*
G01X57000D02*
X59000D01*
G01X63100D02*
Y801750D01*
X63267Y802167D01*
X63600Y802417D01*
X64100Y802500D01*
X64600Y802333D01*
X64850Y801917D01*
G01X63850Y800500D02*
X62183D01*
G01X74800Y802500D02*
Y797500D01*
G01X73633Y800833D02*
X75967D01*
G01X78983Y797500D02*
Y802500D01*
G01Y800083D02*
X79400Y800500D01*
X79817Y800750D01*
X80483Y800833D01*
X80983Y800750D01*
X81567Y800417D01*
X81817Y799917D01*
Y797500D01*
G01X84750Y799750D02*
X87417D01*
X87167Y800333D01*
X86750Y800667D01*
X86167Y800833D01*
X85583Y800750D01*
X85083Y800500D01*
X84750Y799917D01*
X84583Y799417D01*
Y798917D01*
X84750Y798417D01*
X85167Y797917D01*
X85667Y797583D01*
X86250Y797500D01*
X86833Y797667D01*
X87417Y798167D01*
G01X98533Y800417D02*
X97950Y800750D01*
X97450Y800833D01*
X96783Y800667D01*
X96283Y800333D01*
X95950Y799750D01*
X95867Y799167D01*
X95950Y798583D01*
X96283Y798083D01*
X96783Y797667D01*
X97450Y797500D01*
X98033Y797667D01*
X98533Y798000D01*
G01X101633Y797500D02*
Y800833D01*
G01Y800167D02*
X102050Y800500D01*
X102467Y800750D01*
X103050Y800833D01*
X103467Y800750D01*
X103967Y800500D01*
G01X108400Y800833D02*
Y797500D01*
G01Y802167D02*
X108233Y802250D01*
Y802417D01*
X108400Y802500D01*
X108567Y802417D01*
Y802250D01*
X108400Y802167D01*
G01X114000Y802500D02*
Y797500D01*
G01X112833Y800833D02*
X115167D01*
G01X118350Y799750D02*
X121017D01*
X120767Y800333D01*
X120350Y800667D01*
X119767Y800833D01*
X119183Y800750D01*
X118683Y800500D01*
X118350Y799917D01*
X118183Y799417D01*
Y798917D01*
X118350Y798417D01*
X118767Y797917D01*
X119267Y797583D01*
X119850Y797500D01*
X120433Y797667D01*
X121017Y798167D01*
G01X124033Y797500D02*
Y800833D01*
G01Y800167D02*
X124450Y800500D01*
X124867Y800750D01*
X125450Y800833D01*
X125867Y800750D01*
X126367Y800500D01*
G01X130800Y800833D02*
Y797500D01*
G01Y802167D02*
X130633Y802250D01*
Y802417D01*
X130800Y802500D01*
X130967Y802417D01*
Y802250D01*
X130800Y802167D01*
G01X137900Y797500D02*
Y800833D01*
G01Y800250D02*
X137567Y800583D01*
X137067Y800750D01*
X136483Y800833D01*
X135900Y800667D01*
X135400Y800333D01*
X135067Y799833D01*
X134900Y799167D01*
X135067Y798500D01*
X135400Y798000D01*
X135900Y797667D01*
X136483Y797500D01*
X137067Y797583D01*
X137567Y797833D01*
X137900Y798167D01*
G01X147600Y800833D02*
Y797500D01*
G01Y802167D02*
X147433Y802250D01*
Y802417D01*
X147600Y802500D01*
X147767Y802417D01*
Y802250D01*
X147600Y802167D01*
G01X151950Y798083D02*
X152367Y797750D01*
X152950Y797500D01*
X153450D01*
X153950Y797667D01*
X154283Y797917D01*
X154450Y798250D01*
X154367Y798750D01*
X154033Y799000D01*
X152533Y799500D01*
X152200Y800083D01*
X152367Y800500D01*
X152700Y800750D01*
X153200Y800833D01*
X153700Y800750D01*
X154200Y800500D01*
G01X162983Y797500D02*
Y800833D01*
G01Y800000D02*
X163317Y800417D01*
X163817Y800750D01*
X164483Y800833D01*
X165067Y800750D01*
X165567Y800417D01*
X165817Y799833D01*
Y797500D01*
G01X170000D02*
X169500Y797583D01*
X169000Y797917D01*
X168667Y798500D01*
X168500Y799167D01*
X168667Y799833D01*
X169000Y800417D01*
X169500Y800750D01*
X170000Y800833D01*
X170500Y800750D01*
X171000Y800417D01*
X171333Y799833D01*
X171417Y799167D01*
X171333Y798500D01*
X171000Y797917D01*
X170500Y797583D01*
X170000Y797500D01*
G01X175600Y802500D02*
Y797500D01*
G01X174433Y800833D02*
X176767D01*
G01X185550Y798083D02*
X185967Y797750D01*
X186550Y797500D01*
X187050D01*
X187550Y797667D01*
X187883Y797917D01*
X188050Y798250D01*
X187967Y798750D01*
X187633Y799000D01*
X186133Y799500D01*
X185800Y800083D01*
X185967Y800500D01*
X186300Y800750D01*
X186800Y800833D01*
X187300Y800750D01*
X187800Y800500D01*
G01X190900Y795833D02*
Y800833D01*
G01Y800083D02*
X191317Y800500D01*
X191733Y800750D01*
X192400Y800833D01*
X192983Y800750D01*
X193567Y800333D01*
X193817Y799750D01*
X193900Y799167D01*
X193817Y798583D01*
X193567Y798000D01*
X193067Y797667D01*
X192400Y797500D01*
X191817Y797583D01*
X191233Y797833D01*
X190900Y798167D01*
G01X196750Y799750D02*
X199417D01*
X199167Y800333D01*
X198750Y800667D01*
X198167Y800833D01*
X197583Y800750D01*
X197083Y800500D01*
X196750Y799917D01*
X196583Y799417D01*
Y798917D01*
X196750Y798417D01*
X197167Y797917D01*
X197667Y797583D01*
X198250Y797500D01*
X198833Y797667D01*
X199417Y798167D01*
G01X204933Y800417D02*
X204350Y800750D01*
X203850Y800833D01*
X203183Y800667D01*
X202683Y800333D01*
X202350Y799750D01*
X202267Y799167D01*
X202350Y798583D01*
X202683Y798083D01*
X203183Y797667D01*
X203850Y797500D01*
X204433Y797667D01*
X204933Y798000D01*
G01X209200Y800833D02*
Y797500D01*
G01Y802167D02*
X209033Y802250D01*
Y802417D01*
X209200Y802500D01*
X209367Y802417D01*
Y802250D01*
X209200Y802167D01*
G01X214300Y797500D02*
Y801750D01*
X214467Y802167D01*
X214800Y802417D01*
X215300Y802500D01*
X215800Y802333D01*
X216050Y801917D01*
G01X215050Y800500D02*
X213383D01*
G01X220400Y800833D02*
Y797500D01*
G01Y802167D02*
X220233Y802250D01*
Y802417D01*
X220400Y802500D01*
X220567Y802417D01*
Y802250D01*
X220400Y802167D01*
G01X224750Y799750D02*
X227417D01*
X227167Y800333D01*
X226750Y800667D01*
X226167Y800833D01*
X225583Y800750D01*
X225083Y800500D01*
X224750Y799917D01*
X224583Y799417D01*
Y798917D01*
X224750Y798417D01*
X225167Y797917D01*
X225667Y797583D01*
X226250Y797500D01*
X226833Y797667D01*
X227417Y798167D01*
G01X233100Y802500D02*
Y797500D01*
G01Y798250D02*
X232767Y797833D01*
X232267Y797583D01*
X231683Y797500D01*
X231017Y797667D01*
X230517Y798083D01*
X230183Y798583D01*
X230100Y799167D01*
X230183Y799750D01*
X230517Y800250D01*
X231017Y800667D01*
X231683Y800833D01*
X232267Y800750D01*
X232683Y800583D01*
X233100Y800250D01*
G01X242800Y800833D02*
Y797500D01*
G01Y802167D02*
X242633Y802250D01*
Y802417D01*
X242800Y802500D01*
X242967Y802417D01*
Y802250D01*
X242800Y802167D01*
G01X246983Y797500D02*
Y800833D01*
G01Y800000D02*
X247317Y800417D01*
X247817Y800750D01*
X248483Y800833D01*
X249067Y800750D01*
X249567Y800417D01*
X249817Y799833D01*
Y797500D01*
G01X259600Y802500D02*
Y797500D01*
G01X258433Y800833D02*
X260767D01*
G01X263783Y797500D02*
Y802500D01*
G01Y800083D02*
X264200Y800500D01*
X264617Y800750D01*
X265283Y800833D01*
X265783Y800750D01*
X266367Y800417D01*
X266617Y799917D01*
Y797500D01*
G01X269550Y799750D02*
X272217D01*
X271967Y800333D01*
X271550Y800667D01*
X270967Y800833D01*
X270383Y800750D01*
X269883Y800500D01*
X269550Y799917D01*
X269383Y799417D01*
Y798917D01*
X269550Y798417D01*
X269967Y797917D01*
X270467Y797583D01*
X271050Y797500D01*
X271633Y797667D01*
X272217Y798167D01*
G01X282000Y802500D02*
Y797500D01*
G01X280833Y800833D02*
X283167D01*
G01X289100Y797500D02*
Y800833D01*
G01Y800250D02*
X288767Y800583D01*
X288267Y800750D01*
X287683Y800833D01*
X287100Y800667D01*
X286600Y800333D01*
X286267Y799833D01*
X286100Y799167D01*
X286267Y798500D01*
X286600Y798000D01*
X287100Y797667D01*
X287683Y797500D01*
X288267Y797583D01*
X288767Y797833D01*
X289100Y798167D01*
G01X291700Y797500D02*
Y802500D01*
G01Y800000D02*
X292117Y800500D01*
X292617Y800750D01*
X293117Y800833D01*
X293867Y800667D01*
X294367Y800333D01*
X294700Y799750D01*
Y799083D01*
X294533Y798417D01*
X294200Y797917D01*
X293617Y797583D01*
X293117Y797500D01*
X292617Y797583D01*
X292117Y797833D01*
X291700Y798250D01*
G01X298800Y797500D02*
Y802500D01*
G01X303150Y799750D02*
X305817D01*
X305567Y800333D01*
X305150Y800667D01*
X304567Y800833D01*
X303983Y800750D01*
X303483Y800500D01*
X303150Y799917D01*
X302983Y799417D01*
Y798917D01*
X303150Y798417D01*
X303567Y797917D01*
X304067Y797583D01*
X304650Y797500D01*
X305233Y797667D01*
X305817Y798167D01*
G01X310000Y797333D02*
X309833Y797417D01*
Y797583D01*
X310000Y797667D01*
X310167Y797583D01*
Y797417D01*
X310000Y797333D01*
G01Y799583D02*
X309833Y799667D01*
Y799833D01*
X310000Y799917D01*
X310167Y799833D01*
Y799667D01*
X310000Y799583D01*
G01X67000Y743433D02*
X66833Y743517D01*
Y743683D01*
X67000Y743767D01*
X67167Y743683D01*
Y743517D01*
X67000Y743433D01*
G01Y752433D02*
X66833Y752517D01*
Y752683D01*
X67000Y752767D01*
X67167Y752683D01*
Y752517D01*
X67000Y752433D01*
G01Y761433D02*
X66833Y761517D01*
Y761683D01*
X67000Y761767D01*
X67167Y761683D01*
Y761517D01*
X67000Y761433D01*
G01Y770433D02*
X66833Y770517D01*
Y770683D01*
X67000Y770767D01*
X67167Y770683D01*
Y770517D01*
X67000Y770433D01*
G01X71000Y747600D02*
X73000D01*
G01X72000D02*
Y742600D01*
G01X71000D02*
X73000D01*
G01X75933D02*
Y747600D01*
X77933D01*
X78600Y747350D01*
X79100Y746767D01*
X79267Y746100D01*
X79100Y745433D01*
X78683Y744933D01*
X77933Y744683D01*
X75933D01*
G01X85033Y747183D02*
X84533Y747433D01*
X83950Y747600D01*
X83283D01*
X82533Y747350D01*
X81950Y746933D01*
X81533Y746433D01*
X81200Y745600D01*
X81117Y744850D01*
X81283Y744100D01*
X81533Y743600D01*
X82033Y743100D01*
X82617Y742767D01*
X83200Y742600D01*
X83783D01*
X84367Y742767D01*
X84867Y743017D01*
X85283Y743350D01*
G01X87717Y744267D02*
X89883D01*
G01X95400Y742600D02*
Y747600D01*
X92317Y744017D01*
X96483D01*
G01X100000Y742600D02*
Y747600D01*
X99000Y746600D01*
G01Y742600D02*
X101000D01*
G01X105600Y747600D02*
X104933Y747433D01*
X104433Y747017D01*
X104100Y746517D01*
X103850Y745850D01*
X103767Y745100D01*
X103850Y744350D01*
X104100Y743683D01*
X104433Y743183D01*
X104933Y742767D01*
X105600Y742600D01*
X106267Y742767D01*
X106767Y743183D01*
X107100Y743683D01*
X107350Y744350D01*
X107433Y745100D01*
X107350Y745850D01*
X107100Y746517D01*
X106767Y747017D01*
X106267Y747433D01*
X105600Y747600D01*
G01X111200Y742600D02*
Y747600D01*
X110200Y746600D01*
G01Y742600D02*
X112200D01*
G01X120650Y743267D02*
X121317Y742850D01*
X122067Y742600D01*
X122733D01*
X123400Y742850D01*
X123900Y743267D01*
X124150Y743850D01*
X123983Y744433D01*
X123567Y744933D01*
X122817Y745267D01*
X121817Y745433D01*
X121233Y745767D01*
X120983Y746350D01*
X121150Y746933D01*
X121567Y747350D01*
X122150Y747600D01*
X122733D01*
X123317Y747433D01*
X123817Y747017D01*
G01X126500Y740933D02*
Y745933D01*
G01Y745183D02*
X126917Y745600D01*
X127333Y745850D01*
X128000Y745933D01*
X128583Y745850D01*
X129167Y745433D01*
X129417Y744850D01*
X129500Y744267D01*
X129417Y743683D01*
X129167Y743100D01*
X128667Y742767D01*
X128000Y742600D01*
X127417Y742683D01*
X126833Y742933D01*
X126500Y743267D01*
G01X132350Y744850D02*
X135017D01*
X134767Y745433D01*
X134350Y745767D01*
X133767Y745933D01*
X133183Y745850D01*
X132683Y745600D01*
X132350Y745017D01*
X132183Y744517D01*
Y744017D01*
X132350Y743517D01*
X132767Y743017D01*
X133267Y742683D01*
X133850Y742600D01*
X134433Y742767D01*
X135017Y743267D01*
G01X140533Y745517D02*
X139950Y745850D01*
X139450Y745933D01*
X138783Y745767D01*
X138283Y745433D01*
X137950Y744850D01*
X137867Y744267D01*
X137950Y743683D01*
X138283Y743183D01*
X138783Y742767D01*
X139450Y742600D01*
X140033Y742767D01*
X140533Y743100D01*
G01X144800Y745933D02*
Y742600D01*
G01Y747267D02*
X144633Y747350D01*
Y747517D01*
X144800Y747600D01*
X144967Y747517D01*
Y747350D01*
X144800Y747267D01*
G01X149900Y742600D02*
Y746850D01*
X150067Y747267D01*
X150400Y747517D01*
X150900Y747600D01*
X151400Y747433D01*
X151650Y747017D01*
G01X150650Y745600D02*
X148983D01*
G01X156000Y745933D02*
Y742600D01*
G01Y747267D02*
X155833Y747350D01*
Y747517D01*
X156000Y747600D01*
X156167Y747517D01*
Y747350D01*
X156000Y747267D01*
G01X162933Y745517D02*
X162350Y745850D01*
X161850Y745933D01*
X161183Y745767D01*
X160683Y745433D01*
X160350Y744850D01*
X160267Y744267D01*
X160350Y743683D01*
X160683Y743183D01*
X161183Y742767D01*
X161850Y742600D01*
X162433Y742767D01*
X162933Y743100D01*
G01X168700Y742600D02*
Y745933D01*
G01Y745350D02*
X168367Y745683D01*
X167867Y745850D01*
X167283Y745933D01*
X166700Y745767D01*
X166200Y745433D01*
X165867Y744933D01*
X165700Y744267D01*
X165867Y743600D01*
X166200Y743100D01*
X166700Y742767D01*
X167283Y742600D01*
X167867Y742683D01*
X168367Y742933D01*
X168700Y743267D01*
G01X172800Y747600D02*
Y742600D01*
G01X171633Y745933D02*
X173967D01*
G01X178400D02*
Y742600D01*
G01Y747267D02*
X178233Y747350D01*
Y747517D01*
X178400Y747600D01*
X178567Y747517D01*
Y747350D01*
X178400Y747267D01*
G01X184000Y742600D02*
X183500Y742683D01*
X183000Y743017D01*
X182667Y743600D01*
X182500Y744267D01*
X182667Y744933D01*
X183000Y745517D01*
X183500Y745850D01*
X184000Y745933D01*
X184500Y745850D01*
X185000Y745517D01*
X185333Y744933D01*
X185417Y744267D01*
X185333Y743600D01*
X185000Y743017D01*
X184500Y742683D01*
X184000Y742600D01*
G01X188183D02*
Y745933D01*
G01Y745100D02*
X188517Y745517D01*
X189017Y745850D01*
X189683Y745933D01*
X190267Y745850D01*
X190767Y745517D01*
X191017Y744933D01*
Y742600D01*
G01X200300D02*
Y746850D01*
X200467Y747267D01*
X200800Y747517D01*
X201300Y747600D01*
X201800Y747433D01*
X202050Y747017D01*
G01X201050Y745600D02*
X199383D01*
G01X206400Y742600D02*
X205900Y742683D01*
X205400Y743017D01*
X205067Y743600D01*
X204900Y744267D01*
X205067Y744933D01*
X205400Y745517D01*
X205900Y745850D01*
X206400Y745933D01*
X206900Y745850D01*
X207400Y745517D01*
X207733Y744933D01*
X207817Y744267D01*
X207733Y743600D01*
X207400Y743017D01*
X206900Y742683D01*
X206400Y742600D01*
G01X210833D02*
Y745933D01*
G01Y745267D02*
X211250Y745600D01*
X211667Y745850D01*
X212250Y745933D01*
X212667Y745850D01*
X213167Y745600D01*
G01X223867Y745267D02*
X224200Y745517D01*
X224450Y745933D01*
X224617Y746517D01*
X224450Y747017D01*
X224117Y747350D01*
X223533Y747600D01*
X221283D01*
Y742600D01*
X224033D01*
X224617Y742933D01*
X224950Y743433D01*
X225117Y744017D01*
X224950Y744600D01*
X224450Y745100D01*
X223867Y745267D01*
X221283D01*
G01X230300Y742600D02*
Y745933D01*
G01Y745350D02*
X229967Y745683D01*
X229467Y745850D01*
X228883Y745933D01*
X228300Y745767D01*
X227800Y745433D01*
X227467Y744933D01*
X227300Y744267D01*
X227467Y743600D01*
X227800Y743100D01*
X228300Y742767D01*
X228883Y742600D01*
X229467Y742683D01*
X229967Y742933D01*
X230300Y743267D01*
G01X233150Y743183D02*
X233567Y742850D01*
X234150Y742600D01*
X234650D01*
X235150Y742767D01*
X235483Y743017D01*
X235650Y743350D01*
X235567Y743850D01*
X235233Y744100D01*
X233733Y744600D01*
X233400Y745183D01*
X233567Y745600D01*
X233900Y745850D01*
X234400Y745933D01*
X234900Y745850D01*
X235400Y745600D01*
G01X238750Y744850D02*
X241417D01*
X241167Y745433D01*
X240750Y745767D01*
X240167Y745933D01*
X239583Y745850D01*
X239083Y745600D01*
X238750Y745017D01*
X238583Y744517D01*
Y744017D01*
X238750Y743517D01*
X239167Y743017D01*
X239667Y742683D01*
X240250Y742600D01*
X240833Y742767D01*
X241417Y743267D01*
G01X249033Y742600D02*
Y747600D01*
X251200Y743433D01*
X253367Y747600D01*
Y742600D01*
G01X258300D02*
Y745933D01*
G01Y745350D02*
X257967Y745683D01*
X257467Y745850D01*
X256883Y745933D01*
X256300Y745767D01*
X255800Y745433D01*
X255467Y744933D01*
X255300Y744267D01*
X255467Y743600D01*
X255800Y743100D01*
X256300Y742767D01*
X256883Y742600D01*
X257467Y742683D01*
X257967Y742933D01*
X258300Y743267D01*
G01X262400Y747600D02*
Y742600D01*
G01X261233Y745933D02*
X263567D01*
G01X266750Y744850D02*
X269417D01*
X269167Y745433D01*
X268750Y745767D01*
X268167Y745933D01*
X267583Y745850D01*
X267083Y745600D01*
X266750Y745017D01*
X266583Y744517D01*
Y744017D01*
X266750Y743517D01*
X267167Y743017D01*
X267667Y742683D01*
X268250Y742600D01*
X268833Y742767D01*
X269417Y743267D01*
G01X272433Y742600D02*
Y745933D01*
G01Y745267D02*
X272850Y745600D01*
X273267Y745850D01*
X273850Y745933D01*
X274267Y745850D01*
X274767Y745600D01*
G01X279200Y745933D02*
Y742600D01*
G01Y747267D02*
X279033Y747350D01*
Y747517D01*
X279200Y747600D01*
X279367Y747517D01*
Y747350D01*
X279200Y747267D01*
G01X286300Y742600D02*
Y745933D01*
G01Y745350D02*
X285967Y745683D01*
X285467Y745850D01*
X284883Y745933D01*
X284300Y745767D01*
X283800Y745433D01*
X283467Y744933D01*
X283300Y744267D01*
X283467Y743600D01*
X283800Y743100D01*
X284300Y742767D01*
X284883Y742600D01*
X285467Y742683D01*
X285967Y742933D01*
X286300Y743267D01*
G01X290400Y742600D02*
Y747600D01*
G01X294750Y743183D02*
X295167Y742850D01*
X295750Y742600D01*
X296250D01*
X296750Y742767D01*
X297083Y743017D01*
X297250Y743350D01*
X297167Y743850D01*
X296833Y744100D01*
X295333Y744600D01*
X295000Y745183D01*
X295167Y745600D01*
X295500Y745850D01*
X296000Y745933D01*
X296500Y745850D01*
X297000Y745600D01*
G01X306700Y742600D02*
Y746850D01*
X306867Y747267D01*
X307200Y747517D01*
X307700Y747600D01*
X308200Y747433D01*
X308450Y747017D01*
G01X307450Y745600D02*
X305783D01*
G01X312800Y742600D02*
X312300Y742683D01*
X311800Y743017D01*
X311467Y743600D01*
X311300Y744267D01*
X311467Y744933D01*
X311800Y745517D01*
X312300Y745850D01*
X312800Y745933D01*
X313300Y745850D01*
X313800Y745517D01*
X314133Y744933D01*
X314217Y744267D01*
X314133Y743600D01*
X313800Y743017D01*
X313300Y742683D01*
X312800Y742600D01*
G01X317233D02*
Y745933D01*
G01Y745267D02*
X317650Y745600D01*
X318067Y745850D01*
X318650Y745933D01*
X319067Y745850D01*
X319567Y745600D01*
G01X327933Y742600D02*
Y747600D01*
X330017D01*
X330683Y747350D01*
X331100Y747017D01*
X331267Y746350D01*
X331100Y745683D01*
X330600Y745267D01*
X330017Y745017D01*
X327933D01*
G01X330017D02*
X331267Y742600D01*
G01X335200Y745933D02*
Y742600D01*
G01Y747267D02*
X335033Y747350D01*
Y747517D01*
X335200Y747600D01*
X335367Y747517D01*
Y747350D01*
X335200Y747267D01*
G01X339633Y741350D02*
X340217Y741017D01*
X340883Y740933D01*
X341467Y741017D01*
X341967Y741433D01*
X342300Y742017D01*
Y745933D01*
G01Y745267D02*
X341967Y745600D01*
X341467Y745850D01*
X340883Y745933D01*
X340217Y745767D01*
X339800Y745433D01*
X339467Y744850D01*
X339300Y744267D01*
X339383Y743767D01*
X339717Y743183D01*
X340217Y742767D01*
X340883Y742600D01*
X341383Y742683D01*
X341967Y743017D01*
X342300Y743350D01*
G01X346400Y745933D02*
Y742600D01*
G01Y747267D02*
X346233Y747350D01*
Y747517D01*
X346400Y747600D01*
X346567Y747517D01*
Y747350D01*
X346400Y747267D01*
G01X353500Y747600D02*
Y742600D01*
G01Y743350D02*
X353167Y742933D01*
X352667Y742683D01*
X352083Y742600D01*
X351417Y742767D01*
X350917Y743183D01*
X350583Y743683D01*
X350500Y744267D01*
X350583Y744850D01*
X350917Y745350D01*
X351417Y745767D01*
X352083Y745933D01*
X352667Y745850D01*
X353083Y745683D01*
X353500Y745350D01*
G01X364700Y742600D02*
Y745933D01*
G01Y745350D02*
X364367Y745683D01*
X363867Y745850D01*
X363283Y745933D01*
X362700Y745767D01*
X362200Y745433D01*
X361867Y744933D01*
X361700Y744267D01*
X361867Y743600D01*
X362200Y743100D01*
X362700Y742767D01*
X363283Y742600D01*
X363867Y742683D01*
X364367Y742933D01*
X364700Y743267D01*
G01X367383Y742600D02*
Y745933D01*
G01Y745100D02*
X367717Y745517D01*
X368217Y745850D01*
X368883Y745933D01*
X369467Y745850D01*
X369967Y745517D01*
X370217Y744933D01*
Y742600D01*
G01X375900Y747600D02*
Y742600D01*
G01Y743350D02*
X375567Y742933D01*
X375067Y742683D01*
X374483Y742600D01*
X373817Y742767D01*
X373317Y743183D01*
X372983Y743683D01*
X372900Y744267D01*
X372983Y744850D01*
X373317Y745350D01*
X373817Y745767D01*
X374483Y745933D01*
X375067Y745850D01*
X375483Y745683D01*
X375900Y745350D01*
G01X383433Y742600D02*
Y747600D01*
X385600Y743433D01*
X387767Y747600D01*
Y742600D01*
G01X389783Y745933D02*
Y743600D01*
X390117Y743017D01*
X390617Y742683D01*
X391200Y742600D01*
X391783Y742683D01*
X392283Y743017D01*
X392617Y743600D01*
G01Y742600D02*
Y745933D01*
G01X396800Y742600D02*
Y747600D01*
G01X402400D02*
Y742600D01*
G01X401233Y745933D02*
X403567D01*
G01X408000D02*
Y742600D01*
G01Y747267D02*
X407833Y747350D01*
Y747517D01*
X408000Y747600D01*
X408167Y747517D01*
Y747350D01*
X408000Y747267D01*
G01X413600Y742600D02*
Y747600D01*
G01X420700Y742600D02*
Y745933D01*
G01Y745350D02*
X420367Y745683D01*
X419867Y745850D01*
X419283Y745933D01*
X418700Y745767D01*
X418200Y745433D01*
X417867Y744933D01*
X417700Y744267D01*
X417867Y743600D01*
X418200Y743100D01*
X418700Y742767D01*
X419283Y742600D01*
X419867Y742683D01*
X420367Y742933D01*
X420700Y743267D01*
G01X423050Y741100D02*
X423550Y740933D01*
X424217Y741100D01*
X424633Y741433D01*
X424967Y741850D01*
X425467Y743183D01*
X426550Y745933D01*
G01X423883D02*
X425467Y743183D01*
G01X429150Y744850D02*
X431817D01*
X431567Y745433D01*
X431150Y745767D01*
X430567Y745933D01*
X429983Y745850D01*
X429483Y745600D01*
X429150Y745017D01*
X428983Y744517D01*
Y744017D01*
X429150Y743517D01*
X429567Y743017D01*
X430067Y742683D01*
X430650Y742600D01*
X431233Y742767D01*
X431817Y743267D01*
G01X434833Y742600D02*
Y745933D01*
G01Y745267D02*
X435250Y745600D01*
X435667Y745850D01*
X436250Y745933D01*
X436667Y745850D01*
X437167Y745600D01*
G01X445533Y742600D02*
Y747600D01*
X447533D01*
X448200Y747350D01*
X448700Y746767D01*
X448867Y746100D01*
X448700Y745433D01*
X448283Y744933D01*
X447533Y744683D01*
X445533D01*
G01X451633Y742600D02*
Y745933D01*
G01Y745267D02*
X452050Y745600D01*
X452467Y745850D01*
X453050Y745933D01*
X453467Y745850D01*
X453967Y745600D01*
G01X458400Y745933D02*
Y742600D01*
G01Y747267D02*
X458233Y747350D01*
Y747517D01*
X458400Y747600D01*
X458567Y747517D01*
Y747350D01*
X458400Y747267D01*
G01X462583Y742600D02*
Y745933D01*
G01Y745100D02*
X462917Y745517D01*
X463417Y745850D01*
X464083Y745933D01*
X464667Y745850D01*
X465167Y745517D01*
X465417Y744933D01*
Y742600D01*
G01X469600Y747600D02*
Y742600D01*
G01X468433Y745933D02*
X470767D01*
G01X473950Y744850D02*
X476617D01*
X476367Y745433D01*
X475950Y745767D01*
X475367Y745933D01*
X474783Y745850D01*
X474283Y745600D01*
X473950Y745017D01*
X473783Y744517D01*
Y744017D01*
X473950Y743517D01*
X474367Y743017D01*
X474867Y742683D01*
X475450Y742600D01*
X476033Y742767D01*
X476617Y743267D01*
G01X482300Y747600D02*
Y742600D01*
G01Y743350D02*
X481967Y742933D01*
X481467Y742683D01*
X480883Y742600D01*
X480217Y742767D01*
X479717Y743183D01*
X479383Y743683D01*
X479300Y744267D01*
X479383Y744850D01*
X479717Y745350D01*
X480217Y745767D01*
X480883Y745933D01*
X481467Y745850D01*
X481883Y745683D01*
X482300Y745350D01*
G01X492667Y745267D02*
X493000Y745517D01*
X493250Y745933D01*
X493417Y746517D01*
X493250Y747017D01*
X492917Y747350D01*
X492333Y747600D01*
X490083D01*
Y742600D01*
X492833D01*
X493417Y742933D01*
X493750Y743433D01*
X493917Y744017D01*
X493750Y744600D01*
X493250Y745100D01*
X492667Y745267D01*
X490083D01*
G01X497600Y742600D02*
X497100Y742683D01*
X496600Y743017D01*
X496267Y743600D01*
X496100Y744267D01*
X496267Y744933D01*
X496600Y745517D01*
X497100Y745850D01*
X497600Y745933D01*
X498100Y745850D01*
X498600Y745517D01*
X498933Y744933D01*
X499017Y744267D01*
X498933Y743600D01*
X498600Y743017D01*
X498100Y742683D01*
X497600Y742600D01*
G01X504700D02*
Y745933D01*
G01Y745350D02*
X504367Y745683D01*
X503867Y745850D01*
X503283Y745933D01*
X502700Y745767D01*
X502200Y745433D01*
X501867Y744933D01*
X501700Y744267D01*
X501867Y743600D01*
X502200Y743100D01*
X502700Y742767D01*
X503283Y742600D01*
X503867Y742683D01*
X504367Y742933D01*
X504700Y743267D01*
G01X507633Y742600D02*
Y745933D01*
G01Y745267D02*
X508050Y745600D01*
X508467Y745850D01*
X509050Y745933D01*
X509467Y745850D01*
X509967Y745600D01*
G01X515900Y747600D02*
Y742600D01*
G01Y743350D02*
X515567Y742933D01*
X515067Y742683D01*
X514483Y742600D01*
X513817Y742767D01*
X513317Y743183D01*
X512983Y743683D01*
X512900Y744267D01*
X512983Y744850D01*
X513317Y745350D01*
X513817Y745767D01*
X514483Y745933D01*
X515067Y745850D01*
X515483Y745683D01*
X515900Y745350D01*
G01X518750Y743183D02*
X519167Y742850D01*
X519750Y742600D01*
X520250D01*
X520750Y742767D01*
X521083Y743017D01*
X521250Y743350D01*
X521167Y743850D01*
X520833Y744100D01*
X519333Y744600D01*
X519000Y745183D01*
X519167Y745600D01*
X519500Y745850D01*
X520000Y745933D01*
X520500Y745850D01*
X521000Y745600D01*
G01X71000Y756600D02*
X73000D01*
G01X72000D02*
Y751600D01*
G01X71000D02*
X73000D01*
G01X75933D02*
Y756600D01*
X77933D01*
X78600Y756350D01*
X79100Y755767D01*
X79267Y755100D01*
X79100Y754433D01*
X78683Y753933D01*
X77933Y753683D01*
X75933D01*
G01X85033Y756183D02*
X84533Y756433D01*
X83950Y756600D01*
X83283D01*
X82533Y756350D01*
X81950Y755933D01*
X81533Y755433D01*
X81200Y754600D01*
X81117Y753850D01*
X81283Y753100D01*
X81533Y752600D01*
X82033Y752100D01*
X82617Y751767D01*
X83200Y751600D01*
X83783D01*
X84367Y751767D01*
X84867Y752017D01*
X85283Y752350D01*
G01X87717Y753267D02*
X89883D01*
G01X94400Y756600D02*
Y751600D01*
G01X92483Y756600D02*
X96317D01*
G01X97833Y751600D02*
Y756600D01*
X100000Y752433D01*
X102167Y756600D01*
Y751600D01*
G01X104517Y753267D02*
X106683D01*
G01X109617Y753683D02*
X110200Y754267D01*
X110700Y754600D01*
X111367Y754767D01*
X111950Y754600D01*
X112367Y754267D01*
X112700Y753767D01*
X112783Y753183D01*
X112700Y752683D01*
X112367Y752183D01*
X111867Y751767D01*
X111283Y751600D01*
X110617Y751767D01*
X110033Y752267D01*
X109700Y753017D01*
X109617Y753850D01*
X109783Y754933D01*
X110033Y755517D01*
X110450Y756100D01*
X111033Y756517D01*
X111617Y756600D01*
X112200Y756433D01*
X112617Y756017D01*
G01X114967Y752350D02*
X115467Y751933D01*
X116050Y751683D01*
X116800Y751600D01*
X117550Y751767D01*
X118133Y752100D01*
X118550Y752683D01*
X118633Y753350D01*
X118467Y754017D01*
X118050Y754433D01*
X117467Y754767D01*
X116883Y754850D01*
X116300Y754767D01*
X115550Y754433D01*
X115800Y756600D01*
X118050D01*
G01X122400D02*
X121733Y756433D01*
X121233Y756017D01*
X120900Y755517D01*
X120650Y754850D01*
X120567Y754100D01*
X120650Y753350D01*
X120900Y752683D01*
X121233Y752183D01*
X121733Y751767D01*
X122400Y751600D01*
X123067Y751767D01*
X123567Y752183D01*
X123900Y752683D01*
X124150Y753350D01*
X124233Y754100D01*
X124150Y754850D01*
X123900Y755517D01*
X123567Y756017D01*
X123067Y756433D01*
X122400Y756600D01*
G01X133600D02*
Y751600D01*
G01X131683Y756600D02*
X135517D01*
G01X137950Y753850D02*
X140617D01*
X140367Y754433D01*
X139950Y754767D01*
X139367Y754933D01*
X138783Y754850D01*
X138283Y754600D01*
X137950Y754017D01*
X137783Y753517D01*
Y753017D01*
X137950Y752517D01*
X138367Y752017D01*
X138867Y751683D01*
X139450Y751600D01*
X140033Y751767D01*
X140617Y752267D01*
G01X143550Y752183D02*
X143967Y751850D01*
X144550Y751600D01*
X145050D01*
X145550Y751767D01*
X145883Y752017D01*
X146050Y752350D01*
X145967Y752850D01*
X145633Y753100D01*
X144133Y753600D01*
X143800Y754183D01*
X143967Y754600D01*
X144300Y754850D01*
X144800Y754933D01*
X145300Y754850D01*
X145800Y754600D01*
G01X150400Y756600D02*
Y751600D01*
G01X149233Y754933D02*
X151567D01*
G01X159433Y751600D02*
Y756600D01*
X161600Y752433D01*
X163767Y756600D01*
Y751600D01*
G01X165950Y753850D02*
X168617D01*
X168367Y754433D01*
X167950Y754767D01*
X167367Y754933D01*
X166783Y754850D01*
X166283Y754600D01*
X165950Y754017D01*
X165783Y753517D01*
Y753017D01*
X165950Y752517D01*
X166367Y752017D01*
X166867Y751683D01*
X167450Y751600D01*
X168033Y751767D01*
X168617Y752267D01*
G01X172800Y756600D02*
Y751600D01*
G01X171633Y754933D02*
X173967D01*
G01X176983Y751600D02*
Y756600D01*
G01Y754183D02*
X177400Y754600D01*
X177817Y754850D01*
X178483Y754933D01*
X178983Y754850D01*
X179567Y754517D01*
X179817Y754017D01*
Y751600D01*
G01X184000D02*
X183500Y751683D01*
X183000Y752017D01*
X182667Y752600D01*
X182500Y753267D01*
X182667Y753933D01*
X183000Y754517D01*
X183500Y754850D01*
X184000Y754933D01*
X184500Y754850D01*
X185000Y754517D01*
X185333Y753933D01*
X185417Y753267D01*
X185333Y752600D01*
X185000Y752017D01*
X184500Y751683D01*
X184000Y751600D01*
G01X191100Y756600D02*
Y751600D01*
G01Y752350D02*
X190767Y751933D01*
X190267Y751683D01*
X189683Y751600D01*
X189017Y751767D01*
X188517Y752183D01*
X188183Y752683D01*
X188100Y753267D01*
X188183Y753850D01*
X188517Y754350D01*
X189017Y754767D01*
X189683Y754933D01*
X190267Y754850D01*
X190683Y754683D01*
X191100Y754350D01*
G01X193950Y752183D02*
X194367Y751850D01*
X194950Y751600D01*
X195450D01*
X195950Y751767D01*
X196283Y752017D01*
X196450Y752350D01*
X196367Y752850D01*
X196033Y753100D01*
X194533Y753600D01*
X194200Y754183D01*
X194367Y754600D01*
X194700Y754850D01*
X195200Y754933D01*
X195700Y754850D01*
X196200Y754600D01*
G01X204233Y751600D02*
Y756600D01*
X206400Y752433D01*
X208567Y756600D01*
Y751600D01*
G01X213500D02*
Y754933D01*
G01Y754350D02*
X213167Y754683D01*
X212667Y754850D01*
X212083Y754933D01*
X211500Y754767D01*
X211000Y754433D01*
X210667Y753933D01*
X210500Y753267D01*
X210667Y752600D01*
X211000Y752100D01*
X211500Y751767D01*
X212083Y751600D01*
X212667Y751683D01*
X213167Y751933D01*
X213500Y752267D01*
G01X216183Y751600D02*
Y754933D01*
G01Y754100D02*
X216517Y754517D01*
X217017Y754850D01*
X217683Y754933D01*
X218267Y754850D01*
X218767Y754517D01*
X219017Y753933D01*
Y751600D01*
G01X221783Y754933D02*
Y752600D01*
X222117Y752017D01*
X222617Y751683D01*
X223200Y751600D01*
X223783Y751683D01*
X224283Y752017D01*
X224617Y752600D01*
G01Y751600D02*
Y754933D01*
G01X230300Y751600D02*
Y754933D01*
G01Y754350D02*
X229967Y754683D01*
X229467Y754850D01*
X228883Y754933D01*
X228300Y754767D01*
X227800Y754433D01*
X227467Y753933D01*
X227300Y753267D01*
X227467Y752600D01*
X227800Y752100D01*
X228300Y751767D01*
X228883Y751600D01*
X229467Y751683D01*
X229967Y751933D01*
X230300Y752267D01*
G01X234400Y751600D02*
Y756600D01*
G01X71000Y765600D02*
X73000D01*
G01X72000D02*
Y760600D01*
G01X71000D02*
X73000D01*
G01X75933D02*
Y765600D01*
X77933D01*
X78600Y765350D01*
X79100Y764767D01*
X79267Y764100D01*
X79100Y763433D01*
X78683Y762933D01*
X77933Y762683D01*
X75933D01*
G01X85033Y765183D02*
X84533Y765433D01*
X83950Y765600D01*
X83283D01*
X82533Y765350D01*
X81950Y764933D01*
X81533Y764433D01*
X81200Y763600D01*
X81117Y762850D01*
X81283Y762100D01*
X81533Y761600D01*
X82033Y761100D01*
X82617Y760767D01*
X83200Y760600D01*
X83783D01*
X84367Y760767D01*
X84867Y761017D01*
X85283Y761350D01*
G01X87717Y762267D02*
X89883D01*
G01X92817Y762683D02*
X93400Y763267D01*
X93900Y763600D01*
X94567Y763767D01*
X95150Y763600D01*
X95567Y763267D01*
X95900Y762767D01*
X95983Y762183D01*
X95900Y761683D01*
X95567Y761183D01*
X95067Y760767D01*
X94483Y760600D01*
X93817Y760767D01*
X93233Y761267D01*
X92900Y762017D01*
X92817Y762850D01*
X92983Y763933D01*
X93233Y764517D01*
X93650Y765100D01*
X94233Y765517D01*
X94817Y765600D01*
X95400Y765433D01*
X95817Y765017D01*
G01X100000Y765600D02*
X99333Y765433D01*
X98833Y765017D01*
X98500Y764517D01*
X98250Y763850D01*
X98167Y763100D01*
X98250Y762350D01*
X98500Y761683D01*
X98833Y761183D01*
X99333Y760767D01*
X100000Y760600D01*
X100667Y760767D01*
X101167Y761183D01*
X101500Y761683D01*
X101750Y762350D01*
X101833Y763100D01*
X101750Y763850D01*
X101500Y764517D01*
X101167Y765017D01*
X100667Y765433D01*
X100000Y765600D01*
G01X105600Y760600D02*
Y765600D01*
X104600Y764600D01*
G01Y760600D02*
X106600D01*
G01X109617Y762683D02*
X110200Y763267D01*
X110700Y763600D01*
X111367Y763767D01*
X111950Y763600D01*
X112367Y763267D01*
X112700Y762767D01*
X112783Y762183D01*
X112700Y761683D01*
X112367Y761183D01*
X111867Y760767D01*
X111283Y760600D01*
X110617Y760767D01*
X110033Y761267D01*
X109700Y762017D01*
X109617Y762850D01*
X109783Y763933D01*
X110033Y764517D01*
X110450Y765100D01*
X111033Y765517D01*
X111617Y765600D01*
X112200Y765433D01*
X112617Y765017D01*
G01X122400Y760600D02*
X121733Y760683D01*
X121150Y761017D01*
X120650Y761517D01*
X120317Y762100D01*
X120150Y762767D01*
Y763433D01*
X120317Y764100D01*
X120650Y764683D01*
X121150Y765183D01*
X121733Y765517D01*
X122400Y765600D01*
X123067Y765517D01*
X123650Y765183D01*
X124150Y764683D01*
X124483Y764100D01*
X124650Y763433D01*
Y762767D01*
X124483Y762100D01*
X124150Y761517D01*
X123650Y761017D01*
X123067Y760683D01*
X122400Y760600D01*
G01X123067Y761933D02*
X124067Y760600D01*
G01X126583Y763933D02*
Y761600D01*
X126917Y761017D01*
X127417Y760683D01*
X128000Y760600D01*
X128583Y760683D01*
X129083Y761017D01*
X129417Y761600D01*
G01Y760600D02*
Y763933D01*
G01X135100Y760600D02*
Y763933D01*
G01Y763350D02*
X134767Y763683D01*
X134267Y763850D01*
X133683Y763933D01*
X133100Y763767D01*
X132600Y763433D01*
X132267Y762933D01*
X132100Y762267D01*
X132267Y761600D01*
X132600Y761100D01*
X133100Y760767D01*
X133683Y760600D01*
X134267Y760683D01*
X134767Y760933D01*
X135100Y761267D01*
G01X139200Y760600D02*
Y765600D01*
G01X144800Y763933D02*
Y760600D01*
G01Y765267D02*
X144633Y765350D01*
Y765517D01*
X144800Y765600D01*
X144967Y765517D01*
Y765350D01*
X144800Y765267D01*
G01X149900Y760600D02*
Y764850D01*
X150067Y765267D01*
X150400Y765517D01*
X150900Y765600D01*
X151400Y765433D01*
X151650Y765017D01*
G01X150650Y763600D02*
X148983D01*
G01X156000Y763933D02*
Y760600D01*
G01Y765267D02*
X155833Y765350D01*
Y765517D01*
X156000Y765600D01*
X156167Y765517D01*
Y765350D01*
X156000Y765267D01*
G01X162933Y763517D02*
X162350Y763850D01*
X161850Y763933D01*
X161183Y763767D01*
X160683Y763433D01*
X160350Y762850D01*
X160267Y762267D01*
X160350Y761683D01*
X160683Y761183D01*
X161183Y760767D01*
X161850Y760600D01*
X162433Y760767D01*
X162933Y761100D01*
G01X168700Y760600D02*
Y763933D01*
G01Y763350D02*
X168367Y763683D01*
X167867Y763850D01*
X167283Y763933D01*
X166700Y763767D01*
X166200Y763433D01*
X165867Y762933D01*
X165700Y762267D01*
X165867Y761600D01*
X166200Y761100D01*
X166700Y760767D01*
X167283Y760600D01*
X167867Y760683D01*
X168367Y760933D01*
X168700Y761267D01*
G01X172800Y765600D02*
Y760600D01*
G01X171633Y763933D02*
X173967D01*
G01X178400D02*
Y760600D01*
G01Y765267D02*
X178233Y765350D01*
Y765517D01*
X178400Y765600D01*
X178567Y765517D01*
Y765350D01*
X178400Y765267D01*
G01X184000Y760600D02*
X183500Y760683D01*
X183000Y761017D01*
X182667Y761600D01*
X182500Y762267D01*
X182667Y762933D01*
X183000Y763517D01*
X183500Y763850D01*
X184000Y763933D01*
X184500Y763850D01*
X185000Y763517D01*
X185333Y762933D01*
X185417Y762267D01*
X185333Y761600D01*
X185000Y761017D01*
X184500Y760683D01*
X184000Y760600D01*
G01X188183D02*
Y763933D01*
G01Y763100D02*
X188517Y763517D01*
X189017Y763850D01*
X189683Y763933D01*
X190267Y763850D01*
X190767Y763517D01*
X191017Y762933D01*
Y760600D01*
G01X203300Y758933D02*
X199133Y763933D01*
Y764767D01*
X199967Y765600D01*
X200800D01*
X201633Y764767D01*
Y763933D01*
X200800Y763100D01*
X199133Y762267D01*
X198300Y761433D01*
Y759767D01*
X199133Y758933D01*
X201633D01*
X203300Y760600D01*
G01X210333D02*
Y765600D01*
X212333D01*
X213000Y765350D01*
X213500Y764767D01*
X213667Y764100D01*
X213500Y763433D01*
X213083Y762933D01*
X212333Y762683D01*
X210333D01*
G01X216350Y762850D02*
X219017D01*
X218767Y763433D01*
X218350Y763767D01*
X217767Y763933D01*
X217183Y763850D01*
X216683Y763600D01*
X216350Y763017D01*
X216183Y762517D01*
Y762017D01*
X216350Y761517D01*
X216767Y761017D01*
X217267Y760683D01*
X217850Y760600D01*
X218433Y760767D01*
X219017Y761267D01*
G01X222033Y760600D02*
Y763933D01*
G01Y763267D02*
X222450Y763600D01*
X222867Y763850D01*
X223450Y763933D01*
X223867Y763850D01*
X224367Y763600D01*
G01X228300Y760600D02*
Y764850D01*
X228467Y765267D01*
X228800Y765517D01*
X229300Y765600D01*
X229800Y765433D01*
X230050Y765017D01*
G01X229050Y763600D02*
X227383D01*
G01X234400Y760600D02*
X233900Y760683D01*
X233400Y761017D01*
X233067Y761600D01*
X232900Y762267D01*
X233067Y762933D01*
X233400Y763517D01*
X233900Y763850D01*
X234400Y763933D01*
X234900Y763850D01*
X235400Y763517D01*
X235733Y762933D01*
X235817Y762267D01*
X235733Y761600D01*
X235400Y761017D01*
X234900Y760683D01*
X234400Y760600D01*
G01X238833D02*
Y763933D01*
G01Y763267D02*
X239250Y763600D01*
X239667Y763850D01*
X240250Y763933D01*
X240667Y763850D01*
X241167Y763600D01*
G01X243100Y760600D02*
Y763933D01*
G01Y763017D02*
X243350Y763433D01*
X243767Y763767D01*
X244350Y763933D01*
X244933Y763767D01*
X245350Y763433D01*
X245600Y763017D01*
Y760600D01*
G01Y763017D02*
X245850Y763433D01*
X246267Y763767D01*
X246850Y763933D01*
X247433Y763767D01*
X247850Y763433D01*
X248100Y762933D01*
Y760600D01*
G01X252700D02*
Y763933D01*
G01Y763350D02*
X252367Y763683D01*
X251867Y763850D01*
X251283Y763933D01*
X250700Y763767D01*
X250200Y763433D01*
X249867Y762933D01*
X249700Y762267D01*
X249867Y761600D01*
X250200Y761100D01*
X250700Y760767D01*
X251283Y760600D01*
X251867Y760683D01*
X252367Y760933D01*
X252700Y761267D01*
G01X255383Y760600D02*
Y763933D01*
G01Y763100D02*
X255717Y763517D01*
X256217Y763850D01*
X256883Y763933D01*
X257467Y763850D01*
X257967Y763517D01*
X258217Y762933D01*
Y760600D01*
G01X263733Y763517D02*
X263150Y763850D01*
X262650Y763933D01*
X261983Y763767D01*
X261483Y763433D01*
X261150Y762850D01*
X261067Y762267D01*
X261150Y761683D01*
X261483Y761183D01*
X261983Y760767D01*
X262650Y760600D01*
X263233Y760767D01*
X263733Y761100D01*
G01X266750Y762850D02*
X269417D01*
X269167Y763433D01*
X268750Y763767D01*
X268167Y763933D01*
X267583Y763850D01*
X267083Y763600D01*
X266750Y763017D01*
X266583Y762517D01*
Y762017D01*
X266750Y761517D01*
X267167Y761017D01*
X267667Y760683D01*
X268250Y760600D01*
X268833Y760767D01*
X269417Y761267D01*
G01X277450D02*
X278117Y760850D01*
X278867Y760600D01*
X279533D01*
X280200Y760850D01*
X280700Y761267D01*
X280950Y761850D01*
X280783Y762433D01*
X280367Y762933D01*
X279617Y763267D01*
X278617Y763433D01*
X278033Y763767D01*
X277783Y764350D01*
X277950Y764933D01*
X278367Y765350D01*
X278950Y765600D01*
X279533D01*
X280117Y765433D01*
X280617Y765017D01*
G01X283300Y758933D02*
Y763933D01*
G01Y763183D02*
X283717Y763600D01*
X284133Y763850D01*
X284800Y763933D01*
X285383Y763850D01*
X285967Y763433D01*
X286217Y762850D01*
X286300Y762267D01*
X286217Y761683D01*
X285967Y761100D01*
X285467Y760767D01*
X284800Y760600D01*
X284217Y760683D01*
X283633Y760933D01*
X283300Y761267D01*
G01X289150Y762850D02*
X291817D01*
X291567Y763433D01*
X291150Y763767D01*
X290567Y763933D01*
X289983Y763850D01*
X289483Y763600D01*
X289150Y763017D01*
X288983Y762517D01*
Y762017D01*
X289150Y761517D01*
X289567Y761017D01*
X290067Y760683D01*
X290650Y760600D01*
X291233Y760767D01*
X291817Y761267D01*
G01X297333Y763517D02*
X296750Y763850D01*
X296250Y763933D01*
X295583Y763767D01*
X295083Y763433D01*
X294750Y762850D01*
X294667Y762267D01*
X294750Y761683D01*
X295083Y761183D01*
X295583Y760767D01*
X296250Y760600D01*
X296833Y760767D01*
X297333Y761100D01*
G01X301600Y763933D02*
Y760600D01*
G01Y765267D02*
X301433Y765350D01*
Y765517D01*
X301600Y765600D01*
X301767Y765517D01*
Y765350D01*
X301600Y765267D01*
G01X306700Y760600D02*
Y764850D01*
X306867Y765267D01*
X307200Y765517D01*
X307700Y765600D01*
X308200Y765433D01*
X308450Y765017D01*
G01X307450Y763600D02*
X305783D01*
G01X312800Y763933D02*
Y760600D01*
G01Y765267D02*
X312633Y765350D01*
Y765517D01*
X312800Y765600D01*
X312967Y765517D01*
Y765350D01*
X312800Y765267D01*
G01X319733Y763517D02*
X319150Y763850D01*
X318650Y763933D01*
X317983Y763767D01*
X317483Y763433D01*
X317150Y762850D01*
X317067Y762267D01*
X317150Y761683D01*
X317483Y761183D01*
X317983Y760767D01*
X318650Y760600D01*
X319233Y760767D01*
X319733Y761100D01*
G01X325500Y760600D02*
Y763933D01*
G01Y763350D02*
X325167Y763683D01*
X324667Y763850D01*
X324083Y763933D01*
X323500Y763767D01*
X323000Y763433D01*
X322667Y762933D01*
X322500Y762267D01*
X322667Y761600D01*
X323000Y761100D01*
X323500Y760767D01*
X324083Y760600D01*
X324667Y760683D01*
X325167Y760933D01*
X325500Y761267D01*
G01X329600Y765600D02*
Y760600D01*
G01X328433Y763933D02*
X330767D01*
G01X335200D02*
Y760600D01*
G01Y765267D02*
X335033Y765350D01*
Y765517D01*
X335200Y765600D01*
X335367Y765517D01*
Y765350D01*
X335200Y765267D01*
G01X340800Y760600D02*
X340300Y760683D01*
X339800Y761017D01*
X339467Y761600D01*
X339300Y762267D01*
X339467Y762933D01*
X339800Y763517D01*
X340300Y763850D01*
X340800Y763933D01*
X341300Y763850D01*
X341800Y763517D01*
X342133Y762933D01*
X342217Y762267D01*
X342133Y761600D01*
X341800Y761017D01*
X341300Y760683D01*
X340800Y760600D01*
G01X344983D02*
Y763933D01*
G01Y763100D02*
X345317Y763517D01*
X345817Y763850D01*
X346483Y763933D01*
X347067Y763850D01*
X347567Y763517D01*
X347817Y762933D01*
Y760600D01*
G01X357100D02*
Y764850D01*
X357267Y765267D01*
X357600Y765517D01*
X358100Y765600D01*
X358600Y765433D01*
X358850Y765017D01*
G01X357850Y763600D02*
X356183D01*
G01X363200Y760600D02*
X362700Y760683D01*
X362200Y761017D01*
X361867Y761600D01*
X361700Y762267D01*
X361867Y762933D01*
X362200Y763517D01*
X362700Y763850D01*
X363200Y763933D01*
X363700Y763850D01*
X364200Y763517D01*
X364533Y762933D01*
X364617Y762267D01*
X364533Y761600D01*
X364200Y761017D01*
X363700Y760683D01*
X363200Y760600D01*
G01X367633D02*
Y763933D01*
G01Y763267D02*
X368050Y763600D01*
X368467Y763850D01*
X369050Y763933D01*
X369467Y763850D01*
X369967Y763600D01*
G01X378250Y760600D02*
Y765600D01*
G01X381750D02*
Y760600D01*
G01Y763100D02*
X378250D01*
G01X385600Y763933D02*
Y760600D01*
G01Y765267D02*
X385433Y765350D01*
Y765517D01*
X385600Y765600D01*
X385767Y765517D01*
Y765350D01*
X385600Y765267D01*
G01X390033Y759350D02*
X390617Y759017D01*
X391283Y758933D01*
X391867Y759017D01*
X392367Y759433D01*
X392700Y760017D01*
Y763933D01*
G01Y763267D02*
X392367Y763600D01*
X391867Y763850D01*
X391283Y763933D01*
X390617Y763767D01*
X390200Y763433D01*
X389867Y762850D01*
X389700Y762267D01*
X389783Y761767D01*
X390117Y761183D01*
X390617Y760767D01*
X391283Y760600D01*
X391783Y760683D01*
X392367Y761017D01*
X392700Y761350D01*
G01X395383Y760600D02*
Y765600D01*
G01Y763183D02*
X395800Y763600D01*
X396217Y763850D01*
X396883Y763933D01*
X397383Y763850D01*
X397967Y763517D01*
X398217Y763017D01*
Y760600D01*
G01X406167D02*
Y765600D01*
X407833D01*
X408500Y765350D01*
X409000Y765017D01*
X409417Y764517D01*
X409750Y763933D01*
X409833Y763100D01*
X409750Y762267D01*
X409417Y761683D01*
X409000Y761183D01*
X408500Y760850D01*
X407833Y760600D01*
X406167D01*
G01X412350Y762850D02*
X415017D01*
X414767Y763433D01*
X414350Y763767D01*
X413767Y763933D01*
X413183Y763850D01*
X412683Y763600D01*
X412350Y763017D01*
X412183Y762517D01*
Y762017D01*
X412350Y761517D01*
X412767Y761017D01*
X413267Y760683D01*
X413850Y760600D01*
X414433Y760767D01*
X415017Y761267D01*
G01X417783Y760600D02*
Y763933D01*
G01Y763100D02*
X418117Y763517D01*
X418617Y763850D01*
X419283Y763933D01*
X419867Y763850D01*
X420367Y763517D01*
X420617Y762933D01*
Y760600D01*
G01X423550Y761183D02*
X423967Y760850D01*
X424550Y760600D01*
X425050D01*
X425550Y760767D01*
X425883Y761017D01*
X426050Y761350D01*
X425967Y761850D01*
X425633Y762100D01*
X424133Y762600D01*
X423800Y763183D01*
X423967Y763600D01*
X424300Y763850D01*
X424800Y763933D01*
X425300Y763850D01*
X425800Y763600D01*
G01X430400Y763933D02*
Y760600D01*
G01Y765267D02*
X430233Y765350D01*
Y765517D01*
X430400Y765600D01*
X430567Y765517D01*
Y765350D01*
X430400Y765267D01*
G01X436000Y765600D02*
Y760600D01*
G01X434833Y763933D02*
X437167D01*
G01X439850Y759100D02*
X440350Y758933D01*
X441017Y759100D01*
X441433Y759433D01*
X441767Y759850D01*
X442267Y761183D01*
X443350Y763933D01*
G01X440683D02*
X442267Y761183D01*
G01X451800Y765600D02*
X453800D01*
G01X452800D02*
Y760600D01*
G01X451800D02*
X453800D01*
G01X456983D02*
Y763933D01*
G01Y763100D02*
X457317Y763517D01*
X457817Y763850D01*
X458483Y763933D01*
X459067Y763850D01*
X459567Y763517D01*
X459817Y762933D01*
Y760600D01*
G01X464000Y765600D02*
Y760600D01*
G01X462833Y763933D02*
X465167D01*
G01X468350Y762850D02*
X471017D01*
X470767Y763433D01*
X470350Y763767D01*
X469767Y763933D01*
X469183Y763850D01*
X468683Y763600D01*
X468350Y763017D01*
X468183Y762517D01*
Y762017D01*
X468350Y761517D01*
X468767Y761017D01*
X469267Y760683D01*
X469850Y760600D01*
X470433Y760767D01*
X471017Y761267D01*
G01X474033Y760600D02*
Y763933D01*
G01Y763267D02*
X474450Y763600D01*
X474867Y763850D01*
X475450Y763933D01*
X475867Y763850D01*
X476367Y763600D01*
G01X482133Y763517D02*
X481550Y763850D01*
X481050Y763933D01*
X480383Y763767D01*
X479883Y763433D01*
X479550Y762850D01*
X479467Y762267D01*
X479550Y761683D01*
X479883Y761183D01*
X480383Y760767D01*
X481050Y760600D01*
X481633Y760767D01*
X482133Y761100D01*
G01X486400Y760600D02*
X485900Y760683D01*
X485400Y761017D01*
X485067Y761600D01*
X484900Y762267D01*
X485067Y762933D01*
X485400Y763517D01*
X485900Y763850D01*
X486400Y763933D01*
X486900Y763850D01*
X487400Y763517D01*
X487733Y762933D01*
X487817Y762267D01*
X487733Y761600D01*
X487400Y761017D01*
X486900Y760683D01*
X486400Y760600D01*
G01X490583D02*
Y763933D01*
G01Y763100D02*
X490917Y763517D01*
X491417Y763850D01*
X492083Y763933D01*
X492667Y763850D01*
X493167Y763517D01*
X493417Y762933D01*
Y760600D01*
G01X496183D02*
Y763933D01*
G01Y763100D02*
X496517Y763517D01*
X497017Y763850D01*
X497683Y763933D01*
X498267Y763850D01*
X498767Y763517D01*
X499017Y762933D01*
Y760600D01*
G01X501950Y762850D02*
X504617D01*
X504367Y763433D01*
X503950Y763767D01*
X503367Y763933D01*
X502783Y763850D01*
X502283Y763600D01*
X501950Y763017D01*
X501783Y762517D01*
Y762017D01*
X501950Y761517D01*
X502367Y761017D01*
X502867Y760683D01*
X503450Y760600D01*
X504033Y760767D01*
X504617Y761267D01*
G01X510133Y763517D02*
X509550Y763850D01*
X509050Y763933D01*
X508383Y763767D01*
X507883Y763433D01*
X507550Y762850D01*
X507467Y762267D01*
X507550Y761683D01*
X507883Y761183D01*
X508383Y760767D01*
X509050Y760600D01*
X509633Y760767D01*
X510133Y761100D01*
G01X514400Y765600D02*
Y760600D01*
G01X513233Y763933D02*
X515567D01*
G01X519583Y758933D02*
X518750Y759767D01*
X518333Y760600D01*
Y763933D01*
X518750Y764767D01*
X519583Y765600D01*
G01X523850Y760600D02*
Y765600D01*
G01X527350D02*
Y760600D01*
G01Y763100D02*
X523850D01*
G01X529367Y760600D02*
Y765600D01*
X531033D01*
X531700Y765350D01*
X532200Y765017D01*
X532617Y764517D01*
X532950Y763933D01*
X533033Y763100D01*
X532950Y762267D01*
X532617Y761683D01*
X532200Y761183D01*
X531700Y760850D01*
X531033Y760600D01*
X529367D01*
G01X535800Y765600D02*
X537800D01*
G01X536800D02*
Y760600D01*
G01X535800D02*
X537800D01*
G01X542817Y758933D02*
X543650Y759767D01*
X544067Y760600D01*
Y763933D01*
X543650Y764767D01*
X542817Y765600D01*
G01X551933D02*
Y760600D01*
X555267D01*
G01X560700D02*
Y763933D01*
G01Y763350D02*
X560367Y763683D01*
X559867Y763850D01*
X559283Y763933D01*
X558700Y763767D01*
X558200Y763433D01*
X557867Y762933D01*
X557700Y762267D01*
X557867Y761600D01*
X558200Y761100D01*
X558700Y760767D01*
X559283Y760600D01*
X559867Y760683D01*
X560367Y760933D01*
X560700Y761267D01*
G01X563050Y759100D02*
X563550Y758933D01*
X564217Y759100D01*
X564633Y759433D01*
X564967Y759850D01*
X565467Y761183D01*
X566550Y763933D01*
G01X563883D02*
X565467Y761183D01*
G01X569150Y762850D02*
X571817D01*
X571567Y763433D01*
X571150Y763767D01*
X570567Y763933D01*
X569983Y763850D01*
X569483Y763600D01*
X569150Y763017D01*
X568983Y762517D01*
Y762017D01*
X569150Y761517D01*
X569567Y761017D01*
X570067Y760683D01*
X570650Y760600D01*
X571233Y760767D01*
X571817Y761267D01*
G01X574833Y760600D02*
Y763933D01*
G01Y763267D02*
X575250Y763600D01*
X575667Y763850D01*
X576250Y763933D01*
X576667Y763850D01*
X577167Y763600D01*
G01X580350Y761183D02*
X580767Y760850D01*
X581350Y760600D01*
X581850D01*
X582350Y760767D01*
X582683Y761017D01*
X582850Y761350D01*
X582767Y761850D01*
X582433Y762100D01*
X580933Y762600D01*
X580600Y763183D01*
X580767Y763600D01*
X581100Y763850D01*
X581600Y763933D01*
X582100Y763850D01*
X582600Y763600D01*
G01X592800Y760600D02*
X592300Y760683D01*
X591800Y761017D01*
X591467Y761600D01*
X591300Y762267D01*
X591467Y762933D01*
X591800Y763517D01*
X592300Y763850D01*
X592800Y763933D01*
X593300Y763850D01*
X593800Y763517D01*
X594133Y762933D01*
X594217Y762267D01*
X594133Y761600D01*
X593800Y761017D01*
X593300Y760683D01*
X592800Y760600D01*
G01X597233D02*
Y763933D01*
G01Y763267D02*
X597650Y763600D01*
X598067Y763850D01*
X598650Y763933D01*
X599067Y763850D01*
X599567Y763600D01*
G01X610267Y763267D02*
X610600Y763517D01*
X610850Y763933D01*
X611017Y764517D01*
X610850Y765017D01*
X610517Y765350D01*
X609933Y765600D01*
X607683D01*
Y760600D01*
X610433D01*
X611017Y760933D01*
X611350Y761433D01*
X611517Y762017D01*
X611350Y762600D01*
X610850Y763100D01*
X610267Y763267D01*
X607683D01*
G01X615200Y760600D02*
X614700Y760683D01*
X614200Y761017D01*
X613867Y761600D01*
X613700Y762267D01*
X613867Y762933D01*
X614200Y763517D01*
X614700Y763850D01*
X615200Y763933D01*
X615700Y763850D01*
X616200Y763517D01*
X616533Y762933D01*
X616617Y762267D01*
X616533Y761600D01*
X616200Y761017D01*
X615700Y760683D01*
X615200Y760600D01*
G01X622300D02*
Y763933D01*
G01Y763350D02*
X621967Y763683D01*
X621467Y763850D01*
X620883Y763933D01*
X620300Y763767D01*
X619800Y763433D01*
X619467Y762933D01*
X619300Y762267D01*
X619467Y761600D01*
X619800Y761100D01*
X620300Y760767D01*
X620883Y760600D01*
X621467Y760683D01*
X621967Y760933D01*
X622300Y761267D01*
G01X625233Y760600D02*
Y763933D01*
G01Y763267D02*
X625650Y763600D01*
X626067Y763850D01*
X626650Y763933D01*
X627067Y763850D01*
X627567Y763600D01*
G01X633500Y765600D02*
Y760600D01*
G01Y761350D02*
X633167Y760933D01*
X632667Y760683D01*
X632083Y760600D01*
X631417Y760767D01*
X630917Y761183D01*
X630583Y761683D01*
X630500Y762267D01*
X630583Y762850D01*
X630917Y763350D01*
X631417Y763767D01*
X632083Y763933D01*
X632667Y763850D01*
X633083Y763683D01*
X633500Y763350D01*
G01X636350Y761183D02*
X636767Y760850D01*
X637350Y760600D01*
X637850D01*
X638350Y760767D01*
X638683Y761017D01*
X638850Y761350D01*
X638767Y761850D01*
X638433Y762100D01*
X636933Y762600D01*
X636600Y763183D01*
X636767Y763600D01*
X637100Y763850D01*
X637600Y763933D01*
X638100Y763850D01*
X638600Y763600D01*
G01X643617Y758933D02*
X644450Y759767D01*
X644867Y760600D01*
Y763933D01*
X644450Y764767D01*
X643617Y765600D01*
G01X71000Y774600D02*
X73000D01*
G01X72000D02*
Y769600D01*
G01X71000D02*
X73000D01*
G01X75933D02*
Y774600D01*
X77933D01*
X78600Y774350D01*
X79100Y773767D01*
X79267Y773100D01*
X79100Y772433D01*
X78683Y771933D01*
X77933Y771683D01*
X75933D01*
G01X85033Y774183D02*
X84533Y774433D01*
X83950Y774600D01*
X83283D01*
X82533Y774350D01*
X81950Y773933D01*
X81533Y773433D01*
X81200Y772600D01*
X81117Y771850D01*
X81283Y771100D01*
X81533Y770600D01*
X82033Y770100D01*
X82617Y769767D01*
X83200Y769600D01*
X83783D01*
X84367Y769767D01*
X84867Y770017D01*
X85283Y770350D01*
G01X87717Y771267D02*
X89883D01*
G01X92817Y771683D02*
X93400Y772267D01*
X93900Y772600D01*
X94567Y772767D01*
X95150Y772600D01*
X95567Y772267D01*
X95900Y771767D01*
X95983Y771183D01*
X95900Y770683D01*
X95567Y770183D01*
X95067Y769767D01*
X94483Y769600D01*
X93817Y769767D01*
X93233Y770267D01*
X92900Y771017D01*
X92817Y771850D01*
X92983Y772933D01*
X93233Y773517D01*
X93650Y774100D01*
X94233Y774517D01*
X94817Y774600D01*
X95400Y774433D01*
X95817Y774017D01*
G01X100000Y774600D02*
X99333Y774433D01*
X98833Y774017D01*
X98500Y773517D01*
X98250Y772850D01*
X98167Y772100D01*
X98250Y771350D01*
X98500Y770683D01*
X98833Y770183D01*
X99333Y769767D01*
X100000Y769600D01*
X100667Y769767D01*
X101167Y770183D01*
X101500Y770683D01*
X101750Y771350D01*
X101833Y772100D01*
X101750Y772850D01*
X101500Y773517D01*
X101167Y774017D01*
X100667Y774433D01*
X100000Y774600D01*
G01X105600Y769600D02*
Y774600D01*
X104600Y773600D01*
G01Y769600D02*
X106600D01*
G01X109617Y773767D02*
X110117Y774267D01*
X110700Y774517D01*
X111367Y774600D01*
X112200Y774433D01*
X112783Y774017D01*
X112950Y773517D01*
X112867Y773017D01*
X112533Y772600D01*
X110867Y771767D01*
X110117Y771183D01*
X109617Y770350D01*
X109450Y769600D01*
X112950D01*
G01X122400D02*
X121733Y769683D01*
X121150Y770017D01*
X120650Y770517D01*
X120317Y771100D01*
X120150Y771767D01*
Y772433D01*
X120317Y773100D01*
X120650Y773683D01*
X121150Y774183D01*
X121733Y774517D01*
X122400Y774600D01*
X123067Y774517D01*
X123650Y774183D01*
X124150Y773683D01*
X124483Y773100D01*
X124650Y772433D01*
Y771767D01*
X124483Y771100D01*
X124150Y770517D01*
X123650Y770017D01*
X123067Y769683D01*
X122400Y769600D01*
G01X123067Y770933D02*
X124067Y769600D01*
G01X126583Y772933D02*
Y770600D01*
X126917Y770017D01*
X127417Y769683D01*
X128000Y769600D01*
X128583Y769683D01*
X129083Y770017D01*
X129417Y770600D01*
G01Y769600D02*
Y772933D01*
G01X135100Y769600D02*
Y772933D01*
G01Y772350D02*
X134767Y772683D01*
X134267Y772850D01*
X133683Y772933D01*
X133100Y772767D01*
X132600Y772433D01*
X132267Y771933D01*
X132100Y771267D01*
X132267Y770600D01*
X132600Y770100D01*
X133100Y769767D01*
X133683Y769600D01*
X134267Y769683D01*
X134767Y769933D01*
X135100Y770267D01*
G01X139200Y769600D02*
Y774600D01*
G01X144800Y772933D02*
Y769600D01*
G01Y774267D02*
X144633Y774350D01*
Y774517D01*
X144800Y774600D01*
X144967Y774517D01*
Y774350D01*
X144800Y774267D01*
G01X149900Y769600D02*
Y773850D01*
X150067Y774267D01*
X150400Y774517D01*
X150900Y774600D01*
X151400Y774433D01*
X151650Y774017D01*
G01X150650Y772600D02*
X148983D01*
G01X156000Y772933D02*
Y769600D01*
G01Y774267D02*
X155833Y774350D01*
Y774517D01*
X156000Y774600D01*
X156167Y774517D01*
Y774350D01*
X156000Y774267D01*
G01X162933Y772517D02*
X162350Y772850D01*
X161850Y772933D01*
X161183Y772767D01*
X160683Y772433D01*
X160350Y771850D01*
X160267Y771267D01*
X160350Y770683D01*
X160683Y770183D01*
X161183Y769767D01*
X161850Y769600D01*
X162433Y769767D01*
X162933Y770100D01*
G01X168700Y769600D02*
Y772933D01*
G01Y772350D02*
X168367Y772683D01*
X167867Y772850D01*
X167283Y772933D01*
X166700Y772767D01*
X166200Y772433D01*
X165867Y771933D01*
X165700Y771267D01*
X165867Y770600D01*
X166200Y770100D01*
X166700Y769767D01*
X167283Y769600D01*
X167867Y769683D01*
X168367Y769933D01*
X168700Y770267D01*
G01X172800Y774600D02*
Y769600D01*
G01X171633Y772933D02*
X173967D01*
G01X178400D02*
Y769600D01*
G01Y774267D02*
X178233Y774350D01*
Y774517D01*
X178400Y774600D01*
X178567Y774517D01*
Y774350D01*
X178400Y774267D01*
G01X184000Y769600D02*
X183500Y769683D01*
X183000Y770017D01*
X182667Y770600D01*
X182500Y771267D01*
X182667Y771933D01*
X183000Y772517D01*
X183500Y772850D01*
X184000Y772933D01*
X184500Y772850D01*
X185000Y772517D01*
X185333Y771933D01*
X185417Y771267D01*
X185333Y770600D01*
X185000Y770017D01*
X184500Y769683D01*
X184000Y769600D01*
G01X188183D02*
Y772933D01*
G01Y772100D02*
X188517Y772517D01*
X189017Y772850D01*
X189683Y772933D01*
X190267Y772850D01*
X190767Y772517D01*
X191017Y771933D01*
Y769600D01*
G01X202300D02*
Y772933D01*
G01Y772350D02*
X201967Y772683D01*
X201467Y772850D01*
X200883Y772933D01*
X200300Y772767D01*
X199800Y772433D01*
X199467Y771933D01*
X199300Y771267D01*
X199467Y770600D01*
X199800Y770100D01*
X200300Y769767D01*
X200883Y769600D01*
X201467Y769683D01*
X201967Y769933D01*
X202300Y770267D01*
G01X204983Y769600D02*
Y772933D01*
G01Y772100D02*
X205317Y772517D01*
X205817Y772850D01*
X206483Y772933D01*
X207067Y772850D01*
X207567Y772517D01*
X207817Y771933D01*
Y769600D01*
G01X213500Y774600D02*
Y769600D01*
G01Y770350D02*
X213167Y769933D01*
X212667Y769683D01*
X212083Y769600D01*
X211417Y769767D01*
X210917Y770183D01*
X210583Y770683D01*
X210500Y771267D01*
X210583Y771850D01*
X210917Y772350D01*
X211417Y772767D01*
X212083Y772933D01*
X212667Y772850D01*
X213083Y772683D01*
X213500Y772350D01*
G01X221533Y769600D02*
Y774600D01*
X223533D01*
X224200Y774350D01*
X224700Y773767D01*
X224867Y773100D01*
X224700Y772433D01*
X224283Y771933D01*
X223533Y771683D01*
X221533D01*
G01X227550Y771850D02*
X230217D01*
X229967Y772433D01*
X229550Y772767D01*
X228967Y772933D01*
X228383Y772850D01*
X227883Y772600D01*
X227550Y772017D01*
X227383Y771517D01*
Y771017D01*
X227550Y770517D01*
X227967Y770017D01*
X228467Y769683D01*
X229050Y769600D01*
X229633Y769767D01*
X230217Y770267D01*
G01X233233Y769600D02*
Y772933D01*
G01Y772267D02*
X233650Y772600D01*
X234067Y772850D01*
X234650Y772933D01*
X235067Y772850D01*
X235567Y772600D01*
G01X239500Y769600D02*
Y773850D01*
X239667Y774267D01*
X240000Y774517D01*
X240500Y774600D01*
X241000Y774433D01*
X241250Y774017D01*
G01X240250Y772600D02*
X238583D01*
G01X245600Y769600D02*
X245100Y769683D01*
X244600Y770017D01*
X244267Y770600D01*
X244100Y771267D01*
X244267Y771933D01*
X244600Y772517D01*
X245100Y772850D01*
X245600Y772933D01*
X246100Y772850D01*
X246600Y772517D01*
X246933Y771933D01*
X247017Y771267D01*
X246933Y770600D01*
X246600Y770017D01*
X246100Y769683D01*
X245600Y769600D01*
G01X250033D02*
Y772933D01*
G01Y772267D02*
X250450Y772600D01*
X250867Y772850D01*
X251450Y772933D01*
X251867Y772850D01*
X252367Y772600D01*
G01X254300Y769600D02*
Y772933D01*
G01Y772017D02*
X254550Y772433D01*
X254967Y772767D01*
X255550Y772933D01*
X256133Y772767D01*
X256550Y772433D01*
X256800Y772017D01*
Y769600D01*
G01Y772017D02*
X257050Y772433D01*
X257467Y772767D01*
X258050Y772933D01*
X258633Y772767D01*
X259050Y772433D01*
X259300Y771933D01*
Y769600D01*
G01X263900D02*
Y772933D01*
G01Y772350D02*
X263567Y772683D01*
X263067Y772850D01*
X262483Y772933D01*
X261900Y772767D01*
X261400Y772433D01*
X261067Y771933D01*
X260900Y771267D01*
X261067Y770600D01*
X261400Y770100D01*
X261900Y769767D01*
X262483Y769600D01*
X263067Y769683D01*
X263567Y769933D01*
X263900Y770267D01*
G01X266583Y769600D02*
Y772933D01*
G01Y772100D02*
X266917Y772517D01*
X267417Y772850D01*
X268083Y772933D01*
X268667Y772850D01*
X269167Y772517D01*
X269417Y771933D01*
Y769600D01*
G01X274933Y772517D02*
X274350Y772850D01*
X273850Y772933D01*
X273183Y772767D01*
X272683Y772433D01*
X272350Y771850D01*
X272267Y771267D01*
X272350Y770683D01*
X272683Y770183D01*
X273183Y769767D01*
X273850Y769600D01*
X274433Y769767D01*
X274933Y770100D01*
G01X277950Y771850D02*
X280617D01*
X280367Y772433D01*
X279950Y772767D01*
X279367Y772933D01*
X278783Y772850D01*
X278283Y772600D01*
X277950Y772017D01*
X277783Y771517D01*
Y771017D01*
X277950Y770517D01*
X278367Y770017D01*
X278867Y769683D01*
X279450Y769600D01*
X280033Y769767D01*
X280617Y770267D01*
G01X288650D02*
X289317Y769850D01*
X290067Y769600D01*
X290733D01*
X291400Y769850D01*
X291900Y770267D01*
X292150Y770850D01*
X291983Y771433D01*
X291567Y771933D01*
X290817Y772267D01*
X289817Y772433D01*
X289233Y772767D01*
X288983Y773350D01*
X289150Y773933D01*
X289567Y774350D01*
X290150Y774600D01*
X290733D01*
X291317Y774433D01*
X291817Y774017D01*
G01X294500Y767933D02*
Y772933D01*
G01Y772183D02*
X294917Y772600D01*
X295333Y772850D01*
X296000Y772933D01*
X296583Y772850D01*
X297167Y772433D01*
X297417Y771850D01*
X297500Y771267D01*
X297417Y770683D01*
X297167Y770100D01*
X296667Y769767D01*
X296000Y769600D01*
X295417Y769683D01*
X294833Y769933D01*
X294500Y770267D01*
G01X300350Y771850D02*
X303017D01*
X302767Y772433D01*
X302350Y772767D01*
X301767Y772933D01*
X301183Y772850D01*
X300683Y772600D01*
X300350Y772017D01*
X300183Y771517D01*
Y771017D01*
X300350Y770517D01*
X300767Y770017D01*
X301267Y769683D01*
X301850Y769600D01*
X302433Y769767D01*
X303017Y770267D01*
G01X308533Y772517D02*
X307950Y772850D01*
X307450Y772933D01*
X306783Y772767D01*
X306283Y772433D01*
X305950Y771850D01*
X305867Y771267D01*
X305950Y770683D01*
X306283Y770183D01*
X306783Y769767D01*
X307450Y769600D01*
X308033Y769767D01*
X308533Y770100D01*
G01X312800Y772933D02*
Y769600D01*
G01Y774267D02*
X312633Y774350D01*
Y774517D01*
X312800Y774600D01*
X312967Y774517D01*
Y774350D01*
X312800Y774267D01*
G01X317900Y769600D02*
Y773850D01*
X318067Y774267D01*
X318400Y774517D01*
X318900Y774600D01*
X319400Y774433D01*
X319650Y774017D01*
G01X318650Y772600D02*
X316983D01*
G01X324000Y772933D02*
Y769600D01*
G01Y774267D02*
X323833Y774350D01*
Y774517D01*
X324000Y774600D01*
X324167Y774517D01*
Y774350D01*
X324000Y774267D01*
G01X330933Y772517D02*
X330350Y772850D01*
X329850Y772933D01*
X329183Y772767D01*
X328683Y772433D01*
X328350Y771850D01*
X328267Y771267D01*
X328350Y770683D01*
X328683Y770183D01*
X329183Y769767D01*
X329850Y769600D01*
X330433Y769767D01*
X330933Y770100D01*
G01X336700Y769600D02*
Y772933D01*
G01Y772350D02*
X336367Y772683D01*
X335867Y772850D01*
X335283Y772933D01*
X334700Y772767D01*
X334200Y772433D01*
X333867Y771933D01*
X333700Y771267D01*
X333867Y770600D01*
X334200Y770100D01*
X334700Y769767D01*
X335283Y769600D01*
X335867Y769683D01*
X336367Y769933D01*
X336700Y770267D01*
G01X340800Y774600D02*
Y769600D01*
G01X339633Y772933D02*
X341967D01*
G01X346400D02*
Y769600D01*
G01Y774267D02*
X346233Y774350D01*
Y774517D01*
X346400Y774600D01*
X346567Y774517D01*
Y774350D01*
X346400Y774267D01*
G01X352000Y769600D02*
X351500Y769683D01*
X351000Y770017D01*
X350667Y770600D01*
X350500Y771267D01*
X350667Y771933D01*
X351000Y772517D01*
X351500Y772850D01*
X352000Y772933D01*
X352500Y772850D01*
X353000Y772517D01*
X353333Y771933D01*
X353417Y771267D01*
X353333Y770600D01*
X353000Y770017D01*
X352500Y769683D01*
X352000Y769600D01*
G01X356183D02*
Y772933D01*
G01Y772100D02*
X356517Y772517D01*
X357017Y772850D01*
X357683Y772933D01*
X358267Y772850D01*
X358767Y772517D01*
X359017Y771933D01*
Y769600D01*
G01X368300D02*
Y773850D01*
X368467Y774267D01*
X368800Y774517D01*
X369300Y774600D01*
X369800Y774433D01*
X370050Y774017D01*
G01X369050Y772600D02*
X367383D01*
G01X374400Y769600D02*
X373900Y769683D01*
X373400Y770017D01*
X373067Y770600D01*
X372900Y771267D01*
X373067Y771933D01*
X373400Y772517D01*
X373900Y772850D01*
X374400Y772933D01*
X374900Y772850D01*
X375400Y772517D01*
X375733Y771933D01*
X375817Y771267D01*
X375733Y770600D01*
X375400Y770017D01*
X374900Y769683D01*
X374400Y769600D01*
G01X378833D02*
Y772933D01*
G01Y772267D02*
X379250Y772600D01*
X379667Y772850D01*
X380250Y772933D01*
X380667Y772850D01*
X381167Y772600D01*
G01X389533Y769600D02*
Y774600D01*
X391617D01*
X392283Y774350D01*
X392700Y774017D01*
X392867Y773350D01*
X392700Y772683D01*
X392200Y772267D01*
X391617Y772017D01*
X389533D01*
G01X391617D02*
X392867Y769600D01*
G01X396800Y772933D02*
Y769600D01*
G01Y774267D02*
X396633Y774350D01*
Y774517D01*
X396800Y774600D01*
X396967Y774517D01*
Y774350D01*
X396800Y774267D01*
G01X401233Y768350D02*
X401817Y768017D01*
X402483Y767933D01*
X403067Y768017D01*
X403567Y768433D01*
X403900Y769017D01*
Y772933D01*
G01Y772267D02*
X403567Y772600D01*
X403067Y772850D01*
X402483Y772933D01*
X401817Y772767D01*
X401400Y772433D01*
X401067Y771850D01*
X400900Y771267D01*
X400983Y770767D01*
X401317Y770183D01*
X401817Y769767D01*
X402483Y769600D01*
X402983Y769683D01*
X403567Y770017D01*
X403900Y770350D01*
G01X408000Y772933D02*
Y769600D01*
G01Y774267D02*
X407833Y774350D01*
Y774517D01*
X408000Y774600D01*
X408167Y774517D01*
Y774350D01*
X408000Y774267D01*
G01X415100Y774600D02*
Y769600D01*
G01Y770350D02*
X414767Y769933D01*
X414267Y769683D01*
X413683Y769600D01*
X413017Y769767D01*
X412517Y770183D01*
X412183Y770683D01*
X412100Y771267D01*
X412183Y771850D01*
X412517Y772350D01*
X413017Y772767D01*
X413683Y772933D01*
X414267Y772850D01*
X414683Y772683D01*
X415100Y772350D01*
G01X423133Y769600D02*
Y774600D01*
X425133D01*
X425800Y774350D01*
X426300Y773767D01*
X426467Y773100D01*
X426300Y772433D01*
X425883Y771933D01*
X425133Y771683D01*
X423133D01*
G01X429233Y769600D02*
Y772933D01*
G01Y772267D02*
X429650Y772600D01*
X430067Y772850D01*
X430650Y772933D01*
X431067Y772850D01*
X431567Y772600D01*
G01X436000Y772933D02*
Y769600D01*
G01Y774267D02*
X435833Y774350D01*
Y774517D01*
X436000Y774600D01*
X436167Y774517D01*
Y774350D01*
X436000Y774267D01*
G01X440183Y769600D02*
Y772933D01*
G01Y772100D02*
X440517Y772517D01*
X441017Y772850D01*
X441683Y772933D01*
X442267Y772850D01*
X442767Y772517D01*
X443017Y771933D01*
Y769600D01*
G01X447200Y774600D02*
Y769600D01*
G01X446033Y772933D02*
X448367D01*
G01X451550Y771850D02*
X454217D01*
X453967Y772433D01*
X453550Y772767D01*
X452967Y772933D01*
X452383Y772850D01*
X451883Y772600D01*
X451550Y772017D01*
X451383Y771517D01*
Y771017D01*
X451550Y770517D01*
X451967Y770017D01*
X452467Y769683D01*
X453050Y769600D01*
X453633Y769767D01*
X454217Y770267D01*
G01X459900Y774600D02*
Y769600D01*
G01Y770350D02*
X459567Y769933D01*
X459067Y769683D01*
X458483Y769600D01*
X457817Y769767D01*
X457317Y770183D01*
X456983Y770683D01*
X456900Y771267D01*
X456983Y771850D01*
X457317Y772350D01*
X457817Y772767D01*
X458483Y772933D01*
X459067Y772850D01*
X459483Y772683D01*
X459900Y772350D01*
G01X470267Y772267D02*
X470600Y772517D01*
X470850Y772933D01*
X471017Y773517D01*
X470850Y774017D01*
X470517Y774350D01*
X469933Y774600D01*
X467683D01*
Y769600D01*
X470433D01*
X471017Y769933D01*
X471350Y770433D01*
X471517Y771017D01*
X471350Y771600D01*
X470850Y772100D01*
X470267Y772267D01*
X467683D01*
G01X475200Y769600D02*
X474700Y769683D01*
X474200Y770017D01*
X473867Y770600D01*
X473700Y771267D01*
X473867Y771933D01*
X474200Y772517D01*
X474700Y772850D01*
X475200Y772933D01*
X475700Y772850D01*
X476200Y772517D01*
X476533Y771933D01*
X476617Y771267D01*
X476533Y770600D01*
X476200Y770017D01*
X475700Y769683D01*
X475200Y769600D01*
G01X482300D02*
Y772933D01*
G01Y772350D02*
X481967Y772683D01*
X481467Y772850D01*
X480883Y772933D01*
X480300Y772767D01*
X479800Y772433D01*
X479467Y771933D01*
X479300Y771267D01*
X479467Y770600D01*
X479800Y770100D01*
X480300Y769767D01*
X480883Y769600D01*
X481467Y769683D01*
X481967Y769933D01*
X482300Y770267D01*
G01X485233Y769600D02*
Y772933D01*
G01Y772267D02*
X485650Y772600D01*
X486067Y772850D01*
X486650Y772933D01*
X487067Y772850D01*
X487567Y772600D01*
G01X493500Y774600D02*
Y769600D01*
G01Y770350D02*
X493167Y769933D01*
X492667Y769683D01*
X492083Y769600D01*
X491417Y769767D01*
X490917Y770183D01*
X490583Y770683D01*
X490500Y771267D01*
X490583Y771850D01*
X490917Y772350D01*
X491417Y772767D01*
X492083Y772933D01*
X492667Y772850D01*
X493083Y772683D01*
X493500Y772350D01*
G01X496350Y770183D02*
X496767Y769850D01*
X497350Y769600D01*
X497850D01*
X498350Y769767D01*
X498683Y770017D01*
X498850Y770350D01*
X498767Y770850D01*
X498433Y771100D01*
X496933Y771600D01*
X496600Y772183D01*
X496767Y772600D01*
X497100Y772850D01*
X497600Y772933D01*
X498100Y772850D01*
X498600Y772600D01*
G01X67000Y779433D02*
X66833Y779517D01*
Y779683D01*
X67000Y779767D01*
X67167Y779683D01*
Y779517D01*
X67000Y779433D01*
G01Y786333D02*
X66833Y786417D01*
Y786583D01*
X67000Y786667D01*
X67167Y786583D01*
Y786417D01*
X67000Y786333D01*
G01X71000Y783600D02*
X73000D01*
G01X72000D02*
Y778600D01*
G01X71000D02*
X73000D01*
G01X75933D02*
Y783600D01*
X77933D01*
X78600Y783350D01*
X79100Y782767D01*
X79267Y782100D01*
X79100Y781433D01*
X78683Y780933D01*
X77933Y780683D01*
X75933D01*
G01X85033Y783183D02*
X84533Y783433D01*
X83950Y783600D01*
X83283D01*
X82533Y783350D01*
X81950Y782933D01*
X81533Y782433D01*
X81200Y781600D01*
X81117Y780850D01*
X81283Y780100D01*
X81533Y779600D01*
X82033Y779100D01*
X82617Y778767D01*
X83200Y778600D01*
X83783D01*
X84367Y778767D01*
X84867Y779017D01*
X85283Y779350D01*
G01X87717Y780267D02*
X89883D01*
G01X92817Y780683D02*
X93400Y781267D01*
X93900Y781600D01*
X94567Y781767D01*
X95150Y781600D01*
X95567Y781267D01*
X95900Y780767D01*
X95983Y780183D01*
X95900Y779683D01*
X95567Y779183D01*
X95067Y778767D01*
X94483Y778600D01*
X93817Y778767D01*
X93233Y779267D01*
X92900Y780017D01*
X92817Y780850D01*
X92983Y781933D01*
X93233Y782517D01*
X93650Y783100D01*
X94233Y783517D01*
X94817Y783600D01*
X95400Y783433D01*
X95817Y783017D01*
G01X100000Y783600D02*
X99333Y783433D01*
X98833Y783017D01*
X98500Y782517D01*
X98250Y781850D01*
X98167Y781100D01*
X98250Y780350D01*
X98500Y779683D01*
X98833Y779183D01*
X99333Y778767D01*
X100000Y778600D01*
X100667Y778767D01*
X101167Y779183D01*
X101500Y779683D01*
X101750Y780350D01*
X101833Y781100D01*
X101750Y781850D01*
X101500Y782517D01*
X101167Y783017D01*
X100667Y783433D01*
X100000Y783600D01*
G01X105600Y778600D02*
Y783600D01*
X104600Y782600D01*
G01Y778600D02*
X106600D01*
G01X111200D02*
Y783600D01*
X110200Y782600D01*
G01Y778600D02*
X112200D01*
G01X122900Y781100D02*
X124567D01*
Y779600D01*
X124067Y779100D01*
X123483Y778767D01*
X122650Y778600D01*
X121817Y778767D01*
X121233Y779100D01*
X120733Y779600D01*
X120400Y780183D01*
X120233Y780850D01*
Y781433D01*
X120400Y781933D01*
X120733Y782517D01*
X121233Y783017D01*
X121733Y783350D01*
X122400Y783600D01*
X122983D01*
X123650Y783433D01*
X124150Y783100D01*
G01X126750Y780850D02*
X129417D01*
X129167Y781433D01*
X128750Y781767D01*
X128167Y781933D01*
X127583Y781850D01*
X127083Y781600D01*
X126750Y781017D01*
X126583Y780517D01*
Y780017D01*
X126750Y779517D01*
X127167Y779017D01*
X127667Y778683D01*
X128250Y778600D01*
X128833Y778767D01*
X129417Y779267D01*
G01X132183Y778600D02*
Y781933D01*
G01Y781100D02*
X132517Y781517D01*
X133017Y781850D01*
X133683Y781933D01*
X134267Y781850D01*
X134767Y781517D01*
X135017Y780933D01*
Y778600D01*
G01X137950Y780850D02*
X140617D01*
X140367Y781433D01*
X139950Y781767D01*
X139367Y781933D01*
X138783Y781850D01*
X138283Y781600D01*
X137950Y781017D01*
X137783Y780517D01*
Y780017D01*
X137950Y779517D01*
X138367Y779017D01*
X138867Y778683D01*
X139450Y778600D01*
X140033Y778767D01*
X140617Y779267D01*
G01X143633Y778600D02*
Y781933D01*
G01Y781267D02*
X144050Y781600D01*
X144467Y781850D01*
X145050Y781933D01*
X145467Y781850D01*
X145967Y781600D01*
G01X150400Y781933D02*
Y778600D01*
G01Y783267D02*
X150233Y783350D01*
Y783517D01*
X150400Y783600D01*
X150567Y783517D01*
Y783350D01*
X150400Y783267D01*
G01X157333Y781517D02*
X156750Y781850D01*
X156250Y781933D01*
X155583Y781767D01*
X155083Y781433D01*
X154750Y780850D01*
X154667Y780267D01*
X154750Y779683D01*
X155083Y779183D01*
X155583Y778767D01*
X156250Y778600D01*
X156833Y778767D01*
X157333Y779100D01*
G01X165533Y778600D02*
Y783600D01*
X167533D01*
X168200Y783350D01*
X168700Y782767D01*
X168867Y782100D01*
X168700Y781433D01*
X168283Y780933D01*
X167533Y780683D01*
X165533D01*
G01X171550Y780850D02*
X174217D01*
X173967Y781433D01*
X173550Y781767D01*
X172967Y781933D01*
X172383Y781850D01*
X171883Y781600D01*
X171550Y781017D01*
X171383Y780517D01*
Y780017D01*
X171550Y779517D01*
X171967Y779017D01*
X172467Y778683D01*
X173050Y778600D01*
X173633Y778767D01*
X174217Y779267D01*
G01X177233Y778600D02*
Y781933D01*
G01Y781267D02*
X177650Y781600D01*
X178067Y781850D01*
X178650Y781933D01*
X179067Y781850D01*
X179567Y781600D01*
G01X183500Y778600D02*
Y782850D01*
X183667Y783267D01*
X184000Y783517D01*
X184500Y783600D01*
X185000Y783433D01*
X185250Y783017D01*
G01X184250Y781600D02*
X182583D01*
G01X189600Y778600D02*
X189100Y778683D01*
X188600Y779017D01*
X188267Y779600D01*
X188100Y780267D01*
X188267Y780933D01*
X188600Y781517D01*
X189100Y781850D01*
X189600Y781933D01*
X190100Y781850D01*
X190600Y781517D01*
X190933Y780933D01*
X191017Y780267D01*
X190933Y779600D01*
X190600Y779017D01*
X190100Y778683D01*
X189600Y778600D01*
G01X194033D02*
Y781933D01*
G01Y781267D02*
X194450Y781600D01*
X194867Y781850D01*
X195450Y781933D01*
X195867Y781850D01*
X196367Y781600D01*
G01X198300Y778600D02*
Y781933D01*
G01Y781017D02*
X198550Y781433D01*
X198967Y781767D01*
X199550Y781933D01*
X200133Y781767D01*
X200550Y781433D01*
X200800Y781017D01*
Y778600D01*
G01Y781017D02*
X201050Y781433D01*
X201467Y781767D01*
X202050Y781933D01*
X202633Y781767D01*
X203050Y781433D01*
X203300Y780933D01*
Y778600D01*
G01X207900D02*
Y781933D01*
G01Y781350D02*
X207567Y781683D01*
X207067Y781850D01*
X206483Y781933D01*
X205900Y781767D01*
X205400Y781433D01*
X205067Y780933D01*
X204900Y780267D01*
X205067Y779600D01*
X205400Y779100D01*
X205900Y778767D01*
X206483Y778600D01*
X207067Y778683D01*
X207567Y778933D01*
X207900Y779267D01*
G01X210583Y778600D02*
Y781933D01*
G01Y781100D02*
X210917Y781517D01*
X211417Y781850D01*
X212083Y781933D01*
X212667Y781850D01*
X213167Y781517D01*
X213417Y780933D01*
Y778600D01*
G01X218933Y781517D02*
X218350Y781850D01*
X217850Y781933D01*
X217183Y781767D01*
X216683Y781433D01*
X216350Y780850D01*
X216267Y780267D01*
X216350Y779683D01*
X216683Y779183D01*
X217183Y778767D01*
X217850Y778600D01*
X218433Y778767D01*
X218933Y779100D01*
G01X221950Y780850D02*
X224617D01*
X224367Y781433D01*
X223950Y781767D01*
X223367Y781933D01*
X222783Y781850D01*
X222283Y781600D01*
X221950Y781017D01*
X221783Y780517D01*
Y780017D01*
X221950Y779517D01*
X222367Y779017D01*
X222867Y778683D01*
X223450Y778600D01*
X224033Y778767D01*
X224617Y779267D01*
G01X232650D02*
X233317Y778850D01*
X234067Y778600D01*
X234733D01*
X235400Y778850D01*
X235900Y779267D01*
X236150Y779850D01*
X235983Y780433D01*
X235567Y780933D01*
X234817Y781267D01*
X233817Y781433D01*
X233233Y781767D01*
X232983Y782350D01*
X233150Y782933D01*
X233567Y783350D01*
X234150Y783600D01*
X234733D01*
X235317Y783433D01*
X235817Y783017D01*
G01X238500Y776933D02*
Y781933D01*
G01Y781183D02*
X238917Y781600D01*
X239333Y781850D01*
X240000Y781933D01*
X240583Y781850D01*
X241167Y781433D01*
X241417Y780850D01*
X241500Y780267D01*
X241417Y779683D01*
X241167Y779100D01*
X240667Y778767D01*
X240000Y778600D01*
X239417Y778683D01*
X238833Y778933D01*
X238500Y779267D01*
G01X244350Y780850D02*
X247017D01*
X246767Y781433D01*
X246350Y781767D01*
X245767Y781933D01*
X245183Y781850D01*
X244683Y781600D01*
X244350Y781017D01*
X244183Y780517D01*
Y780017D01*
X244350Y779517D01*
X244767Y779017D01*
X245267Y778683D01*
X245850Y778600D01*
X246433Y778767D01*
X247017Y779267D01*
G01X252533Y781517D02*
X251950Y781850D01*
X251450Y781933D01*
X250783Y781767D01*
X250283Y781433D01*
X249950Y780850D01*
X249867Y780267D01*
X249950Y779683D01*
X250283Y779183D01*
X250783Y778767D01*
X251450Y778600D01*
X252033Y778767D01*
X252533Y779100D01*
G01X256800Y781933D02*
Y778600D01*
G01Y783267D02*
X256633Y783350D01*
Y783517D01*
X256800Y783600D01*
X256967Y783517D01*
Y783350D01*
X256800Y783267D01*
G01X261900Y778600D02*
Y782850D01*
X262067Y783267D01*
X262400Y783517D01*
X262900Y783600D01*
X263400Y783433D01*
X263650Y783017D01*
G01X262650Y781600D02*
X260983D01*
G01X268000Y781933D02*
Y778600D01*
G01Y783267D02*
X267833Y783350D01*
Y783517D01*
X268000Y783600D01*
X268167Y783517D01*
Y783350D01*
X268000Y783267D01*
G01X274933Y781517D02*
X274350Y781850D01*
X273850Y781933D01*
X273183Y781767D01*
X272683Y781433D01*
X272350Y780850D01*
X272267Y780267D01*
X272350Y779683D01*
X272683Y779183D01*
X273183Y778767D01*
X273850Y778600D01*
X274433Y778767D01*
X274933Y779100D01*
G01X280700Y778600D02*
Y781933D01*
G01Y781350D02*
X280367Y781683D01*
X279867Y781850D01*
X279283Y781933D01*
X278700Y781767D01*
X278200Y781433D01*
X277867Y780933D01*
X277700Y780267D01*
X277867Y779600D01*
X278200Y779100D01*
X278700Y778767D01*
X279283Y778600D01*
X279867Y778683D01*
X280367Y778933D01*
X280700Y779267D01*
G01X284800Y783600D02*
Y778600D01*
G01X283633Y781933D02*
X285967D01*
G01X290400D02*
Y778600D01*
G01Y783267D02*
X290233Y783350D01*
Y783517D01*
X290400Y783600D01*
X290567Y783517D01*
Y783350D01*
X290400Y783267D01*
G01X296000Y778600D02*
X295500Y778683D01*
X295000Y779017D01*
X294667Y779600D01*
X294500Y780267D01*
X294667Y780933D01*
X295000Y781517D01*
X295500Y781850D01*
X296000Y781933D01*
X296500Y781850D01*
X297000Y781517D01*
X297333Y780933D01*
X297417Y780267D01*
X297333Y779600D01*
X297000Y779017D01*
X296500Y778683D01*
X296000Y778600D01*
G01X300183D02*
Y781933D01*
G01Y781100D02*
X300517Y781517D01*
X301017Y781850D01*
X301683Y781933D01*
X302267Y781850D01*
X302767Y781517D01*
X303017Y780933D01*
Y778600D01*
G01X312300D02*
Y782850D01*
X312467Y783267D01*
X312800Y783517D01*
X313300Y783600D01*
X313800Y783433D01*
X314050Y783017D01*
G01X313050Y781600D02*
X311383D01*
G01X318400Y778600D02*
X317900Y778683D01*
X317400Y779017D01*
X317067Y779600D01*
X316900Y780267D01*
X317067Y780933D01*
X317400Y781517D01*
X317900Y781850D01*
X318400Y781933D01*
X318900Y781850D01*
X319400Y781517D01*
X319733Y780933D01*
X319817Y780267D01*
X319733Y779600D01*
X319400Y779017D01*
X318900Y778683D01*
X318400Y778600D01*
G01X322833D02*
Y781933D01*
G01Y781267D02*
X323250Y781600D01*
X323667Y781850D01*
X324250Y781933D01*
X324667Y781850D01*
X325167Y781600D01*
G01X333533Y778600D02*
Y783600D01*
X335533D01*
X336200Y783350D01*
X336700Y782767D01*
X336867Y782100D01*
X336700Y781433D01*
X336283Y780933D01*
X335533Y780683D01*
X333533D01*
G01X339633Y778600D02*
Y781933D01*
G01Y781267D02*
X340050Y781600D01*
X340467Y781850D01*
X341050Y781933D01*
X341467Y781850D01*
X341967Y781600D01*
G01X346400Y781933D02*
Y778600D01*
G01Y783267D02*
X346233Y783350D01*
Y783517D01*
X346400Y783600D01*
X346567Y783517D01*
Y783350D01*
X346400Y783267D01*
G01X350583Y778600D02*
Y781933D01*
G01Y781100D02*
X350917Y781517D01*
X351417Y781850D01*
X352083Y781933D01*
X352667Y781850D01*
X353167Y781517D01*
X353417Y780933D01*
Y778600D01*
G01X357600Y783600D02*
Y778600D01*
G01X356433Y781933D02*
X358767D01*
G01X361950Y780850D02*
X364617D01*
X364367Y781433D01*
X363950Y781767D01*
X363367Y781933D01*
X362783Y781850D01*
X362283Y781600D01*
X361950Y781017D01*
X361783Y780517D01*
Y780017D01*
X361950Y779517D01*
X362367Y779017D01*
X362867Y778683D01*
X363450Y778600D01*
X364033Y778767D01*
X364617Y779267D01*
G01X370300Y783600D02*
Y778600D01*
G01Y779350D02*
X369967Y778933D01*
X369467Y778683D01*
X368883Y778600D01*
X368217Y778767D01*
X367717Y779183D01*
X367383Y779683D01*
X367300Y780267D01*
X367383Y780850D01*
X367717Y781350D01*
X368217Y781767D01*
X368883Y781933D01*
X369467Y781850D01*
X369883Y781683D01*
X370300Y781350D01*
G01X380667Y781267D02*
X381000Y781517D01*
X381250Y781933D01*
X381417Y782517D01*
X381250Y783017D01*
X380917Y783350D01*
X380333Y783600D01*
X378083D01*
Y778600D01*
X380833D01*
X381417Y778933D01*
X381750Y779433D01*
X381917Y780017D01*
X381750Y780600D01*
X381250Y781100D01*
X380667Y781267D01*
X378083D01*
G01X385600Y778600D02*
X385100Y778683D01*
X384600Y779017D01*
X384267Y779600D01*
X384100Y780267D01*
X384267Y780933D01*
X384600Y781517D01*
X385100Y781850D01*
X385600Y781933D01*
X386100Y781850D01*
X386600Y781517D01*
X386933Y780933D01*
X387017Y780267D01*
X386933Y779600D01*
X386600Y779017D01*
X386100Y778683D01*
X385600Y778600D01*
G01X392700D02*
Y781933D01*
G01Y781350D02*
X392367Y781683D01*
X391867Y781850D01*
X391283Y781933D01*
X390700Y781767D01*
X390200Y781433D01*
X389867Y780933D01*
X389700Y780267D01*
X389867Y779600D01*
X390200Y779100D01*
X390700Y778767D01*
X391283Y778600D01*
X391867Y778683D01*
X392367Y778933D01*
X392700Y779267D01*
G01X395633Y778600D02*
Y781933D01*
G01Y781267D02*
X396050Y781600D01*
X396467Y781850D01*
X397050Y781933D01*
X397467Y781850D01*
X397967Y781600D01*
G01X403900Y783600D02*
Y778600D01*
G01Y779350D02*
X403567Y778933D01*
X403067Y778683D01*
X402483Y778600D01*
X401817Y778767D01*
X401317Y779183D01*
X400983Y779683D01*
X400900Y780267D01*
X400983Y780850D01*
X401317Y781350D01*
X401817Y781767D01*
X402483Y781933D01*
X403067Y781850D01*
X403483Y781683D01*
X403900Y781350D01*
G01X406750Y779183D02*
X407167Y778850D01*
X407750Y778600D01*
X408250D01*
X408750Y778767D01*
X409083Y779017D01*
X409250Y779350D01*
X409167Y779850D01*
X408833Y780100D01*
X407333Y780600D01*
X407000Y781183D01*
X407167Y781600D01*
X407500Y781850D01*
X408000Y781933D01*
X408500Y781850D01*
X409000Y781600D01*
G01X71000Y791500D02*
X73000D01*
G01X72000D02*
Y786500D01*
G01X71000D02*
X73000D01*
G01X75933D02*
Y791500D01*
X77933D01*
X78600Y791250D01*
X79100Y790667D01*
X79267Y790000D01*
X79100Y789333D01*
X78683Y788833D01*
X77933Y788583D01*
X75933D01*
G01X85033Y791083D02*
X84533Y791333D01*
X83950Y791500D01*
X83283D01*
X82533Y791250D01*
X81950Y790833D01*
X81533Y790333D01*
X81200Y789500D01*
X81117Y788750D01*
X81283Y788000D01*
X81533Y787500D01*
X82033Y787000D01*
X82617Y786667D01*
X83200Y786500D01*
X83783D01*
X84367Y786667D01*
X84867Y786917D01*
X85283Y787250D01*
G01X87717Y788167D02*
X89883D01*
G01X92317Y786500D02*
X94400Y791500D01*
X96483Y786500D01*
G01X95733Y788250D02*
X93067D01*
G01X98917Y788167D02*
X101083D01*
G01X104017Y788583D02*
X104600Y789167D01*
X105100Y789500D01*
X105767Y789667D01*
X106350Y789500D01*
X106767Y789167D01*
X107100Y788667D01*
X107183Y788083D01*
X107100Y787583D01*
X106767Y787083D01*
X106267Y786667D01*
X105683Y786500D01*
X105017Y786667D01*
X104433Y787167D01*
X104100Y787917D01*
X104017Y788750D01*
X104183Y789833D01*
X104433Y790417D01*
X104850Y791000D01*
X105433Y791417D01*
X106017Y791500D01*
X106600Y791333D01*
X107017Y790917D01*
G01X111200Y791500D02*
X110533Y791333D01*
X110033Y790917D01*
X109700Y790417D01*
X109450Y789750D01*
X109367Y789000D01*
X109450Y788250D01*
X109700Y787583D01*
X110033Y787083D01*
X110533Y786667D01*
X111200Y786500D01*
X111867Y786667D01*
X112367Y787083D01*
X112700Y787583D01*
X112950Y788250D01*
X113033Y789000D01*
X112950Y789750D01*
X112700Y790417D01*
X112367Y790917D01*
X111867Y791333D01*
X111200Y791500D01*
G01X116800D02*
X116133Y791333D01*
X115633Y790917D01*
X115300Y790417D01*
X115050Y789750D01*
X114967Y789000D01*
X115050Y788250D01*
X115300Y787583D01*
X115633Y787083D01*
X116133Y786667D01*
X116800Y786500D01*
X117467Y786667D01*
X117967Y787083D01*
X118300Y787583D01*
X118550Y788250D01*
X118633Y789000D01*
X118550Y789750D01*
X118300Y790417D01*
X117967Y790917D01*
X117467Y791333D01*
X116800Y791500D01*
G01X125917Y786500D02*
X128000Y791500D01*
X130083Y786500D01*
G01X129333Y788250D02*
X126667D01*
G01X134933Y789417D02*
X134350Y789750D01*
X133850Y789833D01*
X133183Y789667D01*
X132683Y789333D01*
X132350Y788750D01*
X132267Y788167D01*
X132350Y787583D01*
X132683Y787083D01*
X133183Y786667D01*
X133850Y786500D01*
X134433Y786667D01*
X134933Y787000D01*
G01X140533Y789417D02*
X139950Y789750D01*
X139450Y789833D01*
X138783Y789667D01*
X138283Y789333D01*
X137950Y788750D01*
X137867Y788167D01*
X137950Y787583D01*
X138283Y787083D01*
X138783Y786667D01*
X139450Y786500D01*
X140033Y786667D01*
X140533Y787000D01*
G01X143550Y788750D02*
X146217D01*
X145967Y789333D01*
X145550Y789667D01*
X144967Y789833D01*
X144383Y789750D01*
X143883Y789500D01*
X143550Y788917D01*
X143383Y788417D01*
Y787917D01*
X143550Y787417D01*
X143967Y786917D01*
X144467Y786583D01*
X145050Y786500D01*
X145633Y786667D01*
X146217Y787167D01*
G01X148900Y784833D02*
Y789833D01*
G01Y789083D02*
X149317Y789500D01*
X149733Y789750D01*
X150400Y789833D01*
X150983Y789750D01*
X151567Y789333D01*
X151817Y788750D01*
X151900Y788167D01*
X151817Y787583D01*
X151567Y787000D01*
X151067Y786667D01*
X150400Y786500D01*
X149817Y786583D01*
X149233Y786833D01*
X148900Y787167D01*
G01X156000Y791500D02*
Y786500D01*
G01X154833Y789833D02*
X157167D01*
G01X163100Y786500D02*
Y789833D01*
G01Y789250D02*
X162767Y789583D01*
X162267Y789750D01*
X161683Y789833D01*
X161100Y789667D01*
X160600Y789333D01*
X160267Y788833D01*
X160100Y788167D01*
X160267Y787500D01*
X160600Y787000D01*
X161100Y786667D01*
X161683Y786500D01*
X162267Y786583D01*
X162767Y786833D01*
X163100Y787167D01*
G01X165700Y786500D02*
Y791500D01*
G01Y789000D02*
X166117Y789500D01*
X166617Y789750D01*
X167117Y789833D01*
X167867Y789667D01*
X168367Y789333D01*
X168700Y788750D01*
Y788083D01*
X168533Y787417D01*
X168200Y786917D01*
X167617Y786583D01*
X167117Y786500D01*
X166617Y786583D01*
X166117Y786833D01*
X165700Y787250D01*
G01X172800Y789833D02*
Y786500D01*
G01Y791167D02*
X172633Y791250D01*
Y791417D01*
X172800Y791500D01*
X172967Y791417D01*
Y791250D01*
X172800Y791167D01*
G01X178400Y786500D02*
Y791500D01*
G01X184000Y789833D02*
Y786500D01*
G01Y791167D02*
X183833Y791250D01*
Y791417D01*
X184000Y791500D01*
X184167Y791417D01*
Y791250D01*
X184000Y791167D01*
G01X189600Y791500D02*
Y786500D01*
G01X188433Y789833D02*
X190767D01*
G01X193450Y785000D02*
X193950Y784833D01*
X194617Y785000D01*
X195033Y785333D01*
X195367Y785750D01*
X195867Y787083D01*
X196950Y789833D01*
G01X194283D02*
X195867Y787083D01*
G01X206400Y786500D02*
X205900Y786583D01*
X205400Y786917D01*
X205067Y787500D01*
X204900Y788167D01*
X205067Y788833D01*
X205400Y789417D01*
X205900Y789750D01*
X206400Y789833D01*
X206900Y789750D01*
X207400Y789417D01*
X207733Y788833D01*
X207817Y788167D01*
X207733Y787500D01*
X207400Y786917D01*
X206900Y786583D01*
X206400Y786500D01*
G01X211500D02*
Y790750D01*
X211667Y791167D01*
X212000Y791417D01*
X212500Y791500D01*
X213000Y791333D01*
X213250Y790917D01*
G01X212250Y789500D02*
X210583D01*
G01X221533Y786500D02*
Y791500D01*
X223533D01*
X224200Y791250D01*
X224700Y790667D01*
X224867Y790000D01*
X224700Y789333D01*
X224283Y788833D01*
X223533Y788583D01*
X221533D01*
G01X227633Y786500D02*
Y789833D01*
G01Y789167D02*
X228050Y789500D01*
X228467Y789750D01*
X229050Y789833D01*
X229467Y789750D01*
X229967Y789500D01*
G01X234400Y789833D02*
Y786500D01*
G01Y791167D02*
X234233Y791250D01*
Y791417D01*
X234400Y791500D01*
X234567Y791417D01*
Y791250D01*
X234400Y791167D01*
G01X238583Y786500D02*
Y789833D01*
G01Y789000D02*
X238917Y789417D01*
X239417Y789750D01*
X240083Y789833D01*
X240667Y789750D01*
X241167Y789417D01*
X241417Y788833D01*
Y786500D01*
G01X245600Y791500D02*
Y786500D01*
G01X244433Y789833D02*
X246767D01*
G01X249950Y788750D02*
X252617D01*
X252367Y789333D01*
X251950Y789667D01*
X251367Y789833D01*
X250783Y789750D01*
X250283Y789500D01*
X249950Y788917D01*
X249783Y788417D01*
Y787917D01*
X249950Y787417D01*
X250367Y786917D01*
X250867Y786583D01*
X251450Y786500D01*
X252033Y786667D01*
X252617Y787167D01*
G01X258300Y791500D02*
Y786500D01*
G01Y787250D02*
X257967Y786833D01*
X257467Y786583D01*
X256883Y786500D01*
X256217Y786667D01*
X255717Y787083D01*
X255383Y787583D01*
X255300Y788167D01*
X255383Y788750D01*
X255717Y789250D01*
X256217Y789667D01*
X256883Y789833D01*
X257467Y789750D01*
X257883Y789583D01*
X258300Y789250D01*
G01X268667Y789167D02*
X269000Y789417D01*
X269250Y789833D01*
X269417Y790417D01*
X269250Y790917D01*
X268917Y791250D01*
X268333Y791500D01*
X266083D01*
Y786500D01*
X268833D01*
X269417Y786833D01*
X269750Y787333D01*
X269917Y787917D01*
X269750Y788500D01*
X269250Y789000D01*
X268667Y789167D01*
X266083D01*
G01X273600Y786500D02*
X273100Y786583D01*
X272600Y786917D01*
X272267Y787500D01*
X272100Y788167D01*
X272267Y788833D01*
X272600Y789417D01*
X273100Y789750D01*
X273600Y789833D01*
X274100Y789750D01*
X274600Y789417D01*
X274933Y788833D01*
X275017Y788167D01*
X274933Y787500D01*
X274600Y786917D01*
X274100Y786583D01*
X273600Y786500D01*
G01X280700D02*
Y789833D01*
G01Y789250D02*
X280367Y789583D01*
X279867Y789750D01*
X279283Y789833D01*
X278700Y789667D01*
X278200Y789333D01*
X277867Y788833D01*
X277700Y788167D01*
X277867Y787500D01*
X278200Y787000D01*
X278700Y786667D01*
X279283Y786500D01*
X279867Y786583D01*
X280367Y786833D01*
X280700Y787167D01*
G01X283633Y786500D02*
Y789833D01*
G01Y789167D02*
X284050Y789500D01*
X284467Y789750D01*
X285050Y789833D01*
X285467Y789750D01*
X285967Y789500D01*
G01X291900Y791500D02*
Y786500D01*
G01Y787250D02*
X291567Y786833D01*
X291067Y786583D01*
X290483Y786500D01*
X289817Y786667D01*
X289317Y787083D01*
X288983Y787583D01*
X288900Y788167D01*
X288983Y788750D01*
X289317Y789250D01*
X289817Y789667D01*
X290483Y789833D01*
X291067Y789750D01*
X291483Y789583D01*
X291900Y789250D01*
G01X294750Y787083D02*
X295167Y786750D01*
X295750Y786500D01*
X296250D01*
X296750Y786667D01*
X297083Y786917D01*
X297250Y787250D01*
X297167Y787750D01*
X296833Y788000D01*
X295333Y788500D01*
X295000Y789083D01*
X295167Y789500D01*
X295500Y789750D01*
X296000Y789833D01*
X296500Y789750D01*
X297000Y789500D01*
G01X57833Y806500D02*
Y811500D01*
X59833D01*
X60500Y811250D01*
X61000Y810667D01*
X61167Y810000D01*
X61000Y809333D01*
X60583Y808833D01*
X59833Y808583D01*
X57833D01*
G01X65100Y806500D02*
Y811500D01*
G01X69450Y808750D02*
X72117D01*
X71867Y809333D01*
X71450Y809667D01*
X70867Y809833D01*
X70283Y809750D01*
X69783Y809500D01*
X69450Y808917D01*
X69283Y808417D01*
Y807917D01*
X69450Y807417D01*
X69867Y806917D01*
X70367Y806583D01*
X70950Y806500D01*
X71533Y806667D01*
X72117Y807167D01*
G01X77800Y806500D02*
Y809833D01*
G01Y809250D02*
X77467Y809583D01*
X76967Y809750D01*
X76383Y809833D01*
X75800Y809667D01*
X75300Y809333D01*
X74967Y808833D01*
X74800Y808167D01*
X74967Y807500D01*
X75300Y807000D01*
X75800Y806667D01*
X76383Y806500D01*
X76967Y806583D01*
X77467Y806833D01*
X77800Y807167D01*
G01X80650Y807083D02*
X81067Y806750D01*
X81650Y806500D01*
X82150D01*
X82650Y806667D01*
X82983Y806917D01*
X83150Y807250D01*
X83067Y807750D01*
X82733Y808000D01*
X81233Y808500D01*
X80900Y809083D01*
X81067Y809500D01*
X81400Y809750D01*
X81900Y809833D01*
X82400Y809750D01*
X82900Y809500D01*
G01X86250Y808750D02*
X88917D01*
X88667Y809333D01*
X88250Y809667D01*
X87667Y809833D01*
X87083Y809750D01*
X86583Y809500D01*
X86250Y808917D01*
X86083Y808417D01*
Y807917D01*
X86250Y807417D01*
X86667Y806917D01*
X87167Y806583D01*
X87750Y806500D01*
X88333Y806667D01*
X88917Y807167D01*
G01X98200Y806500D02*
Y810750D01*
X98367Y811167D01*
X98700Y811417D01*
X99200Y811500D01*
X99700Y811333D01*
X99950Y810917D01*
G01X98950Y809500D02*
X97283D01*
G01X104300Y806500D02*
X103800Y806583D01*
X103300Y806917D01*
X102967Y807500D01*
X102800Y808167D01*
X102967Y808833D01*
X103300Y809417D01*
X103800Y809750D01*
X104300Y809833D01*
X104800Y809750D01*
X105300Y809417D01*
X105633Y808833D01*
X105717Y808167D01*
X105633Y807500D01*
X105300Y806917D01*
X104800Y806583D01*
X104300Y806500D01*
G01X109900D02*
Y811500D01*
G01X115500Y806500D02*
Y811500D01*
G01X121100Y806500D02*
X120600Y806583D01*
X120100Y806917D01*
X119767Y807500D01*
X119600Y808167D01*
X119767Y808833D01*
X120100Y809417D01*
X120600Y809750D01*
X121100Y809833D01*
X121600Y809750D01*
X122100Y809417D01*
X122433Y808833D01*
X122517Y808167D01*
X122433Y807500D01*
X122100Y806917D01*
X121600Y806583D01*
X121100Y806500D01*
G01X124617Y809833D02*
X125617Y806500D01*
X126700Y809833D01*
X127783Y806500D01*
X128783Y809833D01*
G01X137900Y811500D02*
Y806500D01*
G01X136733Y809833D02*
X139067D01*
G01X142083Y806500D02*
Y811500D01*
G01Y809083D02*
X142500Y809500D01*
X142917Y809750D01*
X143583Y809833D01*
X144083Y809750D01*
X144667Y809417D01*
X144917Y808917D01*
Y806500D01*
G01X147850Y808750D02*
X150517D01*
X150267Y809333D01*
X149850Y809667D01*
X149267Y809833D01*
X148683Y809750D01*
X148183Y809500D01*
X147850Y808917D01*
X147683Y808417D01*
Y807917D01*
X147850Y807417D01*
X148267Y806917D01*
X148767Y806583D01*
X149350Y806500D01*
X149933Y806667D01*
X150517Y807167D01*
G01X159050Y807083D02*
X159467Y806750D01*
X160050Y806500D01*
X160550D01*
X161050Y806667D01*
X161383Y806917D01*
X161550Y807250D01*
X161467Y807750D01*
X161133Y808000D01*
X159633Y808500D01*
X159300Y809083D01*
X159467Y809500D01*
X159800Y809750D01*
X160300Y809833D01*
X160800Y809750D01*
X161300Y809500D01*
G01X164400Y804833D02*
Y809833D01*
G01Y809083D02*
X164817Y809500D01*
X165233Y809750D01*
X165900Y809833D01*
X166483Y809750D01*
X167067Y809333D01*
X167317Y808750D01*
X167400Y808167D01*
X167317Y807583D01*
X167067Y807000D01*
X166567Y806667D01*
X165900Y806500D01*
X165317Y806583D01*
X164733Y806833D01*
X164400Y807167D01*
G01X170250Y808750D02*
X172917D01*
X172667Y809333D01*
X172250Y809667D01*
X171667Y809833D01*
X171083Y809750D01*
X170583Y809500D01*
X170250Y808917D01*
X170083Y808417D01*
Y807917D01*
X170250Y807417D01*
X170667Y806917D01*
X171167Y806583D01*
X171750Y806500D01*
X172333Y806667D01*
X172917Y807167D01*
G01X178433Y809417D02*
X177850Y809750D01*
X177350Y809833D01*
X176683Y809667D01*
X176183Y809333D01*
X175850Y808750D01*
X175767Y808167D01*
X175850Y807583D01*
X176183Y807083D01*
X176683Y806667D01*
X177350Y806500D01*
X177933Y806667D01*
X178433Y807000D01*
G01X182700Y809833D02*
Y806500D01*
G01Y811167D02*
X182533Y811250D01*
Y811417D01*
X182700Y811500D01*
X182867Y811417D01*
Y811250D01*
X182700Y811167D01*
G01X187800Y806500D02*
Y810750D01*
X187967Y811167D01*
X188300Y811417D01*
X188800Y811500D01*
X189300Y811333D01*
X189550Y810917D01*
G01X188550Y809500D02*
X186883D01*
G01X193900Y809833D02*
Y806500D01*
G01Y811167D02*
X193733Y811250D01*
Y811417D01*
X193900Y811500D01*
X194067Y811417D01*
Y811250D01*
X193900Y811167D01*
G01X200833Y809417D02*
X200250Y809750D01*
X199750Y809833D01*
X199083Y809667D01*
X198583Y809333D01*
X198250Y808750D01*
X198167Y808167D01*
X198250Y807583D01*
X198583Y807083D01*
X199083Y806667D01*
X199750Y806500D01*
X200333Y806667D01*
X200833Y807000D01*
G01X206600Y806500D02*
Y809833D01*
G01Y809250D02*
X206267Y809583D01*
X205767Y809750D01*
X205183Y809833D01*
X204600Y809667D01*
X204100Y809333D01*
X203767Y808833D01*
X203600Y808167D01*
X203767Y807500D01*
X204100Y807000D01*
X204600Y806667D01*
X205183Y806500D01*
X205767Y806583D01*
X206267Y806833D01*
X206600Y807167D01*
G01X210700Y811500D02*
Y806500D01*
G01X209533Y809833D02*
X211867D01*
G01X216300D02*
Y806500D01*
G01Y811167D02*
X216133Y811250D01*
Y811417D01*
X216300Y811500D01*
X216467Y811417D01*
Y811250D01*
X216300Y811167D01*
G01X221900Y806500D02*
X221400Y806583D01*
X220900Y806917D01*
X220567Y807500D01*
X220400Y808167D01*
X220567Y808833D01*
X220900Y809417D01*
X221400Y809750D01*
X221900Y809833D01*
X222400Y809750D01*
X222900Y809417D01*
X223233Y808833D01*
X223317Y808167D01*
X223233Y807500D01*
X222900Y806917D01*
X222400Y806583D01*
X221900Y806500D01*
G01X226083D02*
Y809833D01*
G01Y809000D02*
X226417Y809417D01*
X226917Y809750D01*
X227583Y809833D01*
X228167Y809750D01*
X228667Y809417D01*
X228917Y808833D01*
Y806500D01*
G01X240200Y811500D02*
Y806500D01*
G01Y807250D02*
X239867Y806833D01*
X239367Y806583D01*
X238783Y806500D01*
X238117Y806667D01*
X237617Y807083D01*
X237283Y807583D01*
X237200Y808167D01*
X237283Y808750D01*
X237617Y809250D01*
X238117Y809667D01*
X238783Y809833D01*
X239367Y809750D01*
X239783Y809583D01*
X240200Y809250D01*
G01X244300Y806500D02*
X243800Y806583D01*
X243300Y806917D01*
X242967Y807500D01*
X242800Y808167D01*
X242967Y808833D01*
X243300Y809417D01*
X243800Y809750D01*
X244300Y809833D01*
X244800Y809750D01*
X245300Y809417D01*
X245633Y808833D01*
X245717Y808167D01*
X245633Y807500D01*
X245300Y806917D01*
X244800Y806583D01*
X244300Y806500D01*
G01X251233Y809417D02*
X250650Y809750D01*
X250150Y809833D01*
X249483Y809667D01*
X248983Y809333D01*
X248650Y808750D01*
X248567Y808167D01*
X248650Y807583D01*
X248983Y807083D01*
X249483Y806667D01*
X250150Y806500D01*
X250733Y806667D01*
X251233Y807000D01*
G01X254083Y809833D02*
Y807500D01*
X254417Y806917D01*
X254917Y806583D01*
X255500Y806500D01*
X256083Y806583D01*
X256583Y806917D01*
X256917Y807500D01*
G01Y806500D02*
Y809833D01*
G01X258600Y806500D02*
Y809833D01*
G01Y808917D02*
X258850Y809333D01*
X259267Y809667D01*
X259850Y809833D01*
X260433Y809667D01*
X260850Y809333D01*
X261100Y808917D01*
Y806500D01*
G01Y808917D02*
X261350Y809333D01*
X261767Y809667D01*
X262350Y809833D01*
X262933Y809667D01*
X263350Y809333D01*
X263600Y808833D01*
Y806500D01*
G01X265450Y808750D02*
X268117D01*
X267867Y809333D01*
X267450Y809667D01*
X266867Y809833D01*
X266283Y809750D01*
X265783Y809500D01*
X265450Y808917D01*
X265283Y808417D01*
Y807917D01*
X265450Y807417D01*
X265867Y806917D01*
X266367Y806583D01*
X266950Y806500D01*
X267533Y806667D01*
X268117Y807167D01*
G01X270883Y806500D02*
Y809833D01*
G01Y809000D02*
X271217Y809417D01*
X271717Y809750D01*
X272383Y809833D01*
X272967Y809750D01*
X273467Y809417D01*
X273717Y808833D01*
Y806500D01*
G01X277900Y811500D02*
Y806500D01*
G01X276733Y809833D02*
X279067D01*
G01X282250Y807083D02*
X282667Y806750D01*
X283250Y806500D01*
X283750D01*
X284250Y806667D01*
X284583Y806917D01*
X284750Y807250D01*
X284667Y807750D01*
X284333Y808000D01*
X282833Y808500D01*
X282500Y809083D01*
X282667Y809500D01*
X283000Y809750D01*
X283500Y809833D01*
X284000Y809750D01*
X284500Y809500D01*
G01X294700Y809833D02*
Y806500D01*
G01Y811167D02*
X294533Y811250D01*
Y811417D01*
X294700Y811500D01*
X294867Y811417D01*
Y811250D01*
X294700Y811167D01*
G01X298883Y806500D02*
Y809833D01*
G01Y809000D02*
X299217Y809417D01*
X299717Y809750D01*
X300383Y809833D01*
X300967Y809750D01*
X301467Y809417D01*
X301717Y808833D01*
Y806500D01*
G01X312833Y809417D02*
X312250Y809750D01*
X311750Y809833D01*
X311083Y809667D01*
X310583Y809333D01*
X310250Y808750D01*
X310167Y808167D01*
X310250Y807583D01*
X310583Y807083D01*
X311083Y806667D01*
X311750Y806500D01*
X312333Y806667D01*
X312833Y807000D01*
G01X317100Y806500D02*
Y811500D01*
G01X324200Y806500D02*
Y809833D01*
G01Y809250D02*
X323867Y809583D01*
X323367Y809750D01*
X322783Y809833D01*
X322200Y809667D01*
X321700Y809333D01*
X321367Y808833D01*
X321200Y808167D01*
X321367Y807500D01*
X321700Y807000D01*
X322200Y806667D01*
X322783Y806500D01*
X323367Y806583D01*
X323867Y806833D01*
X324200Y807167D01*
G01X327050Y807083D02*
X327467Y806750D01*
X328050Y806500D01*
X328550D01*
X329050Y806667D01*
X329383Y806917D01*
X329550Y807250D01*
X329467Y807750D01*
X329133Y808000D01*
X327633Y808500D01*
X327300Y809083D01*
X327467Y809500D01*
X327800Y809750D01*
X328300Y809833D01*
X328800Y809750D01*
X329300Y809500D01*
G01X332650Y807083D02*
X333067Y806750D01*
X333650Y806500D01*
X334150D01*
X334650Y806667D01*
X334983Y806917D01*
X335150Y807250D01*
X335067Y807750D01*
X334733Y808000D01*
X333233Y808500D01*
X332900Y809083D01*
X333067Y809500D01*
X333400Y809750D01*
X333900Y809833D01*
X334400Y809750D01*
X334900Y809500D01*
G01X343517Y810667D02*
X344017Y811167D01*
X344600Y811417D01*
X345267Y811500D01*
X346100Y811333D01*
X346683Y810917D01*
X346850Y810417D01*
X346767Y809917D01*
X346433Y809500D01*
X344767Y808667D01*
X344017Y808083D01*
X343517Y807250D01*
X343350Y806500D01*
X346850D01*
G01X357800D02*
Y809833D01*
G01Y809250D02*
X357467Y809583D01*
X356967Y809750D01*
X356383Y809833D01*
X355800Y809667D01*
X355300Y809333D01*
X354967Y808833D01*
X354800Y808167D01*
X354967Y807500D01*
X355300Y807000D01*
X355800Y806667D01*
X356383Y806500D01*
X356967Y806583D01*
X357467Y806833D01*
X357800Y807167D01*
G01X360483Y806500D02*
Y809833D01*
G01Y809000D02*
X360817Y809417D01*
X361317Y809750D01*
X361983Y809833D01*
X362567Y809750D01*
X363067Y809417D01*
X363317Y808833D01*
Y806500D01*
G01X369000Y811500D02*
Y806500D01*
G01Y807250D02*
X368667Y806833D01*
X368167Y806583D01*
X367583Y806500D01*
X366917Y806667D01*
X366417Y807083D01*
X366083Y807583D01*
X366000Y808167D01*
X366083Y808750D01*
X366417Y809250D01*
X366917Y809667D01*
X367583Y809833D01*
X368167Y809750D01*
X368583Y809583D01*
X369000Y809250D01*
G01X378700Y811500D02*
Y806500D01*
G01X377533Y809833D02*
X379867D01*
G01X382883Y806500D02*
Y811500D01*
G01Y809083D02*
X383300Y809500D01*
X383717Y809750D01*
X384383Y809833D01*
X384883Y809750D01*
X385467Y809417D01*
X385717Y808917D01*
Y806500D01*
G01X388650Y808750D02*
X391317D01*
X391067Y809333D01*
X390650Y809667D01*
X390067Y809833D01*
X389483Y809750D01*
X388983Y809500D01*
X388650Y808917D01*
X388483Y808417D01*
Y807917D01*
X388650Y807417D01*
X389067Y806917D01*
X389567Y806583D01*
X390150Y806500D01*
X390733Y806667D01*
X391317Y807167D01*
G01X401100Y806500D02*
Y811500D01*
G01X408200Y806500D02*
Y809833D01*
G01Y809250D02*
X407867Y809583D01*
X407367Y809750D01*
X406783Y809833D01*
X406200Y809667D01*
X405700Y809333D01*
X405367Y808833D01*
X405200Y808167D01*
X405367Y807500D01*
X405700Y807000D01*
X406200Y806667D01*
X406783Y806500D01*
X407367Y806583D01*
X407867Y806833D01*
X408200Y807167D01*
G01X412300Y811500D02*
Y806500D01*
G01X411133Y809833D02*
X413467D01*
G01X416650Y808750D02*
X419317D01*
X419067Y809333D01*
X418650Y809667D01*
X418067Y809833D01*
X417483Y809750D01*
X416983Y809500D01*
X416650Y808917D01*
X416483Y808417D01*
Y807917D01*
X416650Y807417D01*
X417067Y806917D01*
X417567Y806583D01*
X418150Y806500D01*
X418733Y806667D01*
X419317Y807167D01*
G01X422250Y807083D02*
X422667Y806750D01*
X423250Y806500D01*
X423750D01*
X424250Y806667D01*
X424583Y806917D01*
X424750Y807250D01*
X424667Y807750D01*
X424333Y808000D01*
X422833Y808500D01*
X422500Y809083D01*
X422667Y809500D01*
X423000Y809750D01*
X423500Y809833D01*
X424000Y809750D01*
X424500Y809500D01*
G01X429100Y811500D02*
Y806500D01*
G01X427933Y809833D02*
X430267D01*
G01X438800D02*
X440300Y806500D01*
X441800Y809833D01*
G01X444650Y808750D02*
X447317D01*
X447067Y809333D01*
X446650Y809667D01*
X446067Y809833D01*
X445483Y809750D01*
X444983Y809500D01*
X444650Y808917D01*
X444483Y808417D01*
Y807917D01*
X444650Y807417D01*
X445067Y806917D01*
X445567Y806583D01*
X446150Y806500D01*
X446733Y806667D01*
X447317Y807167D01*
G01X450333Y806500D02*
Y809833D01*
G01Y809167D02*
X450750Y809500D01*
X451167Y809750D01*
X451750Y809833D01*
X452167Y809750D01*
X452667Y809500D01*
G01X455850Y807083D02*
X456267Y806750D01*
X456850Y806500D01*
X457350D01*
X457850Y806667D01*
X458183Y806917D01*
X458350Y807250D01*
X458267Y807750D01*
X457933Y808000D01*
X456433Y808500D01*
X456100Y809083D01*
X456267Y809500D01*
X456600Y809750D01*
X457100Y809833D01*
X457600Y809750D01*
X458100Y809500D01*
G01X462700Y809833D02*
Y806500D01*
G01Y811167D02*
X462533Y811250D01*
Y811417D01*
X462700Y811500D01*
X462867Y811417D01*
Y811250D01*
X462700Y811167D01*
G01X468300Y806500D02*
X467800Y806583D01*
X467300Y806917D01*
X466967Y807500D01*
X466800Y808167D01*
X466967Y808833D01*
X467300Y809417D01*
X467800Y809750D01*
X468300Y809833D01*
X468800Y809750D01*
X469300Y809417D01*
X469633Y808833D01*
X469717Y808167D01*
X469633Y807500D01*
X469300Y806917D01*
X468800Y806583D01*
X468300Y806500D01*
G01X472483D02*
Y809833D01*
G01Y809000D02*
X472817Y809417D01*
X473317Y809750D01*
X473983Y809833D01*
X474567Y809750D01*
X475067Y809417D01*
X475317Y808833D01*
Y806500D01*
G01X485100Y809833D02*
Y806500D01*
G01Y811167D02*
X484933Y811250D01*
Y811417D01*
X485100Y811500D01*
X485267Y811417D01*
Y811250D01*
X485100Y811167D01*
G01X489450Y807083D02*
X489867Y806750D01*
X490450Y806500D01*
X490950D01*
X491450Y806667D01*
X491783Y806917D01*
X491950Y807250D01*
X491867Y807750D01*
X491533Y808000D01*
X490033Y808500D01*
X489700Y809083D01*
X489867Y809500D01*
X490200Y809750D01*
X490700Y809833D01*
X491200Y809750D01*
X491700Y809500D01*
G01X500733Y806500D02*
Y809833D01*
G01Y809167D02*
X501150Y809500D01*
X501567Y809750D01*
X502150Y809833D01*
X502567Y809750D01*
X503067Y809500D01*
G01X506250Y808750D02*
X508917D01*
X508667Y809333D01*
X508250Y809667D01*
X507667Y809833D01*
X507083Y809750D01*
X506583Y809500D01*
X506250Y808917D01*
X506083Y808417D01*
Y807917D01*
X506250Y807417D01*
X506667Y806917D01*
X507167Y806583D01*
X507750Y806500D01*
X508333Y806667D01*
X508917Y807167D01*
G01X514600Y804833D02*
Y809833D01*
G01Y809083D02*
X514183Y809500D01*
X513683Y809750D01*
X513100Y809833D01*
X512600Y809750D01*
X512017Y809333D01*
X511683Y808750D01*
X511600Y808167D01*
X511683Y807583D01*
X512017Y807000D01*
X512600Y806583D01*
X513100Y806500D01*
X513683Y806583D01*
X514183Y806833D01*
X514600Y807250D01*
G01X517283Y809833D02*
Y807500D01*
X517617Y806917D01*
X518117Y806583D01*
X518700Y806500D01*
X519283Y806583D01*
X519783Y806917D01*
X520117Y807500D01*
G01Y806500D02*
Y809833D01*
G01X524300D02*
Y806500D01*
G01Y811167D02*
X524133Y811250D01*
Y811417D01*
X524300Y811500D01*
X524467Y811417D01*
Y811250D01*
X524300Y811167D01*
G01X528733Y806500D02*
Y809833D01*
G01Y809167D02*
X529150Y809500D01*
X529567Y809750D01*
X530150Y809833D01*
X530567Y809750D01*
X531067Y809500D01*
G01X534250Y808750D02*
X536917D01*
X536667Y809333D01*
X536250Y809667D01*
X535667Y809833D01*
X535083Y809750D01*
X534583Y809500D01*
X534250Y808917D01*
X534083Y808417D01*
Y807917D01*
X534250Y807417D01*
X534667Y806917D01*
X535167Y806583D01*
X535750Y806500D01*
X536333Y806667D01*
X536917Y807167D01*
G01X542600Y811500D02*
Y806500D01*
G01Y807250D02*
X542267Y806833D01*
X541767Y806583D01*
X541183Y806500D01*
X540517Y806667D01*
X540017Y807083D01*
X539683Y807583D01*
X539600Y808167D01*
X539683Y808750D01*
X540017Y809250D01*
X540517Y809667D01*
X541183Y809833D01*
X541767Y809750D01*
X542183Y809583D01*
X542600Y809250D01*
G01X546533Y805583D02*
X546867Y806667D01*
G01X57000Y802500D02*
X59000D01*
G01X58000D02*
Y797500D01*
G01X57000D02*
X59000D01*
G01X63100D02*
Y801750D01*
X63267Y802167D01*
X63600Y802417D01*
X64100Y802500D01*
X64600Y802333D01*
X64850Y801917D01*
G01X63850Y800500D02*
X62183D01*
G01X74800Y802500D02*
Y797500D01*
G01X73633Y800833D02*
X75967D01*
G01X78983Y797500D02*
Y802500D01*
G01Y800083D02*
X79400Y800500D01*
X79817Y800750D01*
X80483Y800833D01*
X80983Y800750D01*
X81567Y800417D01*
X81817Y799917D01*
Y797500D01*
G01X84750Y799750D02*
X87417D01*
X87167Y800333D01*
X86750Y800667D01*
X86167Y800833D01*
X85583Y800750D01*
X85083Y800500D01*
X84750Y799917D01*
X84583Y799417D01*
Y798917D01*
X84750Y798417D01*
X85167Y797917D01*
X85667Y797583D01*
X86250Y797500D01*
X86833Y797667D01*
X87417Y798167D01*
G01X98533Y800417D02*
X97950Y800750D01*
X97450Y800833D01*
X96783Y800667D01*
X96283Y800333D01*
X95950Y799750D01*
X95867Y799167D01*
X95950Y798583D01*
X96283Y798083D01*
X96783Y797667D01*
X97450Y797500D01*
X98033Y797667D01*
X98533Y798000D01*
G01X101633Y797500D02*
Y800833D01*
G01Y800167D02*
X102050Y800500D01*
X102467Y800750D01*
X103050Y800833D01*
X103467Y800750D01*
X103967Y800500D01*
G01X108400Y800833D02*
Y797500D01*
G01Y802167D02*
X108233Y802250D01*
Y802417D01*
X108400Y802500D01*
X108567Y802417D01*
Y802250D01*
X108400Y802167D01*
G01X114000Y802500D02*
Y797500D01*
G01X112833Y800833D02*
X115167D01*
G01X118350Y799750D02*
X121017D01*
X120767Y800333D01*
X120350Y800667D01*
X119767Y800833D01*
X119183Y800750D01*
X118683Y800500D01*
X118350Y799917D01*
X118183Y799417D01*
Y798917D01*
X118350Y798417D01*
X118767Y797917D01*
X119267Y797583D01*
X119850Y797500D01*
X120433Y797667D01*
X121017Y798167D01*
G01X124033Y797500D02*
Y800833D01*
G01Y800167D02*
X124450Y800500D01*
X124867Y800750D01*
X125450Y800833D01*
X125867Y800750D01*
X126367Y800500D01*
G01X130800Y800833D02*
Y797500D01*
G01Y802167D02*
X130633Y802250D01*
Y802417D01*
X130800Y802500D01*
X130967Y802417D01*
Y802250D01*
X130800Y802167D01*
G01X137900Y797500D02*
Y800833D01*
G01Y800250D02*
X137567Y800583D01*
X137067Y800750D01*
X136483Y800833D01*
X135900Y800667D01*
X135400Y800333D01*
X135067Y799833D01*
X134900Y799167D01*
X135067Y798500D01*
X135400Y798000D01*
X135900Y797667D01*
X136483Y797500D01*
X137067Y797583D01*
X137567Y797833D01*
X137900Y798167D01*
G01X147600Y800833D02*
Y797500D01*
G01Y802167D02*
X147433Y802250D01*
Y802417D01*
X147600Y802500D01*
X147767Y802417D01*
Y802250D01*
X147600Y802167D01*
G01X151950Y798083D02*
X152367Y797750D01*
X152950Y797500D01*
X153450D01*
X153950Y797667D01*
X154283Y797917D01*
X154450Y798250D01*
X154367Y798750D01*
X154033Y799000D01*
X152533Y799500D01*
X152200Y800083D01*
X152367Y800500D01*
X152700Y800750D01*
X153200Y800833D01*
X153700Y800750D01*
X154200Y800500D01*
G01X162983Y797500D02*
Y800833D01*
G01Y800000D02*
X163317Y800417D01*
X163817Y800750D01*
X164483Y800833D01*
X165067Y800750D01*
X165567Y800417D01*
X165817Y799833D01*
Y797500D01*
G01X170000D02*
X169500Y797583D01*
X169000Y797917D01*
X168667Y798500D01*
X168500Y799167D01*
X168667Y799833D01*
X169000Y800417D01*
X169500Y800750D01*
X170000Y800833D01*
X170500Y800750D01*
X171000Y800417D01*
X171333Y799833D01*
X171417Y799167D01*
X171333Y798500D01*
X171000Y797917D01*
X170500Y797583D01*
X170000Y797500D01*
G01X175600Y802500D02*
Y797500D01*
G01X174433Y800833D02*
X176767D01*
G01X185550Y798083D02*
X185967Y797750D01*
X186550Y797500D01*
X187050D01*
X187550Y797667D01*
X187883Y797917D01*
X188050Y798250D01*
X187967Y798750D01*
X187633Y799000D01*
X186133Y799500D01*
X185800Y800083D01*
X185967Y800500D01*
X186300Y800750D01*
X186800Y800833D01*
X187300Y800750D01*
X187800Y800500D01*
G01X190900Y795833D02*
Y800833D01*
G01Y800083D02*
X191317Y800500D01*
X191733Y800750D01*
X192400Y800833D01*
X192983Y800750D01*
X193567Y800333D01*
X193817Y799750D01*
X193900Y799167D01*
X193817Y798583D01*
X193567Y798000D01*
X193067Y797667D01*
X192400Y797500D01*
X191817Y797583D01*
X191233Y797833D01*
X190900Y798167D01*
G01X196750Y799750D02*
X199417D01*
X199167Y800333D01*
X198750Y800667D01*
X198167Y800833D01*
X197583Y800750D01*
X197083Y800500D01*
X196750Y799917D01*
X196583Y799417D01*
Y798917D01*
X196750Y798417D01*
X197167Y797917D01*
X197667Y797583D01*
X198250Y797500D01*
X198833Y797667D01*
X199417Y798167D01*
G01X204933Y800417D02*
X204350Y800750D01*
X203850Y800833D01*
X203183Y800667D01*
X202683Y800333D01*
X202350Y799750D01*
X202267Y799167D01*
X202350Y798583D01*
X202683Y798083D01*
X203183Y797667D01*
X203850Y797500D01*
X204433Y797667D01*
X204933Y798000D01*
G01X209200Y800833D02*
Y797500D01*
G01Y802167D02*
X209033Y802250D01*
Y802417D01*
X209200Y802500D01*
X209367Y802417D01*
Y802250D01*
X209200Y802167D01*
G01X214300Y797500D02*
Y801750D01*
X214467Y802167D01*
X214800Y802417D01*
X215300Y802500D01*
X215800Y802333D01*
X216050Y801917D01*
G01X215050Y800500D02*
X213383D01*
G01X220400Y800833D02*
Y797500D01*
G01Y802167D02*
X220233Y802250D01*
Y802417D01*
X220400Y802500D01*
X220567Y802417D01*
Y802250D01*
X220400Y802167D01*
G01X224750Y799750D02*
X227417D01*
X227167Y800333D01*
X226750Y800667D01*
X226167Y800833D01*
X225583Y800750D01*
X225083Y800500D01*
X224750Y799917D01*
X224583Y799417D01*
Y798917D01*
X224750Y798417D01*
X225167Y797917D01*
X225667Y797583D01*
X226250Y797500D01*
X226833Y797667D01*
X227417Y798167D01*
G01X233100Y802500D02*
Y797500D01*
G01Y798250D02*
X232767Y797833D01*
X232267Y797583D01*
X231683Y797500D01*
X231017Y797667D01*
X230517Y798083D01*
X230183Y798583D01*
X230100Y799167D01*
X230183Y799750D01*
X230517Y800250D01*
X231017Y800667D01*
X231683Y800833D01*
X232267Y800750D01*
X232683Y800583D01*
X233100Y800250D01*
G01X242800Y800833D02*
Y797500D01*
G01Y802167D02*
X242633Y802250D01*
Y802417D01*
X242800Y802500D01*
X242967Y802417D01*
Y802250D01*
X242800Y802167D01*
G01X246983Y797500D02*
Y800833D01*
G01Y800000D02*
X247317Y800417D01*
X247817Y800750D01*
X248483Y800833D01*
X249067Y800750D01*
X249567Y800417D01*
X249817Y799833D01*
Y797500D01*
G01X259600Y802500D02*
Y797500D01*
G01X258433Y800833D02*
X260767D01*
G01X263783Y797500D02*
Y802500D01*
G01Y800083D02*
X264200Y800500D01*
X264617Y800750D01*
X265283Y800833D01*
X265783Y800750D01*
X266367Y800417D01*
X266617Y799917D01*
Y797500D01*
G01X269550Y799750D02*
X272217D01*
X271967Y800333D01*
X271550Y800667D01*
X270967Y800833D01*
X270383Y800750D01*
X269883Y800500D01*
X269550Y799917D01*
X269383Y799417D01*
Y798917D01*
X269550Y798417D01*
X269967Y797917D01*
X270467Y797583D01*
X271050Y797500D01*
X271633Y797667D01*
X272217Y798167D01*
G01X282000Y802500D02*
Y797500D01*
G01X280833Y800833D02*
X283167D01*
G01X289100Y797500D02*
Y800833D01*
G01Y800250D02*
X288767Y800583D01*
X288267Y800750D01*
X287683Y800833D01*
X287100Y800667D01*
X286600Y800333D01*
X286267Y799833D01*
X286100Y799167D01*
X286267Y798500D01*
X286600Y798000D01*
X287100Y797667D01*
X287683Y797500D01*
X288267Y797583D01*
X288767Y797833D01*
X289100Y798167D01*
G01X291700Y797500D02*
Y802500D01*
G01Y800000D02*
X292117Y800500D01*
X292617Y800750D01*
X293117Y800833D01*
X293867Y800667D01*
X294367Y800333D01*
X294700Y799750D01*
Y799083D01*
X294533Y798417D01*
X294200Y797917D01*
X293617Y797583D01*
X293117Y797500D01*
X292617Y797583D01*
X292117Y797833D01*
X291700Y798250D01*
G01X298800Y797500D02*
Y802500D01*
G01X303150Y799750D02*
X305817D01*
X305567Y800333D01*
X305150Y800667D01*
X304567Y800833D01*
X303983Y800750D01*
X303483Y800500D01*
X303150Y799917D01*
X302983Y799417D01*
Y798917D01*
X303150Y798417D01*
X303567Y797917D01*
X304067Y797583D01*
X304650Y797500D01*
X305233Y797667D01*
X305817Y798167D01*
G01X310000Y797333D02*
X309833Y797417D01*
Y797583D01*
X310000Y797667D01*
X310167Y797583D01*
Y797417D01*
X310000Y797333D01*
G01Y799583D02*
X309833Y799667D01*
Y799833D01*
X310000Y799917D01*
X310167Y799833D01*
Y799667D01*
X310000Y799583D01*
G01X67000Y743433D02*
X66833Y743517D01*
Y743683D01*
X67000Y743767D01*
X67167Y743683D01*
Y743517D01*
X67000Y743433D01*
G01Y752433D02*
X66833Y752517D01*
Y752683D01*
X67000Y752767D01*
X67167Y752683D01*
Y752517D01*
X67000Y752433D01*
G01Y761433D02*
X66833Y761517D01*
Y761683D01*
X67000Y761767D01*
X67167Y761683D01*
Y761517D01*
X67000Y761433D01*
G01Y770433D02*
X66833Y770517D01*
Y770683D01*
X67000Y770767D01*
X67167Y770683D01*
Y770517D01*
X67000Y770433D01*
G01X71000Y747600D02*
X73000D01*
G01X72000D02*
Y742600D01*
G01X71000D02*
X73000D01*
G01X75933D02*
Y747600D01*
X77933D01*
X78600Y747350D01*
X79100Y746767D01*
X79267Y746100D01*
X79100Y745433D01*
X78683Y744933D01*
X77933Y744683D01*
X75933D01*
G01X85033Y747183D02*
X84533Y747433D01*
X83950Y747600D01*
X83283D01*
X82533Y747350D01*
X81950Y746933D01*
X81533Y746433D01*
X81200Y745600D01*
X81117Y744850D01*
X81283Y744100D01*
X81533Y743600D01*
X82033Y743100D01*
X82617Y742767D01*
X83200Y742600D01*
X83783D01*
X84367Y742767D01*
X84867Y743017D01*
X85283Y743350D01*
G01X87717Y744267D02*
X89883D01*
G01X95400Y742600D02*
Y747600D01*
X92317Y744017D01*
X96483D01*
G01X100000Y742600D02*
Y747600D01*
X99000Y746600D01*
G01Y742600D02*
X101000D01*
G01X105600Y747600D02*
X104933Y747433D01*
X104433Y747017D01*
X104100Y746517D01*
X103850Y745850D01*
X103767Y745100D01*
X103850Y744350D01*
X104100Y743683D01*
X104433Y743183D01*
X104933Y742767D01*
X105600Y742600D01*
X106267Y742767D01*
X106767Y743183D01*
X107100Y743683D01*
X107350Y744350D01*
X107433Y745100D01*
X107350Y745850D01*
X107100Y746517D01*
X106767Y747017D01*
X106267Y747433D01*
X105600Y747600D01*
G01X111200Y742600D02*
Y747600D01*
X110200Y746600D01*
G01Y742600D02*
X112200D01*
G01X120650Y743267D02*
X121317Y742850D01*
X122067Y742600D01*
X122733D01*
X123400Y742850D01*
X123900Y743267D01*
X124150Y743850D01*
X123983Y744433D01*
X123567Y744933D01*
X122817Y745267D01*
X121817Y745433D01*
X121233Y745767D01*
X120983Y746350D01*
X121150Y746933D01*
X121567Y747350D01*
X122150Y747600D01*
X122733D01*
X123317Y747433D01*
X123817Y747017D01*
G01X126500Y740933D02*
Y745933D01*
G01Y745183D02*
X126917Y745600D01*
X127333Y745850D01*
X128000Y745933D01*
X128583Y745850D01*
X129167Y745433D01*
X129417Y744850D01*
X129500Y744267D01*
X129417Y743683D01*
X129167Y743100D01*
X128667Y742767D01*
X128000Y742600D01*
X127417Y742683D01*
X126833Y742933D01*
X126500Y743267D01*
G01X132350Y744850D02*
X135017D01*
X134767Y745433D01*
X134350Y745767D01*
X133767Y745933D01*
X133183Y745850D01*
X132683Y745600D01*
X132350Y745017D01*
X132183Y744517D01*
Y744017D01*
X132350Y743517D01*
X132767Y743017D01*
X133267Y742683D01*
X133850Y742600D01*
X134433Y742767D01*
X135017Y743267D01*
G01X140533Y745517D02*
X139950Y745850D01*
X139450Y745933D01*
X138783Y745767D01*
X138283Y745433D01*
X137950Y744850D01*
X137867Y744267D01*
X137950Y743683D01*
X138283Y743183D01*
X138783Y742767D01*
X139450Y742600D01*
X140033Y742767D01*
X140533Y743100D01*
G01X144800Y745933D02*
Y742600D01*
G01Y747267D02*
X144633Y747350D01*
Y747517D01*
X144800Y747600D01*
X144967Y747517D01*
Y747350D01*
X144800Y747267D01*
G01X149900Y742600D02*
Y746850D01*
X150067Y747267D01*
X150400Y747517D01*
X150900Y747600D01*
X151400Y747433D01*
X151650Y747017D01*
G01X150650Y745600D02*
X148983D01*
G01X156000Y745933D02*
Y742600D01*
G01Y747267D02*
X155833Y747350D01*
Y747517D01*
X156000Y747600D01*
X156167Y747517D01*
Y747350D01*
X156000Y747267D01*
G01X162933Y745517D02*
X162350Y745850D01*
X161850Y745933D01*
X161183Y745767D01*
X160683Y745433D01*
X160350Y744850D01*
X160267Y744267D01*
X160350Y743683D01*
X160683Y743183D01*
X161183Y742767D01*
X161850Y742600D01*
X162433Y742767D01*
X162933Y743100D01*
G01X168700Y742600D02*
Y745933D01*
G01Y745350D02*
X168367Y745683D01*
X167867Y745850D01*
X167283Y745933D01*
X166700Y745767D01*
X166200Y745433D01*
X165867Y744933D01*
X165700Y744267D01*
X165867Y743600D01*
X166200Y743100D01*
X166700Y742767D01*
X167283Y742600D01*
X167867Y742683D01*
X168367Y742933D01*
X168700Y743267D01*
G01X172800Y747600D02*
Y742600D01*
G01X171633Y745933D02*
X173967D01*
G01X178400D02*
Y742600D01*
G01Y747267D02*
X178233Y747350D01*
Y747517D01*
X178400Y747600D01*
X178567Y747517D01*
Y747350D01*
X178400Y747267D01*
G01X184000Y742600D02*
X183500Y742683D01*
X183000Y743017D01*
X182667Y743600D01*
X182500Y744267D01*
X182667Y744933D01*
X183000Y745517D01*
X183500Y745850D01*
X184000Y745933D01*
X184500Y745850D01*
X185000Y745517D01*
X185333Y744933D01*
X185417Y744267D01*
X185333Y743600D01*
X185000Y743017D01*
X184500Y742683D01*
X184000Y742600D01*
G01X188183D02*
Y745933D01*
G01Y745100D02*
X188517Y745517D01*
X189017Y745850D01*
X189683Y745933D01*
X190267Y745850D01*
X190767Y745517D01*
X191017Y744933D01*
Y742600D01*
G01X200300D02*
Y746850D01*
X200467Y747267D01*
X200800Y747517D01*
X201300Y747600D01*
X201800Y747433D01*
X202050Y747017D01*
G01X201050Y745600D02*
X199383D01*
G01X206400Y742600D02*
X205900Y742683D01*
X205400Y743017D01*
X205067Y743600D01*
X204900Y744267D01*
X205067Y744933D01*
X205400Y745517D01*
X205900Y745850D01*
X206400Y745933D01*
X206900Y745850D01*
X207400Y745517D01*
X207733Y744933D01*
X207817Y744267D01*
X207733Y743600D01*
X207400Y743017D01*
X206900Y742683D01*
X206400Y742600D01*
G01X210833D02*
Y745933D01*
G01Y745267D02*
X211250Y745600D01*
X211667Y745850D01*
X212250Y745933D01*
X212667Y745850D01*
X213167Y745600D01*
G01X223867Y745267D02*
X224200Y745517D01*
X224450Y745933D01*
X224617Y746517D01*
X224450Y747017D01*
X224117Y747350D01*
X223533Y747600D01*
X221283D01*
Y742600D01*
X224033D01*
X224617Y742933D01*
X224950Y743433D01*
X225117Y744017D01*
X224950Y744600D01*
X224450Y745100D01*
X223867Y745267D01*
X221283D01*
G01X230300Y742600D02*
Y745933D01*
G01Y745350D02*
X229967Y745683D01*
X229467Y745850D01*
X228883Y745933D01*
X228300Y745767D01*
X227800Y745433D01*
X227467Y744933D01*
X227300Y744267D01*
X227467Y743600D01*
X227800Y743100D01*
X228300Y742767D01*
X228883Y742600D01*
X229467Y742683D01*
X229967Y742933D01*
X230300Y743267D01*
G01X233150Y743183D02*
X233567Y742850D01*
X234150Y742600D01*
X234650D01*
X235150Y742767D01*
X235483Y743017D01*
X235650Y743350D01*
X235567Y743850D01*
X235233Y744100D01*
X233733Y744600D01*
X233400Y745183D01*
X233567Y745600D01*
X233900Y745850D01*
X234400Y745933D01*
X234900Y745850D01*
X235400Y745600D01*
G01X238750Y744850D02*
X241417D01*
X241167Y745433D01*
X240750Y745767D01*
X240167Y745933D01*
X239583Y745850D01*
X239083Y745600D01*
X238750Y745017D01*
X238583Y744517D01*
Y744017D01*
X238750Y743517D01*
X239167Y743017D01*
X239667Y742683D01*
X240250Y742600D01*
X240833Y742767D01*
X241417Y743267D01*
G01X249033Y742600D02*
Y747600D01*
X251200Y743433D01*
X253367Y747600D01*
Y742600D01*
G01X258300D02*
Y745933D01*
G01Y745350D02*
X257967Y745683D01*
X257467Y745850D01*
X256883Y745933D01*
X256300Y745767D01*
X255800Y745433D01*
X255467Y744933D01*
X255300Y744267D01*
X255467Y743600D01*
X255800Y743100D01*
X256300Y742767D01*
X256883Y742600D01*
X257467Y742683D01*
X257967Y742933D01*
X258300Y743267D01*
G01X262400Y747600D02*
Y742600D01*
G01X261233Y745933D02*
X263567D01*
G01X266750Y744850D02*
X269417D01*
X269167Y745433D01*
X268750Y745767D01*
X268167Y745933D01*
X267583Y745850D01*
X267083Y745600D01*
X266750Y745017D01*
X266583Y744517D01*
Y744017D01*
X266750Y743517D01*
X267167Y743017D01*
X267667Y742683D01*
X268250Y742600D01*
X268833Y742767D01*
X269417Y743267D01*
G01X272433Y742600D02*
Y745933D01*
G01Y745267D02*
X272850Y745600D01*
X273267Y745850D01*
X273850Y745933D01*
X274267Y745850D01*
X274767Y745600D01*
G01X279200Y745933D02*
Y742600D01*
G01Y747267D02*
X279033Y747350D01*
Y747517D01*
X279200Y747600D01*
X279367Y747517D01*
Y747350D01*
X279200Y747267D01*
G01X286300Y742600D02*
Y745933D01*
G01Y745350D02*
X285967Y745683D01*
X285467Y745850D01*
X284883Y745933D01*
X284300Y745767D01*
X283800Y745433D01*
X283467Y744933D01*
X283300Y744267D01*
X283467Y743600D01*
X283800Y743100D01*
X284300Y742767D01*
X284883Y742600D01*
X285467Y742683D01*
X285967Y742933D01*
X286300Y743267D01*
G01X290400Y742600D02*
Y747600D01*
G01X294750Y743183D02*
X295167Y742850D01*
X295750Y742600D01*
X296250D01*
X296750Y742767D01*
X297083Y743017D01*
X297250Y743350D01*
X297167Y743850D01*
X296833Y744100D01*
X295333Y744600D01*
X295000Y745183D01*
X295167Y745600D01*
X295500Y745850D01*
X296000Y745933D01*
X296500Y745850D01*
X297000Y745600D01*
G01X306700Y742600D02*
Y746850D01*
X306867Y747267D01*
X307200Y747517D01*
X307700Y747600D01*
X308200Y747433D01*
X308450Y747017D01*
G01X307450Y745600D02*
X305783D01*
G01X312800Y742600D02*
X312300Y742683D01*
X311800Y743017D01*
X311467Y743600D01*
X311300Y744267D01*
X311467Y744933D01*
X311800Y745517D01*
X312300Y745850D01*
X312800Y745933D01*
X313300Y745850D01*
X313800Y745517D01*
X314133Y744933D01*
X314217Y744267D01*
X314133Y743600D01*
X313800Y743017D01*
X313300Y742683D01*
X312800Y742600D01*
G01X317233D02*
Y745933D01*
G01Y745267D02*
X317650Y745600D01*
X318067Y745850D01*
X318650Y745933D01*
X319067Y745850D01*
X319567Y745600D01*
G01X327933Y742600D02*
Y747600D01*
X330017D01*
X330683Y747350D01*
X331100Y747017D01*
X331267Y746350D01*
X331100Y745683D01*
X330600Y745267D01*
X330017Y745017D01*
X327933D01*
G01X330017D02*
X331267Y742600D01*
G01X335200Y745933D02*
Y742600D01*
G01Y747267D02*
X335033Y747350D01*
Y747517D01*
X335200Y747600D01*
X335367Y747517D01*
Y747350D01*
X335200Y747267D01*
G01X339633Y741350D02*
X340217Y741017D01*
X340883Y740933D01*
X341467Y741017D01*
X341967Y741433D01*
X342300Y742017D01*
Y745933D01*
G01Y745267D02*
X341967Y745600D01*
X341467Y745850D01*
X340883Y745933D01*
X340217Y745767D01*
X339800Y745433D01*
X339467Y744850D01*
X339300Y744267D01*
X339383Y743767D01*
X339717Y743183D01*
X340217Y742767D01*
X340883Y742600D01*
X341383Y742683D01*
X341967Y743017D01*
X342300Y743350D01*
G01X346400Y745933D02*
Y742600D01*
G01Y747267D02*
X346233Y747350D01*
Y747517D01*
X346400Y747600D01*
X346567Y747517D01*
Y747350D01*
X346400Y747267D01*
G01X353500Y747600D02*
Y742600D01*
G01Y743350D02*
X353167Y742933D01*
X352667Y742683D01*
X352083Y742600D01*
X351417Y742767D01*
X350917Y743183D01*
X350583Y743683D01*
X350500Y744267D01*
X350583Y744850D01*
X350917Y745350D01*
X351417Y745767D01*
X352083Y745933D01*
X352667Y745850D01*
X353083Y745683D01*
X353500Y745350D01*
G01X364700Y742600D02*
Y745933D01*
G01Y745350D02*
X364367Y745683D01*
X363867Y745850D01*
X363283Y745933D01*
X362700Y745767D01*
X362200Y745433D01*
X361867Y744933D01*
X361700Y744267D01*
X361867Y743600D01*
X362200Y743100D01*
X362700Y742767D01*
X363283Y742600D01*
X363867Y742683D01*
X364367Y742933D01*
X364700Y743267D01*
G01X367383Y742600D02*
Y745933D01*
G01Y745100D02*
X367717Y745517D01*
X368217Y745850D01*
X368883Y745933D01*
X369467Y745850D01*
X369967Y745517D01*
X370217Y744933D01*
Y742600D01*
G01X375900Y747600D02*
Y742600D01*
G01Y743350D02*
X375567Y742933D01*
X375067Y742683D01*
X374483Y742600D01*
X373817Y742767D01*
X373317Y743183D01*
X372983Y743683D01*
X372900Y744267D01*
X372983Y744850D01*
X373317Y745350D01*
X373817Y745767D01*
X374483Y745933D01*
X375067Y745850D01*
X375483Y745683D01*
X375900Y745350D01*
G01X383433Y742600D02*
Y747600D01*
X385600Y743433D01*
X387767Y747600D01*
Y742600D01*
G01X389783Y745933D02*
Y743600D01*
X390117Y743017D01*
X390617Y742683D01*
X391200Y742600D01*
X391783Y742683D01*
X392283Y743017D01*
X392617Y743600D01*
G01Y742600D02*
Y745933D01*
G01X396800Y742600D02*
Y747600D01*
G01X402400D02*
Y742600D01*
G01X401233Y745933D02*
X403567D01*
G01X408000D02*
Y742600D01*
G01Y747267D02*
X407833Y747350D01*
Y747517D01*
X408000Y747600D01*
X408167Y747517D01*
Y747350D01*
X408000Y747267D01*
G01X413600Y742600D02*
Y747600D01*
G01X420700Y742600D02*
Y745933D01*
G01Y745350D02*
X420367Y745683D01*
X419867Y745850D01*
X419283Y745933D01*
X418700Y745767D01*
X418200Y745433D01*
X417867Y744933D01*
X417700Y744267D01*
X417867Y743600D01*
X418200Y743100D01*
X418700Y742767D01*
X419283Y742600D01*
X419867Y742683D01*
X420367Y742933D01*
X420700Y743267D01*
G01X423050Y741100D02*
X423550Y740933D01*
X424217Y741100D01*
X424633Y741433D01*
X424967Y741850D01*
X425467Y743183D01*
X426550Y745933D01*
G01X423883D02*
X425467Y743183D01*
G01X429150Y744850D02*
X431817D01*
X431567Y745433D01*
X431150Y745767D01*
X430567Y745933D01*
X429983Y745850D01*
X429483Y745600D01*
X429150Y745017D01*
X428983Y744517D01*
Y744017D01*
X429150Y743517D01*
X429567Y743017D01*
X430067Y742683D01*
X430650Y742600D01*
X431233Y742767D01*
X431817Y743267D01*
G01X434833Y742600D02*
Y745933D01*
G01Y745267D02*
X435250Y745600D01*
X435667Y745850D01*
X436250Y745933D01*
X436667Y745850D01*
X437167Y745600D01*
G01X445533Y742600D02*
Y747600D01*
X447533D01*
X448200Y747350D01*
X448700Y746767D01*
X448867Y746100D01*
X448700Y745433D01*
X448283Y744933D01*
X447533Y744683D01*
X445533D01*
G01X451633Y742600D02*
Y745933D01*
G01Y745267D02*
X452050Y745600D01*
X452467Y745850D01*
X453050Y745933D01*
X453467Y745850D01*
X453967Y745600D01*
G01X458400Y745933D02*
Y742600D01*
G01Y747267D02*
X458233Y747350D01*
Y747517D01*
X458400Y747600D01*
X458567Y747517D01*
Y747350D01*
X458400Y747267D01*
G01X462583Y742600D02*
Y745933D01*
G01Y745100D02*
X462917Y745517D01*
X463417Y745850D01*
X464083Y745933D01*
X464667Y745850D01*
X465167Y745517D01*
X465417Y744933D01*
Y742600D01*
G01X469600Y747600D02*
Y742600D01*
G01X468433Y745933D02*
X470767D01*
G01X473950Y744850D02*
X476617D01*
X476367Y745433D01*
X475950Y745767D01*
X475367Y745933D01*
X474783Y745850D01*
X474283Y745600D01*
X473950Y745017D01*
X473783Y744517D01*
Y744017D01*
X473950Y743517D01*
X474367Y743017D01*
X474867Y742683D01*
X475450Y742600D01*
X476033Y742767D01*
X476617Y743267D01*
G01X482300Y747600D02*
Y742600D01*
G01Y743350D02*
X481967Y742933D01*
X481467Y742683D01*
X480883Y742600D01*
X480217Y742767D01*
X479717Y743183D01*
X479383Y743683D01*
X479300Y744267D01*
X479383Y744850D01*
X479717Y745350D01*
X480217Y745767D01*
X480883Y745933D01*
X481467Y745850D01*
X481883Y745683D01*
X482300Y745350D01*
G01X492667Y745267D02*
X493000Y745517D01*
X493250Y745933D01*
X493417Y746517D01*
X493250Y747017D01*
X492917Y747350D01*
X492333Y747600D01*
X490083D01*
Y742600D01*
X492833D01*
X493417Y742933D01*
X493750Y743433D01*
X493917Y744017D01*
X493750Y744600D01*
X493250Y745100D01*
X492667Y745267D01*
X490083D01*
G01X497600Y742600D02*
X497100Y742683D01*
X496600Y743017D01*
X496267Y743600D01*
X496100Y744267D01*
X496267Y744933D01*
X496600Y745517D01*
X497100Y745850D01*
X497600Y745933D01*
X498100Y745850D01*
X498600Y745517D01*
X498933Y744933D01*
X499017Y744267D01*
X498933Y743600D01*
X498600Y743017D01*
X498100Y742683D01*
X497600Y742600D01*
G01X504700D02*
Y745933D01*
G01Y745350D02*
X504367Y745683D01*
X503867Y745850D01*
X503283Y745933D01*
X502700Y745767D01*
X502200Y745433D01*
X501867Y744933D01*
X501700Y744267D01*
X501867Y743600D01*
X502200Y743100D01*
X502700Y742767D01*
X503283Y742600D01*
X503867Y742683D01*
X504367Y742933D01*
X504700Y743267D01*
G01X507633Y742600D02*
Y745933D01*
G01Y745267D02*
X508050Y745600D01*
X508467Y745850D01*
X509050Y745933D01*
X509467Y745850D01*
X509967Y745600D01*
G01X515900Y747600D02*
Y742600D01*
G01Y743350D02*
X515567Y742933D01*
X515067Y742683D01*
X514483Y742600D01*
X513817Y742767D01*
X513317Y743183D01*
X512983Y743683D01*
X512900Y744267D01*
X512983Y744850D01*
X513317Y745350D01*
X513817Y745767D01*
X514483Y745933D01*
X515067Y745850D01*
X515483Y745683D01*
X515900Y745350D01*
G01X518750Y743183D02*
X519167Y742850D01*
X519750Y742600D01*
X520250D01*
X520750Y742767D01*
X521083Y743017D01*
X521250Y743350D01*
X521167Y743850D01*
X520833Y744100D01*
X519333Y744600D01*
X519000Y745183D01*
X519167Y745600D01*
X519500Y745850D01*
X520000Y745933D01*
X520500Y745850D01*
X521000Y745600D01*
G01X71000Y756600D02*
X73000D01*
G01X72000D02*
Y751600D01*
G01X71000D02*
X73000D01*
G01X75933D02*
Y756600D01*
X77933D01*
X78600Y756350D01*
X79100Y755767D01*
X79267Y755100D01*
X79100Y754433D01*
X78683Y753933D01*
X77933Y753683D01*
X75933D01*
G01X85033Y756183D02*
X84533Y756433D01*
X83950Y756600D01*
X83283D01*
X82533Y756350D01*
X81950Y755933D01*
X81533Y755433D01*
X81200Y754600D01*
X81117Y753850D01*
X81283Y753100D01*
X81533Y752600D01*
X82033Y752100D01*
X82617Y751767D01*
X83200Y751600D01*
X83783D01*
X84367Y751767D01*
X84867Y752017D01*
X85283Y752350D01*
G01X87717Y753267D02*
X89883D01*
G01X94400Y756600D02*
Y751600D01*
G01X92483Y756600D02*
X96317D01*
G01X97833Y751600D02*
Y756600D01*
X100000Y752433D01*
X102167Y756600D01*
Y751600D01*
G01X104517Y753267D02*
X106683D01*
G01X109617Y753683D02*
X110200Y754267D01*
X110700Y754600D01*
X111367Y754767D01*
X111950Y754600D01*
X112367Y754267D01*
X112700Y753767D01*
X112783Y753183D01*
X112700Y752683D01*
X112367Y752183D01*
X111867Y751767D01*
X111283Y751600D01*
X110617Y751767D01*
X110033Y752267D01*
X109700Y753017D01*
X109617Y753850D01*
X109783Y754933D01*
X110033Y755517D01*
X110450Y756100D01*
X111033Y756517D01*
X111617Y756600D01*
X112200Y756433D01*
X112617Y756017D01*
G01X114967Y752350D02*
X115467Y751933D01*
X116050Y751683D01*
X116800Y751600D01*
X117550Y751767D01*
X118133Y752100D01*
X118550Y752683D01*
X118633Y753350D01*
X118467Y754017D01*
X118050Y754433D01*
X117467Y754767D01*
X116883Y754850D01*
X116300Y754767D01*
X115550Y754433D01*
X115800Y756600D01*
X118050D01*
G01X122400D02*
X121733Y756433D01*
X121233Y756017D01*
X120900Y755517D01*
X120650Y754850D01*
X120567Y754100D01*
X120650Y753350D01*
X120900Y752683D01*
X121233Y752183D01*
X121733Y751767D01*
X122400Y751600D01*
X123067Y751767D01*
X123567Y752183D01*
X123900Y752683D01*
X124150Y753350D01*
X124233Y754100D01*
X124150Y754850D01*
X123900Y755517D01*
X123567Y756017D01*
X123067Y756433D01*
X122400Y756600D01*
G01X133600D02*
Y751600D01*
G01X131683Y756600D02*
X135517D01*
G01X137950Y753850D02*
X140617D01*
X140367Y754433D01*
X139950Y754767D01*
X139367Y754933D01*
X138783Y754850D01*
X138283Y754600D01*
X137950Y754017D01*
X137783Y753517D01*
Y753017D01*
X137950Y752517D01*
X138367Y752017D01*
X138867Y751683D01*
X139450Y751600D01*
X140033Y751767D01*
X140617Y752267D01*
G01X143550Y752183D02*
X143967Y751850D01*
X144550Y751600D01*
X145050D01*
X145550Y751767D01*
X145883Y752017D01*
X146050Y752350D01*
X145967Y752850D01*
X145633Y753100D01*
X144133Y753600D01*
X143800Y754183D01*
X143967Y754600D01*
X144300Y754850D01*
X144800Y754933D01*
X145300Y754850D01*
X145800Y754600D01*
G01X150400Y756600D02*
Y751600D01*
G01X149233Y754933D02*
X151567D01*
G01X159433Y751600D02*
Y756600D01*
X161600Y752433D01*
X163767Y756600D01*
Y751600D01*
G01X165950Y753850D02*
X168617D01*
X168367Y754433D01*
X167950Y754767D01*
X167367Y754933D01*
X166783Y754850D01*
X166283Y754600D01*
X165950Y754017D01*
X165783Y753517D01*
Y753017D01*
X165950Y752517D01*
X166367Y752017D01*
X166867Y751683D01*
X167450Y751600D01*
X168033Y751767D01*
X168617Y752267D01*
G01X172800Y756600D02*
Y751600D01*
G01X171633Y754933D02*
X173967D01*
G01X176983Y751600D02*
Y756600D01*
G01Y754183D02*
X177400Y754600D01*
X177817Y754850D01*
X178483Y754933D01*
X178983Y754850D01*
X179567Y754517D01*
X179817Y754017D01*
Y751600D01*
G01X184000D02*
X183500Y751683D01*
X183000Y752017D01*
X182667Y752600D01*
X182500Y753267D01*
X182667Y753933D01*
X183000Y754517D01*
X183500Y754850D01*
X184000Y754933D01*
X184500Y754850D01*
X185000Y754517D01*
X185333Y753933D01*
X185417Y753267D01*
X185333Y752600D01*
X185000Y752017D01*
X184500Y751683D01*
X184000Y751600D01*
G01X191100Y756600D02*
Y751600D01*
G01Y752350D02*
X190767Y751933D01*
X190267Y751683D01*
X189683Y751600D01*
X189017Y751767D01*
X188517Y752183D01*
X188183Y752683D01*
X188100Y753267D01*
X188183Y753850D01*
X188517Y754350D01*
X189017Y754767D01*
X189683Y754933D01*
X190267Y754850D01*
X190683Y754683D01*
X191100Y754350D01*
G01X193950Y752183D02*
X194367Y751850D01*
X194950Y751600D01*
X195450D01*
X195950Y751767D01*
X196283Y752017D01*
X196450Y752350D01*
X196367Y752850D01*
X196033Y753100D01*
X194533Y753600D01*
X194200Y754183D01*
X194367Y754600D01*
X194700Y754850D01*
X195200Y754933D01*
X195700Y754850D01*
X196200Y754600D01*
G01X204233Y751600D02*
Y756600D01*
X206400Y752433D01*
X208567Y756600D01*
Y751600D01*
G01X213500D02*
Y754933D01*
G01Y754350D02*
X213167Y754683D01*
X212667Y754850D01*
X212083Y754933D01*
X211500Y754767D01*
X211000Y754433D01*
X210667Y753933D01*
X210500Y753267D01*
X210667Y752600D01*
X211000Y752100D01*
X211500Y751767D01*
X212083Y751600D01*
X212667Y751683D01*
X213167Y751933D01*
X213500Y752267D01*
G01X216183Y751600D02*
Y754933D01*
G01Y754100D02*
X216517Y754517D01*
X217017Y754850D01*
X217683Y754933D01*
X218267Y754850D01*
X218767Y754517D01*
X219017Y753933D01*
Y751600D01*
G01X221783Y754933D02*
Y752600D01*
X222117Y752017D01*
X222617Y751683D01*
X223200Y751600D01*
X223783Y751683D01*
X224283Y752017D01*
X224617Y752600D01*
G01Y751600D02*
Y754933D01*
G01X230300Y751600D02*
Y754933D01*
G01Y754350D02*
X229967Y754683D01*
X229467Y754850D01*
X228883Y754933D01*
X228300Y754767D01*
X227800Y754433D01*
X227467Y753933D01*
X227300Y753267D01*
X227467Y752600D01*
X227800Y752100D01*
X228300Y751767D01*
X228883Y751600D01*
X229467Y751683D01*
X229967Y751933D01*
X230300Y752267D01*
G01X234400Y751600D02*
Y756600D01*
G01X71000Y765600D02*
X73000D01*
G01X72000D02*
Y760600D01*
G01X71000D02*
X73000D01*
G01X75933D02*
Y765600D01*
X77933D01*
X78600Y765350D01*
X79100Y764767D01*
X79267Y764100D01*
X79100Y763433D01*
X78683Y762933D01*
X77933Y762683D01*
X75933D01*
G01X85033Y765183D02*
X84533Y765433D01*
X83950Y765600D01*
X83283D01*
X82533Y765350D01*
X81950Y764933D01*
X81533Y764433D01*
X81200Y763600D01*
X81117Y762850D01*
X81283Y762100D01*
X81533Y761600D01*
X82033Y761100D01*
X82617Y760767D01*
X83200Y760600D01*
X83783D01*
X84367Y760767D01*
X84867Y761017D01*
X85283Y761350D01*
G01X87717Y762267D02*
X89883D01*
G01X92817Y762683D02*
X93400Y763267D01*
X93900Y763600D01*
X94567Y763767D01*
X95150Y763600D01*
X95567Y763267D01*
X95900Y762767D01*
X95983Y762183D01*
X95900Y761683D01*
X95567Y761183D01*
X95067Y760767D01*
X94483Y760600D01*
X93817Y760767D01*
X93233Y761267D01*
X92900Y762017D01*
X92817Y762850D01*
X92983Y763933D01*
X93233Y764517D01*
X93650Y765100D01*
X94233Y765517D01*
X94817Y765600D01*
X95400Y765433D01*
X95817Y765017D01*
G01X100000Y765600D02*
X99333Y765433D01*
X98833Y765017D01*
X98500Y764517D01*
X98250Y763850D01*
X98167Y763100D01*
X98250Y762350D01*
X98500Y761683D01*
X98833Y761183D01*
X99333Y760767D01*
X100000Y760600D01*
X100667Y760767D01*
X101167Y761183D01*
X101500Y761683D01*
X101750Y762350D01*
X101833Y763100D01*
X101750Y763850D01*
X101500Y764517D01*
X101167Y765017D01*
X100667Y765433D01*
X100000Y765600D01*
G01X105600Y760600D02*
Y765600D01*
X104600Y764600D01*
G01Y760600D02*
X106600D01*
G01X109617Y762683D02*
X110200Y763267D01*
X110700Y763600D01*
X111367Y763767D01*
X111950Y763600D01*
X112367Y763267D01*
X112700Y762767D01*
X112783Y762183D01*
X112700Y761683D01*
X112367Y761183D01*
X111867Y760767D01*
X111283Y760600D01*
X110617Y760767D01*
X110033Y761267D01*
X109700Y762017D01*
X109617Y762850D01*
X109783Y763933D01*
X110033Y764517D01*
X110450Y765100D01*
X111033Y765517D01*
X111617Y765600D01*
X112200Y765433D01*
X112617Y765017D01*
G01X122400Y760600D02*
X121733Y760683D01*
X121150Y761017D01*
X120650Y761517D01*
X120317Y762100D01*
X120150Y762767D01*
Y763433D01*
X120317Y764100D01*
X120650Y764683D01*
X121150Y765183D01*
X121733Y765517D01*
X122400Y765600D01*
X123067Y765517D01*
X123650Y765183D01*
X124150Y764683D01*
X124483Y764100D01*
X124650Y763433D01*
Y762767D01*
X124483Y762100D01*
X124150Y761517D01*
X123650Y761017D01*
X123067Y760683D01*
X122400Y760600D01*
G01X123067Y761933D02*
X124067Y760600D01*
G01X126583Y763933D02*
Y761600D01*
X126917Y761017D01*
X127417Y760683D01*
X128000Y760600D01*
X128583Y760683D01*
X129083Y761017D01*
X129417Y761600D01*
G01Y760600D02*
Y763933D01*
G01X135100Y760600D02*
Y763933D01*
G01Y763350D02*
X134767Y763683D01*
X134267Y763850D01*
X133683Y763933D01*
X133100Y763767D01*
X132600Y763433D01*
X132267Y762933D01*
X132100Y762267D01*
X132267Y761600D01*
X132600Y761100D01*
X133100Y760767D01*
X133683Y760600D01*
X134267Y760683D01*
X134767Y760933D01*
X135100Y761267D01*
G01X139200Y760600D02*
Y765600D01*
G01X144800Y763933D02*
Y760600D01*
G01Y765267D02*
X144633Y765350D01*
Y765517D01*
X144800Y765600D01*
X144967Y765517D01*
Y765350D01*
X144800Y765267D01*
G01X149900Y760600D02*
Y764850D01*
X150067Y765267D01*
X150400Y765517D01*
X150900Y765600D01*
X151400Y765433D01*
X151650Y765017D01*
G01X150650Y763600D02*
X148983D01*
G01X156000Y763933D02*
Y760600D01*
G01Y765267D02*
X155833Y765350D01*
Y765517D01*
X156000Y765600D01*
X156167Y765517D01*
Y765350D01*
X156000Y765267D01*
G01X162933Y763517D02*
X162350Y763850D01*
X161850Y763933D01*
X161183Y763767D01*
X160683Y763433D01*
X160350Y762850D01*
X160267Y762267D01*
X160350Y761683D01*
X160683Y761183D01*
X161183Y760767D01*
X161850Y760600D01*
X162433Y760767D01*
X162933Y761100D01*
G01X168700Y760600D02*
Y763933D01*
G01Y763350D02*
X168367Y763683D01*
X167867Y763850D01*
X167283Y763933D01*
X166700Y763767D01*
X166200Y763433D01*
X165867Y762933D01*
X165700Y762267D01*
X165867Y761600D01*
X166200Y761100D01*
X166700Y760767D01*
X167283Y760600D01*
X167867Y760683D01*
X168367Y760933D01*
X168700Y761267D01*
G01X172800Y765600D02*
Y760600D01*
G01X171633Y763933D02*
X173967D01*
G01X178400D02*
Y760600D01*
G01Y765267D02*
X178233Y765350D01*
Y765517D01*
X178400Y765600D01*
X178567Y765517D01*
Y765350D01*
X178400Y765267D01*
G01X184000Y760600D02*
X183500Y760683D01*
X183000Y761017D01*
X182667Y761600D01*
X182500Y762267D01*
X182667Y762933D01*
X183000Y763517D01*
X183500Y763850D01*
X184000Y763933D01*
X184500Y763850D01*
X185000Y763517D01*
X185333Y762933D01*
X185417Y762267D01*
X185333Y761600D01*
X185000Y761017D01*
X184500Y760683D01*
X184000Y760600D01*
G01X188183D02*
Y763933D01*
G01Y763100D02*
X188517Y763517D01*
X189017Y763850D01*
X189683Y763933D01*
X190267Y763850D01*
X190767Y763517D01*
X191017Y762933D01*
Y760600D01*
G01X203300Y758933D02*
X199133Y763933D01*
Y764767D01*
X199967Y765600D01*
X200800D01*
X201633Y764767D01*
Y763933D01*
X200800Y763100D01*
X199133Y762267D01*
X198300Y761433D01*
Y759767D01*
X199133Y758933D01*
X201633D01*
X203300Y760600D01*
G01X210333D02*
Y765600D01*
X212333D01*
X213000Y765350D01*
X213500Y764767D01*
X213667Y764100D01*
X213500Y763433D01*
X213083Y762933D01*
X212333Y762683D01*
X210333D01*
G01X216350Y762850D02*
X219017D01*
X218767Y763433D01*
X218350Y763767D01*
X217767Y763933D01*
X217183Y763850D01*
X216683Y763600D01*
X216350Y763017D01*
X216183Y762517D01*
Y762017D01*
X216350Y761517D01*
X216767Y761017D01*
X217267Y760683D01*
X217850Y760600D01*
X218433Y760767D01*
X219017Y761267D01*
G01X222033Y760600D02*
Y763933D01*
G01Y763267D02*
X222450Y763600D01*
X222867Y763850D01*
X223450Y763933D01*
X223867Y763850D01*
X224367Y763600D01*
G01X228300Y760600D02*
Y764850D01*
X228467Y765267D01*
X228800Y765517D01*
X229300Y765600D01*
X229800Y765433D01*
X230050Y765017D01*
G01X229050Y763600D02*
X227383D01*
G01X234400Y760600D02*
X233900Y760683D01*
X233400Y761017D01*
X233067Y761600D01*
X232900Y762267D01*
X233067Y762933D01*
X233400Y763517D01*
X233900Y763850D01*
X234400Y763933D01*
X234900Y763850D01*
X235400Y763517D01*
X235733Y762933D01*
X235817Y762267D01*
X235733Y761600D01*
X235400Y761017D01*
X234900Y760683D01*
X234400Y760600D01*
G01X238833D02*
Y763933D01*
G01Y763267D02*
X239250Y763600D01*
X239667Y763850D01*
X240250Y763933D01*
X240667Y763850D01*
X241167Y763600D01*
G01X243100Y760600D02*
Y763933D01*
G01Y763017D02*
X243350Y763433D01*
X243767Y763767D01*
X244350Y763933D01*
X244933Y763767D01*
X245350Y763433D01*
X245600Y763017D01*
Y760600D01*
G01Y763017D02*
X245850Y763433D01*
X246267Y763767D01*
X246850Y763933D01*
X247433Y763767D01*
X247850Y763433D01*
X248100Y762933D01*
Y760600D01*
G01X252700D02*
Y763933D01*
G01Y763350D02*
X252367Y763683D01*
X251867Y763850D01*
X251283Y763933D01*
X250700Y763767D01*
X250200Y763433D01*
X249867Y762933D01*
X249700Y762267D01*
X249867Y761600D01*
X250200Y761100D01*
X250700Y760767D01*
X251283Y760600D01*
X251867Y760683D01*
X252367Y760933D01*
X252700Y761267D01*
G01X255383Y760600D02*
Y763933D01*
G01Y763100D02*
X255717Y763517D01*
X256217Y763850D01*
X256883Y763933D01*
X257467Y763850D01*
X257967Y763517D01*
X258217Y762933D01*
Y760600D01*
G01X263733Y763517D02*
X263150Y763850D01*
X262650Y763933D01*
X261983Y763767D01*
X261483Y763433D01*
X261150Y762850D01*
X261067Y762267D01*
X261150Y761683D01*
X261483Y761183D01*
X261983Y760767D01*
X262650Y760600D01*
X263233Y760767D01*
X263733Y761100D01*
G01X266750Y762850D02*
X269417D01*
X269167Y763433D01*
X268750Y763767D01*
X268167Y763933D01*
X267583Y763850D01*
X267083Y763600D01*
X266750Y763017D01*
X266583Y762517D01*
Y762017D01*
X266750Y761517D01*
X267167Y761017D01*
X267667Y760683D01*
X268250Y760600D01*
X268833Y760767D01*
X269417Y761267D01*
G01X277450D02*
X278117Y760850D01*
X278867Y760600D01*
X279533D01*
X280200Y760850D01*
X280700Y761267D01*
X280950Y761850D01*
X280783Y762433D01*
X280367Y762933D01*
X279617Y763267D01*
X278617Y763433D01*
X278033Y763767D01*
X277783Y764350D01*
X277950Y764933D01*
X278367Y765350D01*
X278950Y765600D01*
X279533D01*
X280117Y765433D01*
X280617Y765017D01*
G01X283300Y758933D02*
Y763933D01*
G01Y763183D02*
X283717Y763600D01*
X284133Y763850D01*
X284800Y763933D01*
X285383Y763850D01*
X285967Y763433D01*
X286217Y762850D01*
X286300Y762267D01*
X286217Y761683D01*
X285967Y761100D01*
X285467Y760767D01*
X284800Y760600D01*
X284217Y760683D01*
X283633Y760933D01*
X283300Y761267D01*
G01X289150Y762850D02*
X291817D01*
X291567Y763433D01*
X291150Y763767D01*
X290567Y763933D01*
X289983Y763850D01*
X289483Y763600D01*
X289150Y763017D01*
X288983Y762517D01*
Y762017D01*
X289150Y761517D01*
X289567Y761017D01*
X290067Y760683D01*
X290650Y760600D01*
X291233Y760767D01*
X291817Y761267D01*
G01X297333Y763517D02*
X296750Y763850D01*
X296250Y763933D01*
X295583Y763767D01*
X295083Y763433D01*
X294750Y762850D01*
X294667Y762267D01*
X294750Y761683D01*
X295083Y761183D01*
X295583Y760767D01*
X296250Y760600D01*
X296833Y760767D01*
X297333Y761100D01*
G01X301600Y763933D02*
Y760600D01*
G01Y765267D02*
X301433Y765350D01*
Y765517D01*
X301600Y765600D01*
X301767Y765517D01*
Y765350D01*
X301600Y765267D01*
G01X306700Y760600D02*
Y764850D01*
X306867Y765267D01*
X307200Y765517D01*
X307700Y765600D01*
X308200Y765433D01*
X308450Y765017D01*
G01X307450Y763600D02*
X305783D01*
G01X312800Y763933D02*
Y760600D01*
G01Y765267D02*
X312633Y765350D01*
Y765517D01*
X312800Y765600D01*
X312967Y765517D01*
Y765350D01*
X312800Y765267D01*
G01X319733Y763517D02*
X319150Y763850D01*
X318650Y763933D01*
X317983Y763767D01*
X317483Y763433D01*
X317150Y762850D01*
X317067Y762267D01*
X317150Y761683D01*
X317483Y761183D01*
X317983Y760767D01*
X318650Y760600D01*
X319233Y760767D01*
X319733Y761100D01*
G01X325500Y760600D02*
Y763933D01*
G01Y763350D02*
X325167Y763683D01*
X324667Y763850D01*
X324083Y763933D01*
X323500Y763767D01*
X323000Y763433D01*
X322667Y762933D01*
X322500Y762267D01*
X322667Y761600D01*
X323000Y761100D01*
X323500Y760767D01*
X324083Y760600D01*
X324667Y760683D01*
X325167Y760933D01*
X325500Y761267D01*
G01X329600Y765600D02*
Y760600D01*
G01X328433Y763933D02*
X330767D01*
G01X335200D02*
Y760600D01*
G01Y765267D02*
X335033Y765350D01*
Y765517D01*
X335200Y765600D01*
X335367Y765517D01*
Y765350D01*
X335200Y765267D01*
G01X340800Y760600D02*
X340300Y760683D01*
X339800Y761017D01*
X339467Y761600D01*
X339300Y762267D01*
X339467Y762933D01*
X339800Y763517D01*
X340300Y763850D01*
X340800Y763933D01*
X341300Y763850D01*
X341800Y763517D01*
X342133Y762933D01*
X342217Y762267D01*
X342133Y761600D01*
X341800Y761017D01*
X341300Y760683D01*
X340800Y760600D01*
G01X344983D02*
Y763933D01*
G01Y763100D02*
X345317Y763517D01*
X345817Y763850D01*
X346483Y763933D01*
X347067Y763850D01*
X347567Y763517D01*
X347817Y762933D01*
Y760600D01*
G01X357100D02*
Y764850D01*
X357267Y765267D01*
X357600Y765517D01*
X358100Y765600D01*
X358600Y765433D01*
X358850Y765017D01*
G01X357850Y763600D02*
X356183D01*
G01X363200Y760600D02*
X362700Y760683D01*
X362200Y761017D01*
X361867Y761600D01*
X361700Y762267D01*
X361867Y762933D01*
X362200Y763517D01*
X362700Y763850D01*
X363200Y763933D01*
X363700Y763850D01*
X364200Y763517D01*
X364533Y762933D01*
X364617Y762267D01*
X364533Y761600D01*
X364200Y761017D01*
X363700Y760683D01*
X363200Y760600D01*
G01X367633D02*
Y763933D01*
G01Y763267D02*
X368050Y763600D01*
X368467Y763850D01*
X369050Y763933D01*
X369467Y763850D01*
X369967Y763600D01*
G01X378250Y760600D02*
Y765600D01*
G01X381750D02*
Y760600D01*
G01Y763100D02*
X378250D01*
G01X385600Y763933D02*
Y760600D01*
G01Y765267D02*
X385433Y765350D01*
Y765517D01*
X385600Y765600D01*
X385767Y765517D01*
Y765350D01*
X385600Y765267D01*
G01X390033Y759350D02*
X390617Y759017D01*
X391283Y758933D01*
X391867Y759017D01*
X392367Y759433D01*
X392700Y760017D01*
Y763933D01*
G01Y763267D02*
X392367Y763600D01*
X391867Y763850D01*
X391283Y763933D01*
X390617Y763767D01*
X390200Y763433D01*
X389867Y762850D01*
X389700Y762267D01*
X389783Y761767D01*
X390117Y761183D01*
X390617Y760767D01*
X391283Y760600D01*
X391783Y760683D01*
X392367Y761017D01*
X392700Y761350D01*
G01X395383Y760600D02*
Y765600D01*
G01Y763183D02*
X395800Y763600D01*
X396217Y763850D01*
X396883Y763933D01*
X397383Y763850D01*
X397967Y763517D01*
X398217Y763017D01*
Y760600D01*
G01X406167D02*
Y765600D01*
X407833D01*
X408500Y765350D01*
X409000Y765017D01*
X409417Y764517D01*
X409750Y763933D01*
X409833Y763100D01*
X409750Y762267D01*
X409417Y761683D01*
X409000Y761183D01*
X408500Y760850D01*
X407833Y760600D01*
X406167D01*
G01X412350Y762850D02*
X415017D01*
X414767Y763433D01*
X414350Y763767D01*
X413767Y763933D01*
X413183Y763850D01*
X412683Y763600D01*
X412350Y763017D01*
X412183Y762517D01*
Y762017D01*
X412350Y761517D01*
X412767Y761017D01*
X413267Y760683D01*
X413850Y760600D01*
X414433Y760767D01*
X415017Y761267D01*
G01X417783Y760600D02*
Y763933D01*
G01Y763100D02*
X418117Y763517D01*
X418617Y763850D01*
X419283Y763933D01*
X419867Y763850D01*
X420367Y763517D01*
X420617Y762933D01*
Y760600D01*
G01X423550Y761183D02*
X423967Y760850D01*
X424550Y760600D01*
X425050D01*
X425550Y760767D01*
X425883Y761017D01*
X426050Y761350D01*
X425967Y761850D01*
X425633Y762100D01*
X424133Y762600D01*
X423800Y763183D01*
X423967Y763600D01*
X424300Y763850D01*
X424800Y763933D01*
X425300Y763850D01*
X425800Y763600D01*
G01X430400Y763933D02*
Y760600D01*
G01Y765267D02*
X430233Y765350D01*
Y765517D01*
X430400Y765600D01*
X430567Y765517D01*
Y765350D01*
X430400Y765267D01*
G01X436000Y765600D02*
Y760600D01*
G01X434833Y763933D02*
X437167D01*
G01X439850Y759100D02*
X440350Y758933D01*
X441017Y759100D01*
X441433Y759433D01*
X441767Y759850D01*
X442267Y761183D01*
X443350Y763933D01*
G01X440683D02*
X442267Y761183D01*
G01X451800Y765600D02*
X453800D01*
G01X452800D02*
Y760600D01*
G01X451800D02*
X453800D01*
G01X456983D02*
Y763933D01*
G01Y763100D02*
X457317Y763517D01*
X457817Y763850D01*
X458483Y763933D01*
X459067Y763850D01*
X459567Y763517D01*
X459817Y762933D01*
Y760600D01*
G01X464000Y765600D02*
Y760600D01*
G01X462833Y763933D02*
X465167D01*
G01X468350Y762850D02*
X471017D01*
X470767Y763433D01*
X470350Y763767D01*
X469767Y763933D01*
X469183Y763850D01*
X468683Y763600D01*
X468350Y763017D01*
X468183Y762517D01*
Y762017D01*
X468350Y761517D01*
X468767Y761017D01*
X469267Y760683D01*
X469850Y760600D01*
X470433Y760767D01*
X471017Y761267D01*
G01X474033Y760600D02*
Y763933D01*
G01Y763267D02*
X474450Y763600D01*
X474867Y763850D01*
X475450Y763933D01*
X475867Y763850D01*
X476367Y763600D01*
G01X482133Y763517D02*
X481550Y763850D01*
X481050Y763933D01*
X480383Y763767D01*
X479883Y763433D01*
X479550Y762850D01*
X479467Y762267D01*
X479550Y761683D01*
X479883Y761183D01*
X480383Y760767D01*
X481050Y760600D01*
X481633Y760767D01*
X482133Y761100D01*
G01X486400Y760600D02*
X485900Y760683D01*
X485400Y761017D01*
X485067Y761600D01*
X484900Y762267D01*
X485067Y762933D01*
X485400Y763517D01*
X485900Y763850D01*
X486400Y763933D01*
X486900Y763850D01*
X487400Y763517D01*
X487733Y762933D01*
X487817Y762267D01*
X487733Y761600D01*
X487400Y761017D01*
X486900Y760683D01*
X486400Y760600D01*
G01X490583D02*
Y763933D01*
G01Y763100D02*
X490917Y763517D01*
X491417Y763850D01*
X492083Y763933D01*
X492667Y763850D01*
X493167Y763517D01*
X493417Y762933D01*
Y760600D01*
G01X496183D02*
Y763933D01*
G01Y763100D02*
X496517Y763517D01*
X497017Y763850D01*
X497683Y763933D01*
X498267Y763850D01*
X498767Y763517D01*
X499017Y762933D01*
Y760600D01*
G01X501950Y762850D02*
X504617D01*
X504367Y763433D01*
X503950Y763767D01*
X503367Y763933D01*
X502783Y763850D01*
X502283Y763600D01*
X501950Y763017D01*
X501783Y762517D01*
Y762017D01*
X501950Y761517D01*
X502367Y761017D01*
X502867Y760683D01*
X503450Y760600D01*
X504033Y760767D01*
X504617Y761267D01*
G01X510133Y763517D02*
X509550Y763850D01*
X509050Y763933D01*
X508383Y763767D01*
X507883Y763433D01*
X507550Y762850D01*
X507467Y762267D01*
X507550Y761683D01*
X507883Y761183D01*
X508383Y760767D01*
X509050Y760600D01*
X509633Y760767D01*
X510133Y761100D01*
G01X514400Y765600D02*
Y760600D01*
G01X513233Y763933D02*
X515567D01*
G01X519583Y758933D02*
X518750Y759767D01*
X518333Y760600D01*
Y763933D01*
X518750Y764767D01*
X519583Y765600D01*
G01X523850Y760600D02*
Y765600D01*
G01X527350D02*
Y760600D01*
G01Y763100D02*
X523850D01*
G01X529367Y760600D02*
Y765600D01*
X531033D01*
X531700Y765350D01*
X532200Y765017D01*
X532617Y764517D01*
X532950Y763933D01*
X533033Y763100D01*
X532950Y762267D01*
X532617Y761683D01*
X532200Y761183D01*
X531700Y760850D01*
X531033Y760600D01*
X529367D01*
G01X535800Y765600D02*
X537800D01*
G01X536800D02*
Y760600D01*
G01X535800D02*
X537800D01*
G01X542817Y758933D02*
X543650Y759767D01*
X544067Y760600D01*
Y763933D01*
X543650Y764767D01*
X542817Y765600D01*
G01X551933D02*
Y760600D01*
X555267D01*
G01X560700D02*
Y763933D01*
G01Y763350D02*
X560367Y763683D01*
X559867Y763850D01*
X559283Y763933D01*
X558700Y763767D01*
X558200Y763433D01*
X557867Y762933D01*
X557700Y762267D01*
X557867Y761600D01*
X558200Y761100D01*
X558700Y760767D01*
X559283Y760600D01*
X559867Y760683D01*
X560367Y760933D01*
X560700Y761267D01*
G01X563050Y759100D02*
X563550Y758933D01*
X564217Y759100D01*
X564633Y759433D01*
X564967Y759850D01*
X565467Y761183D01*
X566550Y763933D01*
G01X563883D02*
X565467Y761183D01*
G01X569150Y762850D02*
X571817D01*
X571567Y763433D01*
X571150Y763767D01*
X570567Y763933D01*
X569983Y763850D01*
X569483Y763600D01*
X569150Y763017D01*
X568983Y762517D01*
Y762017D01*
X569150Y761517D01*
X569567Y761017D01*
X570067Y760683D01*
X570650Y760600D01*
X571233Y760767D01*
X571817Y761267D01*
G01X574833Y760600D02*
Y763933D01*
G01Y763267D02*
X575250Y763600D01*
X575667Y763850D01*
X576250Y763933D01*
X576667Y763850D01*
X577167Y763600D01*
G01X580350Y761183D02*
X580767Y760850D01*
X581350Y760600D01*
X581850D01*
X582350Y760767D01*
X582683Y761017D01*
X582850Y761350D01*
X582767Y761850D01*
X582433Y762100D01*
X580933Y762600D01*
X580600Y763183D01*
X580767Y763600D01*
X581100Y763850D01*
X581600Y763933D01*
X582100Y763850D01*
X582600Y763600D01*
G01X592800Y760600D02*
X592300Y760683D01*
X591800Y761017D01*
X591467Y761600D01*
X591300Y762267D01*
X591467Y762933D01*
X591800Y763517D01*
X592300Y763850D01*
X592800Y763933D01*
X593300Y763850D01*
X593800Y763517D01*
X594133Y762933D01*
X594217Y762267D01*
X594133Y761600D01*
X593800Y761017D01*
X593300Y760683D01*
X592800Y760600D01*
G01X597233D02*
Y763933D01*
G01Y763267D02*
X597650Y763600D01*
X598067Y763850D01*
X598650Y763933D01*
X599067Y763850D01*
X599567Y763600D01*
G01X610267Y763267D02*
X610600Y763517D01*
X610850Y763933D01*
X611017Y764517D01*
X610850Y765017D01*
X610517Y765350D01*
X609933Y765600D01*
X607683D01*
Y760600D01*
X610433D01*
X611017Y760933D01*
X611350Y761433D01*
X611517Y762017D01*
X611350Y762600D01*
X610850Y763100D01*
X610267Y763267D01*
X607683D01*
G01X615200Y760600D02*
X614700Y760683D01*
X614200Y761017D01*
X613867Y761600D01*
X613700Y762267D01*
X613867Y762933D01*
X614200Y763517D01*
X614700Y763850D01*
X615200Y763933D01*
X615700Y763850D01*
X616200Y763517D01*
X616533Y762933D01*
X616617Y762267D01*
X616533Y761600D01*
X616200Y761017D01*
X615700Y760683D01*
X615200Y760600D01*
G01X622300D02*
Y763933D01*
G01Y763350D02*
X621967Y763683D01*
X621467Y763850D01*
X620883Y763933D01*
X620300Y763767D01*
X619800Y763433D01*
X619467Y762933D01*
X619300Y762267D01*
X619467Y761600D01*
X619800Y761100D01*
X620300Y760767D01*
X620883Y760600D01*
X621467Y760683D01*
X621967Y760933D01*
X622300Y761267D01*
G01X625233Y760600D02*
Y763933D01*
G01Y763267D02*
X625650Y763600D01*
X626067Y763850D01*
X626650Y763933D01*
X627067Y763850D01*
X627567Y763600D01*
G01X633500Y765600D02*
Y760600D01*
G01Y761350D02*
X633167Y760933D01*
X632667Y760683D01*
X632083Y760600D01*
X631417Y760767D01*
X630917Y761183D01*
X630583Y761683D01*
X630500Y762267D01*
X630583Y762850D01*
X630917Y763350D01*
X631417Y763767D01*
X632083Y763933D01*
X632667Y763850D01*
X633083Y763683D01*
X633500Y763350D01*
G01X636350Y761183D02*
X636767Y760850D01*
X637350Y760600D01*
X637850D01*
X638350Y760767D01*
X638683Y761017D01*
X638850Y761350D01*
X638767Y761850D01*
X638433Y762100D01*
X636933Y762600D01*
X636600Y763183D01*
X636767Y763600D01*
X637100Y763850D01*
X637600Y763933D01*
X638100Y763850D01*
X638600Y763600D01*
G01X643617Y758933D02*
X644450Y759767D01*
X644867Y760600D01*
Y763933D01*
X644450Y764767D01*
X643617Y765600D01*
G01X71000Y774600D02*
X73000D01*
G01X72000D02*
Y769600D01*
G01X71000D02*
X73000D01*
G01X75933D02*
Y774600D01*
X77933D01*
X78600Y774350D01*
X79100Y773767D01*
X79267Y773100D01*
X79100Y772433D01*
X78683Y771933D01*
X77933Y771683D01*
X75933D01*
G01X85033Y774183D02*
X84533Y774433D01*
X83950Y774600D01*
X83283D01*
X82533Y774350D01*
X81950Y773933D01*
X81533Y773433D01*
X81200Y772600D01*
X81117Y771850D01*
X81283Y771100D01*
X81533Y770600D01*
X82033Y770100D01*
X82617Y769767D01*
X83200Y769600D01*
X83783D01*
X84367Y769767D01*
X84867Y770017D01*
X85283Y770350D01*
G01X87717Y771267D02*
X89883D01*
G01X92817Y771683D02*
X93400Y772267D01*
X93900Y772600D01*
X94567Y772767D01*
X95150Y772600D01*
X95567Y772267D01*
X95900Y771767D01*
X95983Y771183D01*
X95900Y770683D01*
X95567Y770183D01*
X95067Y769767D01*
X94483Y769600D01*
X93817Y769767D01*
X93233Y770267D01*
X92900Y771017D01*
X92817Y771850D01*
X92983Y772933D01*
X93233Y773517D01*
X93650Y774100D01*
X94233Y774517D01*
X94817Y774600D01*
X95400Y774433D01*
X95817Y774017D01*
G01X100000Y774600D02*
X99333Y774433D01*
X98833Y774017D01*
X98500Y773517D01*
X98250Y772850D01*
X98167Y772100D01*
X98250Y771350D01*
X98500Y770683D01*
X98833Y770183D01*
X99333Y769767D01*
X100000Y769600D01*
X100667Y769767D01*
X101167Y770183D01*
X101500Y770683D01*
X101750Y771350D01*
X101833Y772100D01*
X101750Y772850D01*
X101500Y773517D01*
X101167Y774017D01*
X100667Y774433D01*
X100000Y774600D01*
G01X105600Y769600D02*
Y774600D01*
X104600Y773600D01*
G01Y769600D02*
X106600D01*
G01X109617Y773767D02*
X110117Y774267D01*
X110700Y774517D01*
X111367Y774600D01*
X112200Y774433D01*
X112783Y774017D01*
X112950Y773517D01*
X112867Y773017D01*
X112533Y772600D01*
X110867Y771767D01*
X110117Y771183D01*
X109617Y770350D01*
X109450Y769600D01*
X112950D01*
G01X122400D02*
X121733Y769683D01*
X121150Y770017D01*
X120650Y770517D01*
X120317Y771100D01*
X120150Y771767D01*
Y772433D01*
X120317Y773100D01*
X120650Y773683D01*
X121150Y774183D01*
X121733Y774517D01*
X122400Y774600D01*
X123067Y774517D01*
X123650Y774183D01*
X124150Y773683D01*
X124483Y773100D01*
X124650Y772433D01*
Y771767D01*
X124483Y771100D01*
X124150Y770517D01*
X123650Y770017D01*
X123067Y769683D01*
X122400Y769600D01*
G01X123067Y770933D02*
X124067Y769600D01*
G01X126583Y772933D02*
Y770600D01*
X126917Y770017D01*
X127417Y769683D01*
X128000Y769600D01*
X128583Y769683D01*
X129083Y770017D01*
X129417Y770600D01*
G01Y769600D02*
Y772933D01*
G01X135100Y769600D02*
Y772933D01*
G01Y772350D02*
X134767Y772683D01*
X134267Y772850D01*
X133683Y772933D01*
X133100Y772767D01*
X132600Y772433D01*
X132267Y771933D01*
X132100Y771267D01*
X132267Y770600D01*
X132600Y770100D01*
X133100Y769767D01*
X133683Y769600D01*
X134267Y769683D01*
X134767Y769933D01*
X135100Y770267D01*
G01X139200Y769600D02*
Y774600D01*
G01X144800Y772933D02*
Y769600D01*
G01Y774267D02*
X144633Y774350D01*
Y774517D01*
X144800Y774600D01*
X144967Y774517D01*
Y774350D01*
X144800Y774267D01*
G01X149900Y769600D02*
Y773850D01*
X150067Y774267D01*
X150400Y774517D01*
X150900Y774600D01*
X151400Y774433D01*
X151650Y774017D01*
G01X150650Y772600D02*
X148983D01*
G01X156000Y772933D02*
Y769600D01*
G01Y774267D02*
X155833Y774350D01*
Y774517D01*
X156000Y774600D01*
X156167Y774517D01*
Y774350D01*
X156000Y774267D01*
G01X162933Y772517D02*
X162350Y772850D01*
X161850Y772933D01*
X161183Y772767D01*
X160683Y772433D01*
X160350Y771850D01*
X160267Y771267D01*
X160350Y770683D01*
X160683Y770183D01*
X161183Y769767D01*
X161850Y769600D01*
X162433Y769767D01*
X162933Y770100D01*
G01X168700Y769600D02*
Y772933D01*
G01Y772350D02*
X168367Y772683D01*
X167867Y772850D01*
X167283Y772933D01*
X166700Y772767D01*
X166200Y772433D01*
X165867Y771933D01*
X165700Y771267D01*
X165867Y770600D01*
X166200Y770100D01*
X166700Y769767D01*
X167283Y769600D01*
X167867Y769683D01*
X168367Y769933D01*
X168700Y770267D01*
G01X172800Y774600D02*
Y769600D01*
G01X171633Y772933D02*
X173967D01*
G01X178400D02*
Y769600D01*
G01Y774267D02*
X178233Y774350D01*
Y774517D01*
X178400Y774600D01*
X178567Y774517D01*
Y774350D01*
X178400Y774267D01*
G01X184000Y769600D02*
X183500Y769683D01*
X183000Y770017D01*
X182667Y770600D01*
X182500Y771267D01*
X182667Y771933D01*
X183000Y772517D01*
X183500Y772850D01*
X184000Y772933D01*
X184500Y772850D01*
X185000Y772517D01*
X185333Y771933D01*
X185417Y771267D01*
X185333Y770600D01*
X185000Y770017D01*
X184500Y769683D01*
X184000Y769600D01*
G01X188183D02*
Y772933D01*
G01Y772100D02*
X188517Y772517D01*
X189017Y772850D01*
X189683Y772933D01*
X190267Y772850D01*
X190767Y772517D01*
X191017Y771933D01*
Y769600D01*
G01X202300D02*
Y772933D01*
G01Y772350D02*
X201967Y772683D01*
X201467Y772850D01*
X200883Y772933D01*
X200300Y772767D01*
X199800Y772433D01*
X199467Y771933D01*
X199300Y771267D01*
X199467Y770600D01*
X199800Y770100D01*
X200300Y769767D01*
X200883Y769600D01*
X201467Y769683D01*
X201967Y769933D01*
X202300Y770267D01*
G01X204983Y769600D02*
Y772933D01*
G01Y772100D02*
X205317Y772517D01*
X205817Y772850D01*
X206483Y772933D01*
X207067Y772850D01*
X207567Y772517D01*
X207817Y771933D01*
Y769600D01*
G01X213500Y774600D02*
Y769600D01*
G01Y770350D02*
X213167Y769933D01*
X212667Y769683D01*
X212083Y769600D01*
X211417Y769767D01*
X210917Y770183D01*
X210583Y770683D01*
X210500Y771267D01*
X210583Y771850D01*
X210917Y772350D01*
X211417Y772767D01*
X212083Y772933D01*
X212667Y772850D01*
X213083Y772683D01*
X213500Y772350D01*
G01X221533Y769600D02*
Y774600D01*
X223533D01*
X224200Y774350D01*
X224700Y773767D01*
X224867Y773100D01*
X224700Y772433D01*
X224283Y771933D01*
X223533Y771683D01*
X221533D01*
G01X227550Y771850D02*
X230217D01*
X229967Y772433D01*
X229550Y772767D01*
X228967Y772933D01*
X228383Y772850D01*
X227883Y772600D01*
X227550Y772017D01*
X227383Y771517D01*
Y771017D01*
X227550Y770517D01*
X227967Y770017D01*
X228467Y769683D01*
X229050Y769600D01*
X229633Y769767D01*
X230217Y770267D01*
G01X233233Y769600D02*
Y772933D01*
G01Y772267D02*
X233650Y772600D01*
X234067Y772850D01*
X234650Y772933D01*
X235067Y772850D01*
X235567Y772600D01*
G01X239500Y769600D02*
Y773850D01*
X239667Y774267D01*
X240000Y774517D01*
X240500Y774600D01*
X241000Y774433D01*
X241250Y774017D01*
G01X240250Y772600D02*
X238583D01*
G01X245600Y769600D02*
X245100Y769683D01*
X244600Y770017D01*
X244267Y770600D01*
X244100Y771267D01*
X244267Y771933D01*
X244600Y772517D01*
X245100Y772850D01*
X245600Y772933D01*
X246100Y772850D01*
X246600Y772517D01*
X246933Y771933D01*
X247017Y771267D01*
X246933Y770600D01*
X246600Y770017D01*
X246100Y769683D01*
X245600Y769600D01*
G01X250033D02*
Y772933D01*
G01Y772267D02*
X250450Y772600D01*
X250867Y772850D01*
X251450Y772933D01*
X251867Y772850D01*
X252367Y772600D01*
G01X254300Y769600D02*
Y772933D01*
G01Y772017D02*
X254550Y772433D01*
X254967Y772767D01*
X255550Y772933D01*
X256133Y772767D01*
X256550Y772433D01*
X256800Y772017D01*
Y769600D01*
G01Y772017D02*
X257050Y772433D01*
X257467Y772767D01*
X258050Y772933D01*
X258633Y772767D01*
X259050Y772433D01*
X259300Y771933D01*
Y769600D01*
G01X263900D02*
Y772933D01*
G01Y772350D02*
X263567Y772683D01*
X263067Y772850D01*
X262483Y772933D01*
X261900Y772767D01*
X261400Y772433D01*
X261067Y771933D01*
X260900Y771267D01*
X261067Y770600D01*
X261400Y770100D01*
X261900Y769767D01*
X262483Y769600D01*
X263067Y769683D01*
X263567Y769933D01*
X263900Y770267D01*
G01X266583Y769600D02*
Y772933D01*
G01Y772100D02*
X266917Y772517D01*
X267417Y772850D01*
X268083Y772933D01*
X268667Y772850D01*
X269167Y772517D01*
X269417Y771933D01*
Y769600D01*
G01X274933Y772517D02*
X274350Y772850D01*
X273850Y772933D01*
X273183Y772767D01*
X272683Y772433D01*
X272350Y771850D01*
X272267Y771267D01*
X272350Y770683D01*
X272683Y770183D01*
X273183Y769767D01*
X273850Y769600D01*
X274433Y769767D01*
X274933Y770100D01*
G01X277950Y771850D02*
X280617D01*
X280367Y772433D01*
X279950Y772767D01*
X279367Y772933D01*
X278783Y772850D01*
X278283Y772600D01*
X277950Y772017D01*
X277783Y771517D01*
Y771017D01*
X277950Y770517D01*
X278367Y770017D01*
X278867Y769683D01*
X279450Y769600D01*
X280033Y769767D01*
X280617Y770267D01*
G01X288650D02*
X289317Y769850D01*
X290067Y769600D01*
X290733D01*
X291400Y769850D01*
X291900Y770267D01*
X292150Y770850D01*
X291983Y771433D01*
X291567Y771933D01*
X290817Y772267D01*
X289817Y772433D01*
X289233Y772767D01*
X288983Y773350D01*
X289150Y773933D01*
X289567Y774350D01*
X290150Y774600D01*
X290733D01*
X291317Y774433D01*
X291817Y774017D01*
G01X294500Y767933D02*
Y772933D01*
G01Y772183D02*
X294917Y772600D01*
X295333Y772850D01*
X296000Y772933D01*
X296583Y772850D01*
X297167Y772433D01*
X297417Y771850D01*
X297500Y771267D01*
X297417Y770683D01*
X297167Y770100D01*
X296667Y769767D01*
X296000Y769600D01*
X295417Y769683D01*
X294833Y769933D01*
X294500Y770267D01*
G01X300350Y771850D02*
X303017D01*
X302767Y772433D01*
X302350Y772767D01*
X301767Y772933D01*
X301183Y772850D01*
X300683Y772600D01*
X300350Y772017D01*
X300183Y771517D01*
Y771017D01*
X300350Y770517D01*
X300767Y770017D01*
X301267Y769683D01*
X301850Y769600D01*
X302433Y769767D01*
X303017Y770267D01*
G01X308533Y772517D02*
X307950Y772850D01*
X307450Y772933D01*
X306783Y772767D01*
X306283Y772433D01*
X305950Y771850D01*
X305867Y771267D01*
X305950Y770683D01*
X306283Y770183D01*
X306783Y769767D01*
X307450Y769600D01*
X308033Y769767D01*
X308533Y770100D01*
G01X312800Y772933D02*
Y769600D01*
G01Y774267D02*
X312633Y774350D01*
Y774517D01*
X312800Y774600D01*
X312967Y774517D01*
Y774350D01*
X312800Y774267D01*
G01X317900Y769600D02*
Y773850D01*
X318067Y774267D01*
X318400Y774517D01*
X318900Y774600D01*
X319400Y774433D01*
X319650Y774017D01*
G01X318650Y772600D02*
X316983D01*
G01X324000Y772933D02*
Y769600D01*
G01Y774267D02*
X323833Y774350D01*
Y774517D01*
X324000Y774600D01*
X324167Y774517D01*
Y774350D01*
X324000Y774267D01*
G01X330933Y772517D02*
X330350Y772850D01*
X329850Y772933D01*
X329183Y772767D01*
X328683Y772433D01*
X328350Y771850D01*
X328267Y771267D01*
X328350Y770683D01*
X328683Y770183D01*
X329183Y769767D01*
X329850Y769600D01*
X330433Y769767D01*
X330933Y770100D01*
G01X336700Y769600D02*
Y772933D01*
G01Y772350D02*
X336367Y772683D01*
X335867Y772850D01*
X335283Y772933D01*
X334700Y772767D01*
X334200Y772433D01*
X333867Y771933D01*
X333700Y771267D01*
X333867Y770600D01*
X334200Y770100D01*
X334700Y769767D01*
X335283Y769600D01*
X335867Y769683D01*
X336367Y769933D01*
X336700Y770267D01*
G01X340800Y774600D02*
Y769600D01*
G01X339633Y772933D02*
X341967D01*
G01X346400D02*
Y769600D01*
G01Y774267D02*
X346233Y774350D01*
Y774517D01*
X346400Y774600D01*
X346567Y774517D01*
Y774350D01*
X346400Y774267D01*
G01X352000Y769600D02*
X351500Y769683D01*
X351000Y770017D01*
X350667Y770600D01*
X350500Y771267D01*
X350667Y771933D01*
X351000Y772517D01*
X351500Y772850D01*
X352000Y772933D01*
X352500Y772850D01*
X353000Y772517D01*
X353333Y771933D01*
X353417Y771267D01*
X353333Y770600D01*
X353000Y770017D01*
X352500Y769683D01*
X352000Y769600D01*
G01X356183D02*
Y772933D01*
G01Y772100D02*
X356517Y772517D01*
X357017Y772850D01*
X357683Y772933D01*
X358267Y772850D01*
X358767Y772517D01*
X359017Y771933D01*
Y769600D01*
G01X368300D02*
Y773850D01*
X368467Y774267D01*
X368800Y774517D01*
X369300Y774600D01*
X369800Y774433D01*
X370050Y774017D01*
G01X369050Y772600D02*
X367383D01*
G01X374400Y769600D02*
X373900Y769683D01*
X373400Y770017D01*
X373067Y770600D01*
X372900Y771267D01*
X373067Y771933D01*
X373400Y772517D01*
X373900Y772850D01*
X374400Y772933D01*
X374900Y772850D01*
X375400Y772517D01*
X375733Y771933D01*
X375817Y771267D01*
X375733Y770600D01*
X375400Y770017D01*
X374900Y769683D01*
X374400Y769600D01*
G01X378833D02*
Y772933D01*
G01Y772267D02*
X379250Y772600D01*
X379667Y772850D01*
X380250Y772933D01*
X380667Y772850D01*
X381167Y772600D01*
G01X389533Y769600D02*
Y774600D01*
X391617D01*
X392283Y774350D01*
X392700Y774017D01*
X392867Y773350D01*
X392700Y772683D01*
X392200Y772267D01*
X391617Y772017D01*
X389533D01*
G01X391617D02*
X392867Y769600D01*
G01X396800Y772933D02*
Y769600D01*
G01Y774267D02*
X396633Y774350D01*
Y774517D01*
X396800Y774600D01*
X396967Y774517D01*
Y774350D01*
X396800Y774267D01*
G01X401233Y768350D02*
X401817Y768017D01*
X402483Y767933D01*
X403067Y768017D01*
X403567Y768433D01*
X403900Y769017D01*
Y772933D01*
G01Y772267D02*
X403567Y772600D01*
X403067Y772850D01*
X402483Y772933D01*
X401817Y772767D01*
X401400Y772433D01*
X401067Y771850D01*
X400900Y771267D01*
X400983Y770767D01*
X401317Y770183D01*
X401817Y769767D01*
X402483Y769600D01*
X402983Y769683D01*
X403567Y770017D01*
X403900Y770350D01*
G01X408000Y772933D02*
Y769600D01*
G01Y774267D02*
X407833Y774350D01*
Y774517D01*
X408000Y774600D01*
X408167Y774517D01*
Y774350D01*
X408000Y774267D01*
G01X415100Y774600D02*
Y769600D01*
G01Y770350D02*
X414767Y769933D01*
X414267Y769683D01*
X413683Y769600D01*
X413017Y769767D01*
X412517Y770183D01*
X412183Y770683D01*
X412100Y771267D01*
X412183Y771850D01*
X412517Y772350D01*
X413017Y772767D01*
X413683Y772933D01*
X414267Y772850D01*
X414683Y772683D01*
X415100Y772350D01*
G01X423133Y769600D02*
Y774600D01*
X425133D01*
X425800Y774350D01*
X426300Y773767D01*
X426467Y773100D01*
X426300Y772433D01*
X425883Y771933D01*
X425133Y771683D01*
X423133D01*
G01X429233Y769600D02*
Y772933D01*
G01Y772267D02*
X429650Y772600D01*
X430067Y772850D01*
X430650Y772933D01*
X431067Y772850D01*
X431567Y772600D01*
G01X436000Y772933D02*
Y769600D01*
G01Y774267D02*
X435833Y774350D01*
Y774517D01*
X436000Y774600D01*
X436167Y774517D01*
Y774350D01*
X436000Y774267D01*
G01X440183Y769600D02*
Y772933D01*
G01Y772100D02*
X440517Y772517D01*
X441017Y772850D01*
X441683Y772933D01*
X442267Y772850D01*
X442767Y772517D01*
X443017Y771933D01*
Y769600D01*
G01X447200Y774600D02*
Y769600D01*
G01X446033Y772933D02*
X448367D01*
G01X451550Y771850D02*
X454217D01*
X453967Y772433D01*
X453550Y772767D01*
X452967Y772933D01*
X452383Y772850D01*
X451883Y772600D01*
X451550Y772017D01*
X451383Y771517D01*
Y771017D01*
X451550Y770517D01*
X451967Y770017D01*
X452467Y769683D01*
X453050Y769600D01*
X453633Y769767D01*
X454217Y770267D01*
G01X459900Y774600D02*
Y769600D01*
G01Y770350D02*
X459567Y769933D01*
X459067Y769683D01*
X458483Y769600D01*
X457817Y769767D01*
X457317Y770183D01*
X456983Y770683D01*
X456900Y771267D01*
X456983Y771850D01*
X457317Y772350D01*
X457817Y772767D01*
X458483Y772933D01*
X459067Y772850D01*
X459483Y772683D01*
X459900Y772350D01*
G01X470267Y772267D02*
X470600Y772517D01*
X470850Y772933D01*
X471017Y773517D01*
X470850Y774017D01*
X470517Y774350D01*
X469933Y774600D01*
X467683D01*
Y769600D01*
X470433D01*
X471017Y769933D01*
X471350Y770433D01*
X471517Y771017D01*
X471350Y771600D01*
X470850Y772100D01*
X470267Y772267D01*
X467683D01*
G01X475200Y769600D02*
X474700Y769683D01*
X474200Y770017D01*
X473867Y770600D01*
X473700Y771267D01*
X473867Y771933D01*
X474200Y772517D01*
X474700Y772850D01*
X475200Y772933D01*
X475700Y772850D01*
X476200Y772517D01*
X476533Y771933D01*
X476617Y771267D01*
X476533Y770600D01*
X476200Y770017D01*
X475700Y769683D01*
X475200Y769600D01*
G01X482300D02*
Y772933D01*
G01Y772350D02*
X481967Y772683D01*
X481467Y772850D01*
X480883Y772933D01*
X480300Y772767D01*
X479800Y772433D01*
X479467Y771933D01*
X479300Y771267D01*
X479467Y770600D01*
X479800Y770100D01*
X480300Y769767D01*
X480883Y769600D01*
X481467Y769683D01*
X481967Y769933D01*
X482300Y770267D01*
G01X485233Y769600D02*
Y772933D01*
G01Y772267D02*
X485650Y772600D01*
X486067Y772850D01*
X486650Y772933D01*
X487067Y772850D01*
X487567Y772600D01*
G01X493500Y774600D02*
Y769600D01*
G01Y770350D02*
X493167Y769933D01*
X492667Y769683D01*
X492083Y769600D01*
X491417Y769767D01*
X490917Y770183D01*
X490583Y770683D01*
X490500Y771267D01*
X490583Y771850D01*
X490917Y772350D01*
X491417Y772767D01*
X492083Y772933D01*
X492667Y772850D01*
X493083Y772683D01*
X493500Y772350D01*
G01X496350Y770183D02*
X496767Y769850D01*
X497350Y769600D01*
X497850D01*
X498350Y769767D01*
X498683Y770017D01*
X498850Y770350D01*
X498767Y770850D01*
X498433Y771100D01*
X496933Y771600D01*
X496600Y772183D01*
X496767Y772600D01*
X497100Y772850D01*
X497600Y772933D01*
X498100Y772850D01*
X498600Y772600D01*
G01X67000Y779433D02*
X66833Y779517D01*
Y779683D01*
X67000Y779767D01*
X67167Y779683D01*
Y779517D01*
X67000Y779433D01*
G01Y786333D02*
X66833Y786417D01*
Y786583D01*
X67000Y786667D01*
X67167Y786583D01*
Y786417D01*
X67000Y786333D01*
G01X71000Y783600D02*
X73000D01*
G01X72000D02*
Y778600D01*
G01X71000D02*
X73000D01*
G01X75933D02*
Y783600D01*
X77933D01*
X78600Y783350D01*
X79100Y782767D01*
X79267Y782100D01*
X79100Y781433D01*
X78683Y780933D01*
X77933Y780683D01*
X75933D01*
G01X85033Y783183D02*
X84533Y783433D01*
X83950Y783600D01*
X83283D01*
X82533Y783350D01*
X81950Y782933D01*
X81533Y782433D01*
X81200Y781600D01*
X81117Y780850D01*
X81283Y780100D01*
X81533Y779600D01*
X82033Y779100D01*
X82617Y778767D01*
X83200Y778600D01*
X83783D01*
X84367Y778767D01*
X84867Y779017D01*
X85283Y779350D01*
G01X87717Y780267D02*
X89883D01*
G01X92817Y780683D02*
X93400Y781267D01*
X93900Y781600D01*
X94567Y781767D01*
X95150Y781600D01*
X95567Y781267D01*
X95900Y780767D01*
X95983Y780183D01*
X95900Y779683D01*
X95567Y779183D01*
X95067Y778767D01*
X94483Y778600D01*
X93817Y778767D01*
X93233Y779267D01*
X92900Y780017D01*
X92817Y780850D01*
X92983Y781933D01*
X93233Y782517D01*
X93650Y783100D01*
X94233Y783517D01*
X94817Y783600D01*
X95400Y783433D01*
X95817Y783017D01*
G01X100000Y783600D02*
X99333Y783433D01*
X98833Y783017D01*
X98500Y782517D01*
X98250Y781850D01*
X98167Y781100D01*
X98250Y780350D01*
X98500Y779683D01*
X98833Y779183D01*
X99333Y778767D01*
X100000Y778600D01*
X100667Y778767D01*
X101167Y779183D01*
X101500Y779683D01*
X101750Y780350D01*
X101833Y781100D01*
X101750Y781850D01*
X101500Y782517D01*
X101167Y783017D01*
X100667Y783433D01*
X100000Y783600D01*
G01X105600Y778600D02*
Y783600D01*
X104600Y782600D01*
G01Y778600D02*
X106600D01*
G01X111200D02*
Y783600D01*
X110200Y782600D01*
G01Y778600D02*
X112200D01*
G01X122900Y781100D02*
X124567D01*
Y779600D01*
X124067Y779100D01*
X123483Y778767D01*
X122650Y778600D01*
X121817Y778767D01*
X121233Y779100D01*
X120733Y779600D01*
X120400Y780183D01*
X120233Y780850D01*
Y781433D01*
X120400Y781933D01*
X120733Y782517D01*
X121233Y783017D01*
X121733Y783350D01*
X122400Y783600D01*
X122983D01*
X123650Y783433D01*
X124150Y783100D01*
G01X126750Y780850D02*
X129417D01*
X129167Y781433D01*
X128750Y781767D01*
X128167Y781933D01*
X127583Y781850D01*
X127083Y781600D01*
X126750Y781017D01*
X126583Y780517D01*
Y780017D01*
X126750Y779517D01*
X127167Y779017D01*
X127667Y778683D01*
X128250Y778600D01*
X128833Y778767D01*
X129417Y779267D01*
G01X132183Y778600D02*
Y781933D01*
G01Y781100D02*
X132517Y781517D01*
X133017Y781850D01*
X133683Y781933D01*
X134267Y781850D01*
X134767Y781517D01*
X135017Y780933D01*
Y778600D01*
G01X137950Y780850D02*
X140617D01*
X140367Y781433D01*
X139950Y781767D01*
X139367Y781933D01*
X138783Y781850D01*
X138283Y781600D01*
X137950Y781017D01*
X137783Y780517D01*
Y780017D01*
X137950Y779517D01*
X138367Y779017D01*
X138867Y778683D01*
X139450Y778600D01*
X140033Y778767D01*
X140617Y779267D01*
G01X143633Y778600D02*
Y781933D01*
G01Y781267D02*
X144050Y781600D01*
X144467Y781850D01*
X145050Y781933D01*
X145467Y781850D01*
X145967Y781600D01*
G01X150400Y781933D02*
Y778600D01*
G01Y783267D02*
X150233Y783350D01*
Y783517D01*
X150400Y783600D01*
X150567Y783517D01*
Y783350D01*
X150400Y783267D01*
G01X157333Y781517D02*
X156750Y781850D01*
X156250Y781933D01*
X155583Y781767D01*
X155083Y781433D01*
X154750Y780850D01*
X154667Y780267D01*
X154750Y779683D01*
X155083Y779183D01*
X155583Y778767D01*
X156250Y778600D01*
X156833Y778767D01*
X157333Y779100D01*
G01X165533Y778600D02*
Y783600D01*
X167533D01*
X168200Y783350D01*
X168700Y782767D01*
X168867Y782100D01*
X168700Y781433D01*
X168283Y780933D01*
X167533Y780683D01*
X165533D01*
G01X171550Y780850D02*
X174217D01*
X173967Y781433D01*
X173550Y781767D01*
X172967Y781933D01*
X172383Y781850D01*
X171883Y781600D01*
X171550Y781017D01*
X171383Y780517D01*
Y780017D01*
X171550Y779517D01*
X171967Y779017D01*
X172467Y778683D01*
X173050Y778600D01*
X173633Y778767D01*
X174217Y779267D01*
G01X177233Y778600D02*
Y781933D01*
G01Y781267D02*
X177650Y781600D01*
X178067Y781850D01*
X178650Y781933D01*
X179067Y781850D01*
X179567Y781600D01*
G01X183500Y778600D02*
Y782850D01*
X183667Y783267D01*
X184000Y783517D01*
X184500Y783600D01*
X185000Y783433D01*
X185250Y783017D01*
G01X184250Y781600D02*
X182583D01*
G01X189600Y778600D02*
X189100Y778683D01*
X188600Y779017D01*
X188267Y779600D01*
X188100Y780267D01*
X188267Y780933D01*
X188600Y781517D01*
X189100Y781850D01*
X189600Y781933D01*
X190100Y781850D01*
X190600Y781517D01*
X190933Y780933D01*
X191017Y780267D01*
X190933Y779600D01*
X190600Y779017D01*
X190100Y778683D01*
X189600Y778600D01*
G01X194033D02*
Y781933D01*
G01Y781267D02*
X194450Y781600D01*
X194867Y781850D01*
X195450Y781933D01*
X195867Y781850D01*
X196367Y781600D01*
G01X198300Y778600D02*
Y781933D01*
G01Y781017D02*
X198550Y781433D01*
X198967Y781767D01*
X199550Y781933D01*
X200133Y781767D01*
X200550Y781433D01*
X200800Y781017D01*
Y778600D01*
G01Y781017D02*
X201050Y781433D01*
X201467Y781767D01*
X202050Y781933D01*
X202633Y781767D01*
X203050Y781433D01*
X203300Y780933D01*
Y778600D01*
G01X207900D02*
Y781933D01*
G01Y781350D02*
X207567Y781683D01*
X207067Y781850D01*
X206483Y781933D01*
X205900Y781767D01*
X205400Y781433D01*
X205067Y780933D01*
X204900Y780267D01*
X205067Y779600D01*
X205400Y779100D01*
X205900Y778767D01*
X206483Y778600D01*
X207067Y778683D01*
X207567Y778933D01*
X207900Y779267D01*
G01X210583Y778600D02*
Y781933D01*
G01Y781100D02*
X210917Y781517D01*
X211417Y781850D01*
X212083Y781933D01*
X212667Y781850D01*
X213167Y781517D01*
X213417Y780933D01*
Y778600D01*
G01X218933Y781517D02*
X218350Y781850D01*
X217850Y781933D01*
X217183Y781767D01*
X216683Y781433D01*
X216350Y780850D01*
X216267Y780267D01*
X216350Y779683D01*
X216683Y779183D01*
X217183Y778767D01*
X217850Y778600D01*
X218433Y778767D01*
X218933Y779100D01*
G01X221950Y780850D02*
X224617D01*
X224367Y781433D01*
X223950Y781767D01*
X223367Y781933D01*
X222783Y781850D01*
X222283Y781600D01*
X221950Y781017D01*
X221783Y780517D01*
Y780017D01*
X221950Y779517D01*
X222367Y779017D01*
X222867Y778683D01*
X223450Y778600D01*
X224033Y778767D01*
X224617Y779267D01*
G01X232650D02*
X233317Y778850D01*
X234067Y778600D01*
X234733D01*
X235400Y778850D01*
X235900Y779267D01*
X236150Y779850D01*
X235983Y780433D01*
X235567Y780933D01*
X234817Y781267D01*
X233817Y781433D01*
X233233Y781767D01*
X232983Y782350D01*
X233150Y782933D01*
X233567Y783350D01*
X234150Y783600D01*
X234733D01*
X235317Y783433D01*
X235817Y783017D01*
G01X238500Y776933D02*
Y781933D01*
G01Y781183D02*
X238917Y781600D01*
X239333Y781850D01*
X240000Y781933D01*
X240583Y781850D01*
X241167Y781433D01*
X241417Y780850D01*
X241500Y780267D01*
X241417Y779683D01*
X241167Y779100D01*
X240667Y778767D01*
X240000Y778600D01*
X239417Y778683D01*
X238833Y778933D01*
X238500Y779267D01*
G01X244350Y780850D02*
X247017D01*
X246767Y781433D01*
X246350Y781767D01*
X245767Y781933D01*
X245183Y781850D01*
X244683Y781600D01*
X244350Y781017D01*
X244183Y780517D01*
Y780017D01*
X244350Y779517D01*
X244767Y779017D01*
X245267Y778683D01*
X245850Y778600D01*
X246433Y778767D01*
X247017Y779267D01*
G01X252533Y781517D02*
X251950Y781850D01*
X251450Y781933D01*
X250783Y781767D01*
X250283Y781433D01*
X249950Y780850D01*
X249867Y780267D01*
X249950Y779683D01*
X250283Y779183D01*
X250783Y778767D01*
X251450Y778600D01*
X252033Y778767D01*
X252533Y779100D01*
G01X256800Y781933D02*
Y778600D01*
G01Y783267D02*
X256633Y783350D01*
Y783517D01*
X256800Y783600D01*
X256967Y783517D01*
Y783350D01*
X256800Y783267D01*
G01X261900Y778600D02*
Y782850D01*
X262067Y783267D01*
X262400Y783517D01*
X262900Y783600D01*
X263400Y783433D01*
X263650Y783017D01*
G01X262650Y781600D02*
X260983D01*
G01X268000Y781933D02*
Y778600D01*
G01Y783267D02*
X267833Y783350D01*
Y783517D01*
X268000Y783600D01*
X268167Y783517D01*
Y783350D01*
X268000Y783267D01*
G01X274933Y781517D02*
X274350Y781850D01*
X273850Y781933D01*
X273183Y781767D01*
X272683Y781433D01*
X272350Y780850D01*
X272267Y780267D01*
X272350Y779683D01*
X272683Y779183D01*
X273183Y778767D01*
X273850Y778600D01*
X274433Y778767D01*
X274933Y779100D01*
G01X280700Y778600D02*
Y781933D01*
G01Y781350D02*
X280367Y781683D01*
X279867Y781850D01*
X279283Y781933D01*
X278700Y781767D01*
X278200Y781433D01*
X277867Y780933D01*
X277700Y780267D01*
X277867Y779600D01*
X278200Y779100D01*
X278700Y778767D01*
X279283Y778600D01*
X279867Y778683D01*
X280367Y778933D01*
X280700Y779267D01*
G01X284800Y783600D02*
Y778600D01*
G01X283633Y781933D02*
X285967D01*
G01X290400D02*
Y778600D01*
G01Y783267D02*
X290233Y783350D01*
Y783517D01*
X290400Y783600D01*
X290567Y783517D01*
Y783350D01*
X290400Y783267D01*
G01X296000Y778600D02*
X295500Y778683D01*
X295000Y779017D01*
X294667Y779600D01*
X294500Y780267D01*
X294667Y780933D01*
X295000Y781517D01*
X295500Y781850D01*
X296000Y781933D01*
X296500Y781850D01*
X297000Y781517D01*
X297333Y780933D01*
X297417Y780267D01*
X297333Y779600D01*
X297000Y779017D01*
X296500Y778683D01*
X296000Y778600D01*
G01X300183D02*
Y781933D01*
G01Y781100D02*
X300517Y781517D01*
X301017Y781850D01*
X301683Y781933D01*
X302267Y781850D01*
X302767Y781517D01*
X303017Y780933D01*
Y778600D01*
G01X312300D02*
Y782850D01*
X312467Y783267D01*
X312800Y783517D01*
X313300Y783600D01*
X313800Y783433D01*
X314050Y783017D01*
G01X313050Y781600D02*
X311383D01*
G01X318400Y778600D02*
X317900Y778683D01*
X317400Y779017D01*
X317067Y779600D01*
X316900Y780267D01*
X317067Y780933D01*
X317400Y781517D01*
X317900Y781850D01*
X318400Y781933D01*
X318900Y781850D01*
X319400Y781517D01*
X319733Y780933D01*
X319817Y780267D01*
X319733Y779600D01*
X319400Y779017D01*
X318900Y778683D01*
X318400Y778600D01*
G01X322833D02*
Y781933D01*
G01Y781267D02*
X323250Y781600D01*
X323667Y781850D01*
X324250Y781933D01*
X324667Y781850D01*
X325167Y781600D01*
G01X333533Y778600D02*
Y783600D01*
X335533D01*
X336200Y783350D01*
X336700Y782767D01*
X336867Y782100D01*
X336700Y781433D01*
X336283Y780933D01*
X335533Y780683D01*
X333533D01*
G01X339633Y778600D02*
Y781933D01*
G01Y781267D02*
X340050Y781600D01*
X340467Y781850D01*
X341050Y781933D01*
X341467Y781850D01*
X341967Y781600D01*
G01X346400Y781933D02*
Y778600D01*
G01Y783267D02*
X346233Y783350D01*
Y783517D01*
X346400Y783600D01*
X346567Y783517D01*
Y783350D01*
X346400Y783267D01*
G01X350583Y778600D02*
Y781933D01*
G01Y781100D02*
X350917Y781517D01*
X351417Y781850D01*
X352083Y781933D01*
X352667Y781850D01*
X353167Y781517D01*
X353417Y780933D01*
Y778600D01*
G01X357600Y783600D02*
Y778600D01*
G01X356433Y781933D02*
X358767D01*
G01X361950Y780850D02*
X364617D01*
X364367Y781433D01*
X363950Y781767D01*
X363367Y781933D01*
X362783Y781850D01*
X362283Y781600D01*
X361950Y781017D01*
X361783Y780517D01*
Y780017D01*
X361950Y779517D01*
X362367Y779017D01*
X362867Y778683D01*
X363450Y778600D01*
X364033Y778767D01*
X364617Y779267D01*
G01X370300Y783600D02*
Y778600D01*
G01Y779350D02*
X369967Y778933D01*
X369467Y778683D01*
X368883Y778600D01*
X368217Y778767D01*
X367717Y779183D01*
X367383Y779683D01*
X367300Y780267D01*
X367383Y780850D01*
X367717Y781350D01*
X368217Y781767D01*
X368883Y781933D01*
X369467Y781850D01*
X369883Y781683D01*
X370300Y781350D01*
G01X380667Y781267D02*
X381000Y781517D01*
X381250Y781933D01*
X381417Y782517D01*
X381250Y783017D01*
X380917Y783350D01*
X380333Y783600D01*
X378083D01*
Y778600D01*
X380833D01*
X381417Y778933D01*
X381750Y779433D01*
X381917Y780017D01*
X381750Y780600D01*
X381250Y781100D01*
X380667Y781267D01*
X378083D01*
G01X385600Y778600D02*
X385100Y778683D01*
X384600Y779017D01*
X384267Y779600D01*
X384100Y780267D01*
X384267Y780933D01*
X384600Y781517D01*
X385100Y781850D01*
X385600Y781933D01*
X386100Y781850D01*
X386600Y781517D01*
X386933Y780933D01*
X387017Y780267D01*
X386933Y779600D01*
X386600Y779017D01*
X386100Y778683D01*
X385600Y778600D01*
G01X392700D02*
Y781933D01*
G01Y781350D02*
X392367Y781683D01*
X391867Y781850D01*
X391283Y781933D01*
X390700Y781767D01*
X390200Y781433D01*
X389867Y780933D01*
X389700Y780267D01*
X389867Y779600D01*
X390200Y779100D01*
X390700Y778767D01*
X391283Y778600D01*
X391867Y778683D01*
X392367Y778933D01*
X392700Y779267D01*
G01X395633Y778600D02*
Y781933D01*
G01Y781267D02*
X396050Y781600D01*
X396467Y781850D01*
X397050Y781933D01*
X397467Y781850D01*
X397967Y781600D01*
G01X403900Y783600D02*
Y778600D01*
G01Y779350D02*
X403567Y778933D01*
X403067Y778683D01*
X402483Y778600D01*
X401817Y778767D01*
X401317Y779183D01*
X400983Y779683D01*
X400900Y780267D01*
X400983Y780850D01*
X401317Y781350D01*
X401817Y781767D01*
X402483Y781933D01*
X403067Y781850D01*
X403483Y781683D01*
X403900Y781350D01*
G01X406750Y779183D02*
X407167Y778850D01*
X407750Y778600D01*
X408250D01*
X408750Y778767D01*
X409083Y779017D01*
X409250Y779350D01*
X409167Y779850D01*
X408833Y780100D01*
X407333Y780600D01*
X407000Y781183D01*
X407167Y781600D01*
X407500Y781850D01*
X408000Y781933D01*
X408500Y781850D01*
X409000Y781600D01*
G01X71000Y791500D02*
X73000D01*
G01X72000D02*
Y786500D01*
G01X71000D02*
X73000D01*
G01X75933D02*
Y791500D01*
X77933D01*
X78600Y791250D01*
X79100Y790667D01*
X79267Y790000D01*
X79100Y789333D01*
X78683Y788833D01*
X77933Y788583D01*
X75933D01*
G01X85033Y791083D02*
X84533Y791333D01*
X83950Y791500D01*
X83283D01*
X82533Y791250D01*
X81950Y790833D01*
X81533Y790333D01*
X81200Y789500D01*
X81117Y788750D01*
X81283Y788000D01*
X81533Y787500D01*
X82033Y787000D01*
X82617Y786667D01*
X83200Y786500D01*
X83783D01*
X84367Y786667D01*
X84867Y786917D01*
X85283Y787250D01*
G01X87717Y788167D02*
X89883D01*
G01X92317Y786500D02*
X94400Y791500D01*
X96483Y786500D01*
G01X95733Y788250D02*
X93067D01*
G01X98917Y788167D02*
X101083D01*
G01X104017Y788583D02*
X104600Y789167D01*
X105100Y789500D01*
X105767Y789667D01*
X106350Y789500D01*
X106767Y789167D01*
X107100Y788667D01*
X107183Y788083D01*
X107100Y787583D01*
X106767Y787083D01*
X106267Y786667D01*
X105683Y786500D01*
X105017Y786667D01*
X104433Y787167D01*
X104100Y787917D01*
X104017Y788750D01*
X104183Y789833D01*
X104433Y790417D01*
X104850Y791000D01*
X105433Y791417D01*
X106017Y791500D01*
X106600Y791333D01*
X107017Y790917D01*
G01X111200Y791500D02*
X110533Y791333D01*
X110033Y790917D01*
X109700Y790417D01*
X109450Y789750D01*
X109367Y789000D01*
X109450Y788250D01*
X109700Y787583D01*
X110033Y787083D01*
X110533Y786667D01*
X111200Y786500D01*
X111867Y786667D01*
X112367Y787083D01*
X112700Y787583D01*
X112950Y788250D01*
X113033Y789000D01*
X112950Y789750D01*
X112700Y790417D01*
X112367Y790917D01*
X111867Y791333D01*
X111200Y791500D01*
G01X116800D02*
X116133Y791333D01*
X115633Y790917D01*
X115300Y790417D01*
X115050Y789750D01*
X114967Y789000D01*
X115050Y788250D01*
X115300Y787583D01*
X115633Y787083D01*
X116133Y786667D01*
X116800Y786500D01*
X117467Y786667D01*
X117967Y787083D01*
X118300Y787583D01*
X118550Y788250D01*
X118633Y789000D01*
X118550Y789750D01*
X118300Y790417D01*
X117967Y790917D01*
X117467Y791333D01*
X116800Y791500D01*
G01X125917Y786500D02*
X128000Y791500D01*
X130083Y786500D01*
G01X129333Y788250D02*
X126667D01*
G01X134933Y789417D02*
X134350Y789750D01*
X133850Y789833D01*
X133183Y789667D01*
X132683Y789333D01*
X132350Y788750D01*
X132267Y788167D01*
X132350Y787583D01*
X132683Y787083D01*
X133183Y786667D01*
X133850Y786500D01*
X134433Y786667D01*
X134933Y787000D01*
G01X140533Y789417D02*
X139950Y789750D01*
X139450Y789833D01*
X138783Y789667D01*
X138283Y789333D01*
X137950Y788750D01*
X137867Y788167D01*
X137950Y787583D01*
X138283Y787083D01*
X138783Y786667D01*
X139450Y786500D01*
X140033Y786667D01*
X140533Y787000D01*
G01X143550Y788750D02*
X146217D01*
X145967Y789333D01*
X145550Y789667D01*
X144967Y789833D01*
X144383Y789750D01*
X143883Y789500D01*
X143550Y788917D01*
X143383Y788417D01*
Y787917D01*
X143550Y787417D01*
X143967Y786917D01*
X144467Y786583D01*
X145050Y786500D01*
X145633Y786667D01*
X146217Y787167D01*
G01X148900Y784833D02*
Y789833D01*
G01Y789083D02*
X149317Y789500D01*
X149733Y789750D01*
X150400Y789833D01*
X150983Y789750D01*
X151567Y789333D01*
X151817Y788750D01*
X151900Y788167D01*
X151817Y787583D01*
X151567Y787000D01*
X151067Y786667D01*
X150400Y786500D01*
X149817Y786583D01*
X149233Y786833D01*
X148900Y787167D01*
G01X156000Y791500D02*
Y786500D01*
G01X154833Y789833D02*
X157167D01*
G01X163100Y786500D02*
Y789833D01*
G01Y789250D02*
X162767Y789583D01*
X162267Y789750D01*
X161683Y789833D01*
X161100Y789667D01*
X160600Y789333D01*
X160267Y788833D01*
X160100Y788167D01*
X160267Y787500D01*
X160600Y787000D01*
X161100Y786667D01*
X161683Y786500D01*
X162267Y786583D01*
X162767Y786833D01*
X163100Y787167D01*
G01X165700Y786500D02*
Y791500D01*
G01Y789000D02*
X166117Y789500D01*
X166617Y789750D01*
X167117Y789833D01*
X167867Y789667D01*
X168367Y789333D01*
X168700Y788750D01*
Y788083D01*
X168533Y787417D01*
X168200Y786917D01*
X167617Y786583D01*
X167117Y786500D01*
X166617Y786583D01*
X166117Y786833D01*
X165700Y787250D01*
G01X172800Y789833D02*
Y786500D01*
G01Y791167D02*
X172633Y791250D01*
Y791417D01*
X172800Y791500D01*
X172967Y791417D01*
Y791250D01*
X172800Y791167D01*
G01X178400Y786500D02*
Y791500D01*
G01X184000Y789833D02*
Y786500D01*
G01Y791167D02*
X183833Y791250D01*
Y791417D01*
X184000Y791500D01*
X184167Y791417D01*
Y791250D01*
X184000Y791167D01*
G01X189600Y791500D02*
Y786500D01*
G01X188433Y789833D02*
X190767D01*
G01X193450Y785000D02*
X193950Y784833D01*
X194617Y785000D01*
X195033Y785333D01*
X195367Y785750D01*
X195867Y787083D01*
X196950Y789833D01*
G01X194283D02*
X195867Y787083D01*
G01X206400Y786500D02*
X205900Y786583D01*
X205400Y786917D01*
X205067Y787500D01*
X204900Y788167D01*
X205067Y788833D01*
X205400Y789417D01*
X205900Y789750D01*
X206400Y789833D01*
X206900Y789750D01*
X207400Y789417D01*
X207733Y788833D01*
X207817Y788167D01*
X207733Y787500D01*
X207400Y786917D01*
X206900Y786583D01*
X206400Y786500D01*
G01X211500D02*
Y790750D01*
X211667Y791167D01*
X212000Y791417D01*
X212500Y791500D01*
X213000Y791333D01*
X213250Y790917D01*
G01X212250Y789500D02*
X210583D01*
G01X221533Y786500D02*
Y791500D01*
X223533D01*
X224200Y791250D01*
X224700Y790667D01*
X224867Y790000D01*
X224700Y789333D01*
X224283Y788833D01*
X223533Y788583D01*
X221533D01*
G01X227633Y786500D02*
Y789833D01*
G01Y789167D02*
X228050Y789500D01*
X228467Y789750D01*
X229050Y789833D01*
X229467Y789750D01*
X229967Y789500D01*
G01X234400Y789833D02*
Y786500D01*
G01Y791167D02*
X234233Y791250D01*
Y791417D01*
X234400Y791500D01*
X234567Y791417D01*
Y791250D01*
X234400Y791167D01*
G01X238583Y786500D02*
Y789833D01*
G01Y789000D02*
X238917Y789417D01*
X239417Y789750D01*
X240083Y789833D01*
X240667Y789750D01*
X241167Y789417D01*
X241417Y788833D01*
Y786500D01*
G01X245600Y791500D02*
Y786500D01*
G01X244433Y789833D02*
X246767D01*
G01X249950Y788750D02*
X252617D01*
X252367Y789333D01*
X251950Y789667D01*
X251367Y789833D01*
X250783Y789750D01*
X250283Y789500D01*
X249950Y788917D01*
X249783Y788417D01*
Y787917D01*
X249950Y787417D01*
X250367Y786917D01*
X250867Y786583D01*
X251450Y786500D01*
X252033Y786667D01*
X252617Y787167D01*
G01X258300Y791500D02*
Y786500D01*
G01Y787250D02*
X257967Y786833D01*
X257467Y786583D01*
X256883Y786500D01*
X256217Y786667D01*
X255717Y787083D01*
X255383Y787583D01*
X255300Y788167D01*
X255383Y788750D01*
X255717Y789250D01*
X256217Y789667D01*
X256883Y789833D01*
X257467Y789750D01*
X257883Y789583D01*
X258300Y789250D01*
G01X268667Y789167D02*
X269000Y789417D01*
X269250Y789833D01*
X269417Y790417D01*
X269250Y790917D01*
X268917Y791250D01*
X268333Y791500D01*
X266083D01*
Y786500D01*
X268833D01*
X269417Y786833D01*
X269750Y787333D01*
X269917Y787917D01*
X269750Y788500D01*
X269250Y789000D01*
X268667Y789167D01*
X266083D01*
G01X273600Y786500D02*
X273100Y786583D01*
X272600Y786917D01*
X272267Y787500D01*
X272100Y788167D01*
X272267Y788833D01*
X272600Y789417D01*
X273100Y789750D01*
X273600Y789833D01*
X274100Y789750D01*
X274600Y789417D01*
X274933Y788833D01*
X275017Y788167D01*
X274933Y787500D01*
X274600Y786917D01*
X274100Y786583D01*
X273600Y786500D01*
G01X280700D02*
Y789833D01*
G01Y789250D02*
X280367Y789583D01*
X279867Y789750D01*
X279283Y789833D01*
X278700Y789667D01*
X278200Y789333D01*
X277867Y788833D01*
X277700Y788167D01*
X277867Y787500D01*
X278200Y787000D01*
X278700Y786667D01*
X279283Y786500D01*
X279867Y786583D01*
X280367Y786833D01*
X280700Y787167D01*
G01X283633Y786500D02*
Y789833D01*
G01Y789167D02*
X284050Y789500D01*
X284467Y789750D01*
X285050Y789833D01*
X285467Y789750D01*
X285967Y789500D01*
G01X291900Y791500D02*
Y786500D01*
G01Y787250D02*
X291567Y786833D01*
X291067Y786583D01*
X290483Y786500D01*
X289817Y786667D01*
X289317Y787083D01*
X288983Y787583D01*
X288900Y788167D01*
X288983Y788750D01*
X289317Y789250D01*
X289817Y789667D01*
X290483Y789833D01*
X291067Y789750D01*
X291483Y789583D01*
X291900Y789250D01*
G01X294750Y787083D02*
X295167Y786750D01*
X295750Y786500D01*
X296250D01*
X296750Y786667D01*
X297083Y786917D01*
X297250Y787250D01*
X297167Y787750D01*
X296833Y788000D01*
X295333Y788500D01*
X295000Y789083D01*
X295167Y789500D01*
X295500Y789750D01*
X296000Y789833D01*
X296500Y789750D01*
X297000Y789500D01*
G01X57833Y806500D02*
Y811500D01*
X59833D01*
X60500Y811250D01*
X61000Y810667D01*
X61167Y810000D01*
X61000Y809333D01*
X60583Y808833D01*
X59833Y808583D01*
X57833D01*
G01X65100Y806500D02*
Y811500D01*
G01X69450Y808750D02*
X72117D01*
X71867Y809333D01*
X71450Y809667D01*
X70867Y809833D01*
X70283Y809750D01*
X69783Y809500D01*
X69450Y808917D01*
X69283Y808417D01*
Y807917D01*
X69450Y807417D01*
X69867Y806917D01*
X70367Y806583D01*
X70950Y806500D01*
X71533Y806667D01*
X72117Y807167D01*
G01X77800Y806500D02*
Y809833D01*
G01Y809250D02*
X77467Y809583D01*
X76967Y809750D01*
X76383Y809833D01*
X75800Y809667D01*
X75300Y809333D01*
X74967Y808833D01*
X74800Y808167D01*
X74967Y807500D01*
X75300Y807000D01*
X75800Y806667D01*
X76383Y806500D01*
X76967Y806583D01*
X77467Y806833D01*
X77800Y807167D01*
G01X80650Y807083D02*
X81067Y806750D01*
X81650Y806500D01*
X82150D01*
X82650Y806667D01*
X82983Y806917D01*
X83150Y807250D01*
X83067Y807750D01*
X82733Y808000D01*
X81233Y808500D01*
X80900Y809083D01*
X81067Y809500D01*
X81400Y809750D01*
X81900Y809833D01*
X82400Y809750D01*
X82900Y809500D01*
G01X86250Y808750D02*
X88917D01*
X88667Y809333D01*
X88250Y809667D01*
X87667Y809833D01*
X87083Y809750D01*
X86583Y809500D01*
X86250Y808917D01*
X86083Y808417D01*
Y807917D01*
X86250Y807417D01*
X86667Y806917D01*
X87167Y806583D01*
X87750Y806500D01*
X88333Y806667D01*
X88917Y807167D01*
G01X98200Y806500D02*
Y810750D01*
X98367Y811167D01*
X98700Y811417D01*
X99200Y811500D01*
X99700Y811333D01*
X99950Y810917D01*
G01X98950Y809500D02*
X97283D01*
G01X104300Y806500D02*
X103800Y806583D01*
X103300Y806917D01*
X102967Y807500D01*
X102800Y808167D01*
X102967Y808833D01*
X103300Y809417D01*
X103800Y809750D01*
X104300Y809833D01*
X104800Y809750D01*
X105300Y809417D01*
X105633Y808833D01*
X105717Y808167D01*
X105633Y807500D01*
X105300Y806917D01*
X104800Y806583D01*
X104300Y806500D01*
G01X109900D02*
Y811500D01*
G01X115500Y806500D02*
Y811500D01*
G01X121100Y806500D02*
X120600Y806583D01*
X120100Y806917D01*
X119767Y807500D01*
X119600Y808167D01*
X119767Y808833D01*
X120100Y809417D01*
X120600Y809750D01*
X121100Y809833D01*
X121600Y809750D01*
X122100Y809417D01*
X122433Y808833D01*
X122517Y808167D01*
X122433Y807500D01*
X122100Y806917D01*
X121600Y806583D01*
X121100Y806500D01*
G01X124617Y809833D02*
X125617Y806500D01*
X126700Y809833D01*
X127783Y806500D01*
X128783Y809833D01*
G01X137900Y811500D02*
Y806500D01*
G01X136733Y809833D02*
X139067D01*
G01X142083Y806500D02*
Y811500D01*
G01Y809083D02*
X142500Y809500D01*
X142917Y809750D01*
X143583Y809833D01*
X144083Y809750D01*
X144667Y809417D01*
X144917Y808917D01*
Y806500D01*
G01X147850Y808750D02*
X150517D01*
X150267Y809333D01*
X149850Y809667D01*
X149267Y809833D01*
X148683Y809750D01*
X148183Y809500D01*
X147850Y808917D01*
X147683Y808417D01*
Y807917D01*
X147850Y807417D01*
X148267Y806917D01*
X148767Y806583D01*
X149350Y806500D01*
X149933Y806667D01*
X150517Y807167D01*
G01X159050Y807083D02*
X159467Y806750D01*
X160050Y806500D01*
X160550D01*
X161050Y806667D01*
X161383Y806917D01*
X161550Y807250D01*
X161467Y807750D01*
X161133Y808000D01*
X159633Y808500D01*
X159300Y809083D01*
X159467Y809500D01*
X159800Y809750D01*
X160300Y809833D01*
X160800Y809750D01*
X161300Y809500D01*
G01X164400Y804833D02*
Y809833D01*
G01Y809083D02*
X164817Y809500D01*
X165233Y809750D01*
X165900Y809833D01*
X166483Y809750D01*
X167067Y809333D01*
X167317Y808750D01*
X167400Y808167D01*
X167317Y807583D01*
X167067Y807000D01*
X166567Y806667D01*
X165900Y806500D01*
X165317Y806583D01*
X164733Y806833D01*
X164400Y807167D01*
G01X170250Y808750D02*
X172917D01*
X172667Y809333D01*
X172250Y809667D01*
X171667Y809833D01*
X171083Y809750D01*
X170583Y809500D01*
X170250Y808917D01*
X170083Y808417D01*
Y807917D01*
X170250Y807417D01*
X170667Y806917D01*
X171167Y806583D01*
X171750Y806500D01*
X172333Y806667D01*
X172917Y807167D01*
G01X178433Y809417D02*
X177850Y809750D01*
X177350Y809833D01*
X176683Y809667D01*
X176183Y809333D01*
X175850Y808750D01*
X175767Y808167D01*
X175850Y807583D01*
X176183Y807083D01*
X176683Y806667D01*
X177350Y806500D01*
X177933Y806667D01*
X178433Y807000D01*
G01X182700Y809833D02*
Y806500D01*
G01Y811167D02*
X182533Y811250D01*
Y811417D01*
X182700Y811500D01*
X182867Y811417D01*
Y811250D01*
X182700Y811167D01*
G01X187800Y806500D02*
Y810750D01*
X187967Y811167D01*
X188300Y811417D01*
X188800Y811500D01*
X189300Y811333D01*
X189550Y810917D01*
G01X188550Y809500D02*
X186883D01*
G01X193900Y809833D02*
Y806500D01*
G01Y811167D02*
X193733Y811250D01*
Y811417D01*
X193900Y811500D01*
X194067Y811417D01*
Y811250D01*
X193900Y811167D01*
G01X200833Y809417D02*
X200250Y809750D01*
X199750Y809833D01*
X199083Y809667D01*
X198583Y809333D01*
X198250Y808750D01*
X198167Y808167D01*
X198250Y807583D01*
X198583Y807083D01*
X199083Y806667D01*
X199750Y806500D01*
X200333Y806667D01*
X200833Y807000D01*
G01X206600Y806500D02*
Y809833D01*
G01Y809250D02*
X206267Y809583D01*
X205767Y809750D01*
X205183Y809833D01*
X204600Y809667D01*
X204100Y809333D01*
X203767Y808833D01*
X203600Y808167D01*
X203767Y807500D01*
X204100Y807000D01*
X204600Y806667D01*
X205183Y806500D01*
X205767Y806583D01*
X206267Y806833D01*
X206600Y807167D01*
G01X210700Y811500D02*
Y806500D01*
G01X209533Y809833D02*
X211867D01*
G01X216300D02*
Y806500D01*
G01Y811167D02*
X216133Y811250D01*
Y811417D01*
X216300Y811500D01*
X216467Y811417D01*
Y811250D01*
X216300Y811167D01*
G01X221900Y806500D02*
X221400Y806583D01*
X220900Y806917D01*
X220567Y807500D01*
X220400Y808167D01*
X220567Y808833D01*
X220900Y809417D01*
X221400Y809750D01*
X221900Y809833D01*
X222400Y809750D01*
X222900Y809417D01*
X223233Y808833D01*
X223317Y808167D01*
X223233Y807500D01*
X222900Y806917D01*
X222400Y806583D01*
X221900Y806500D01*
G01X226083D02*
Y809833D01*
G01Y809000D02*
X226417Y809417D01*
X226917Y809750D01*
X227583Y809833D01*
X228167Y809750D01*
X228667Y809417D01*
X228917Y808833D01*
Y806500D01*
G01X240200Y811500D02*
Y806500D01*
G01Y807250D02*
X239867Y806833D01*
X239367Y806583D01*
X238783Y806500D01*
X238117Y806667D01*
X237617Y807083D01*
X237283Y807583D01*
X237200Y808167D01*
X237283Y808750D01*
X237617Y809250D01*
X238117Y809667D01*
X238783Y809833D01*
X239367Y809750D01*
X239783Y809583D01*
X240200Y809250D01*
G01X244300Y806500D02*
X243800Y806583D01*
X243300Y806917D01*
X242967Y807500D01*
X242800Y808167D01*
X242967Y808833D01*
X243300Y809417D01*
X243800Y809750D01*
X244300Y809833D01*
X244800Y809750D01*
X245300Y809417D01*
X245633Y808833D01*
X245717Y808167D01*
X245633Y807500D01*
X245300Y806917D01*
X244800Y806583D01*
X244300Y806500D01*
G01X251233Y809417D02*
X250650Y809750D01*
X250150Y809833D01*
X249483Y809667D01*
X248983Y809333D01*
X248650Y808750D01*
X248567Y808167D01*
X248650Y807583D01*
X248983Y807083D01*
X249483Y806667D01*
X250150Y806500D01*
X250733Y806667D01*
X251233Y807000D01*
G01X254083Y809833D02*
Y807500D01*
X254417Y806917D01*
X254917Y806583D01*
X255500Y806500D01*
X256083Y806583D01*
X256583Y806917D01*
X256917Y807500D01*
G01Y806500D02*
Y809833D01*
G01X258600Y806500D02*
Y809833D01*
G01Y808917D02*
X258850Y809333D01*
X259267Y809667D01*
X259850Y809833D01*
X260433Y809667D01*
X260850Y809333D01*
X261100Y808917D01*
Y806500D01*
G01Y808917D02*
X261350Y809333D01*
X261767Y809667D01*
X262350Y809833D01*
X262933Y809667D01*
X263350Y809333D01*
X263600Y808833D01*
Y806500D01*
G01X265450Y808750D02*
X268117D01*
X267867Y809333D01*
X267450Y809667D01*
X266867Y809833D01*
X266283Y809750D01*
X265783Y809500D01*
X265450Y808917D01*
X265283Y808417D01*
Y807917D01*
X265450Y807417D01*
X265867Y806917D01*
X266367Y806583D01*
X266950Y806500D01*
X267533Y806667D01*
X268117Y807167D01*
G01X270883Y806500D02*
Y809833D01*
G01Y809000D02*
X271217Y809417D01*
X271717Y809750D01*
X272383Y809833D01*
X272967Y809750D01*
X273467Y809417D01*
X273717Y808833D01*
Y806500D01*
G01X277900Y811500D02*
Y806500D01*
G01X276733Y809833D02*
X279067D01*
G01X282250Y807083D02*
X282667Y806750D01*
X283250Y806500D01*
X283750D01*
X284250Y806667D01*
X284583Y806917D01*
X284750Y807250D01*
X284667Y807750D01*
X284333Y808000D01*
X282833Y808500D01*
X282500Y809083D01*
X282667Y809500D01*
X283000Y809750D01*
X283500Y809833D01*
X284000Y809750D01*
X284500Y809500D01*
G01X294700Y809833D02*
Y806500D01*
G01Y811167D02*
X294533Y811250D01*
Y811417D01*
X294700Y811500D01*
X294867Y811417D01*
Y811250D01*
X294700Y811167D01*
G01X298883Y806500D02*
Y809833D01*
G01Y809000D02*
X299217Y809417D01*
X299717Y809750D01*
X300383Y809833D01*
X300967Y809750D01*
X301467Y809417D01*
X301717Y808833D01*
Y806500D01*
G01X312833Y809417D02*
X312250Y809750D01*
X311750Y809833D01*
X311083Y809667D01*
X310583Y809333D01*
X310250Y808750D01*
X310167Y808167D01*
X310250Y807583D01*
X310583Y807083D01*
X311083Y806667D01*
X311750Y806500D01*
X312333Y806667D01*
X312833Y807000D01*
G01X317100Y806500D02*
Y811500D01*
G01X324200Y806500D02*
Y809833D01*
G01Y809250D02*
X323867Y809583D01*
X323367Y809750D01*
X322783Y809833D01*
X322200Y809667D01*
X321700Y809333D01*
X321367Y808833D01*
X321200Y808167D01*
X321367Y807500D01*
X321700Y807000D01*
X322200Y806667D01*
X322783Y806500D01*
X323367Y806583D01*
X323867Y806833D01*
X324200Y807167D01*
G01X327050Y807083D02*
X327467Y806750D01*
X328050Y806500D01*
X328550D01*
X329050Y806667D01*
X329383Y806917D01*
X329550Y807250D01*
X329467Y807750D01*
X329133Y808000D01*
X327633Y808500D01*
X327300Y809083D01*
X327467Y809500D01*
X327800Y809750D01*
X328300Y809833D01*
X328800Y809750D01*
X329300Y809500D01*
G01X332650Y807083D02*
X333067Y806750D01*
X333650Y806500D01*
X334150D01*
X334650Y806667D01*
X334983Y806917D01*
X335150Y807250D01*
X335067Y807750D01*
X334733Y808000D01*
X333233Y808500D01*
X332900Y809083D01*
X333067Y809500D01*
X333400Y809750D01*
X333900Y809833D01*
X334400Y809750D01*
X334900Y809500D01*
G01X343517Y810667D02*
X344017Y811167D01*
X344600Y811417D01*
X345267Y811500D01*
X346100Y811333D01*
X346683Y810917D01*
X346850Y810417D01*
X346767Y809917D01*
X346433Y809500D01*
X344767Y808667D01*
X344017Y808083D01*
X343517Y807250D01*
X343350Y806500D01*
X346850D01*
G01X357800D02*
Y809833D01*
G01Y809250D02*
X357467Y809583D01*
X356967Y809750D01*
X356383Y809833D01*
X355800Y809667D01*
X355300Y809333D01*
X354967Y808833D01*
X354800Y808167D01*
X354967Y807500D01*
X355300Y807000D01*
X355800Y806667D01*
X356383Y806500D01*
X356967Y806583D01*
X357467Y806833D01*
X357800Y807167D01*
G01X360483Y806500D02*
Y809833D01*
G01Y809000D02*
X360817Y809417D01*
X361317Y809750D01*
X361983Y809833D01*
X362567Y809750D01*
X363067Y809417D01*
X363317Y808833D01*
Y806500D01*
G01X369000Y811500D02*
Y806500D01*
G01Y807250D02*
X368667Y806833D01*
X368167Y806583D01*
X367583Y806500D01*
X366917Y806667D01*
X366417Y807083D01*
X366083Y807583D01*
X366000Y808167D01*
X366083Y808750D01*
X366417Y809250D01*
X366917Y809667D01*
X367583Y809833D01*
X368167Y809750D01*
X368583Y809583D01*
X369000Y809250D01*
G01X378700Y811500D02*
Y806500D01*
G01X377533Y809833D02*
X379867D01*
G01X382883Y806500D02*
Y811500D01*
G01Y809083D02*
X383300Y809500D01*
X383717Y809750D01*
X384383Y809833D01*
X384883Y809750D01*
X385467Y809417D01*
X385717Y808917D01*
Y806500D01*
G01X388650Y808750D02*
X391317D01*
X391067Y809333D01*
X390650Y809667D01*
X390067Y809833D01*
X389483Y809750D01*
X388983Y809500D01*
X388650Y808917D01*
X388483Y808417D01*
Y807917D01*
X388650Y807417D01*
X389067Y806917D01*
X389567Y806583D01*
X390150Y806500D01*
X390733Y806667D01*
X391317Y807167D01*
G01X401100Y806500D02*
Y811500D01*
G01X408200Y806500D02*
Y809833D01*
G01Y809250D02*
X407867Y809583D01*
X407367Y809750D01*
X406783Y809833D01*
X406200Y809667D01*
X405700Y809333D01*
X405367Y808833D01*
X405200Y808167D01*
X405367Y807500D01*
X405700Y807000D01*
X406200Y806667D01*
X406783Y806500D01*
X407367Y806583D01*
X407867Y806833D01*
X408200Y807167D01*
G01X412300Y811500D02*
Y806500D01*
G01X411133Y809833D02*
X413467D01*
G01X416650Y808750D02*
X419317D01*
X419067Y809333D01*
X418650Y809667D01*
X418067Y809833D01*
X417483Y809750D01*
X416983Y809500D01*
X416650Y808917D01*
X416483Y808417D01*
Y807917D01*
X416650Y807417D01*
X417067Y806917D01*
X417567Y806583D01*
X418150Y806500D01*
X418733Y806667D01*
X419317Y807167D01*
G01X422250Y807083D02*
X422667Y806750D01*
X423250Y806500D01*
X423750D01*
X424250Y806667D01*
X424583Y806917D01*
X424750Y807250D01*
X424667Y807750D01*
X424333Y808000D01*
X422833Y808500D01*
X422500Y809083D01*
X422667Y809500D01*
X423000Y809750D01*
X423500Y809833D01*
X424000Y809750D01*
X424500Y809500D01*
G01X429100Y811500D02*
Y806500D01*
G01X427933Y809833D02*
X430267D01*
G01X438800D02*
X440300Y806500D01*
X441800Y809833D01*
G01X444650Y808750D02*
X447317D01*
X447067Y809333D01*
X446650Y809667D01*
X446067Y809833D01*
X445483Y809750D01*
X444983Y809500D01*
X444650Y808917D01*
X444483Y808417D01*
Y807917D01*
X444650Y807417D01*
X445067Y806917D01*
X445567Y806583D01*
X446150Y806500D01*
X446733Y806667D01*
X447317Y807167D01*
G01X450333Y806500D02*
Y809833D01*
G01Y809167D02*
X450750Y809500D01*
X451167Y809750D01*
X451750Y809833D01*
X452167Y809750D01*
X452667Y809500D01*
G01X455850Y807083D02*
X456267Y806750D01*
X456850Y806500D01*
X457350D01*
X457850Y806667D01*
X458183Y806917D01*
X458350Y807250D01*
X458267Y807750D01*
X457933Y808000D01*
X456433Y808500D01*
X456100Y809083D01*
X456267Y809500D01*
X456600Y809750D01*
X457100Y809833D01*
X457600Y809750D01*
X458100Y809500D01*
G01X462700Y809833D02*
Y806500D01*
G01Y811167D02*
X462533Y811250D01*
Y811417D01*
X462700Y811500D01*
X462867Y811417D01*
Y811250D01*
X462700Y811167D01*
G01X468300Y806500D02*
X467800Y806583D01*
X467300Y806917D01*
X466967Y807500D01*
X466800Y808167D01*
X466967Y808833D01*
X467300Y809417D01*
X467800Y809750D01*
X468300Y809833D01*
X468800Y809750D01*
X469300Y809417D01*
X469633Y808833D01*
X469717Y808167D01*
X469633Y807500D01*
X469300Y806917D01*
X468800Y806583D01*
X468300Y806500D01*
G01X472483D02*
Y809833D01*
G01Y809000D02*
X472817Y809417D01*
X473317Y809750D01*
X473983Y809833D01*
X474567Y809750D01*
X475067Y809417D01*
X475317Y808833D01*
Y806500D01*
G01X485100Y809833D02*
Y806500D01*
G01Y811167D02*
X484933Y811250D01*
Y811417D01*
X485100Y811500D01*
X485267Y811417D01*
Y811250D01*
X485100Y811167D01*
G01X489450Y807083D02*
X489867Y806750D01*
X490450Y806500D01*
X490950D01*
X491450Y806667D01*
X491783Y806917D01*
X491950Y807250D01*
X491867Y807750D01*
X491533Y808000D01*
X490033Y808500D01*
X489700Y809083D01*
X489867Y809500D01*
X490200Y809750D01*
X490700Y809833D01*
X491200Y809750D01*
X491700Y809500D01*
G01X500733Y806500D02*
Y809833D01*
G01Y809167D02*
X501150Y809500D01*
X501567Y809750D01*
X502150Y809833D01*
X502567Y809750D01*
X503067Y809500D01*
G01X506250Y808750D02*
X508917D01*
X508667Y809333D01*
X508250Y809667D01*
X507667Y809833D01*
X507083Y809750D01*
X506583Y809500D01*
X506250Y808917D01*
X506083Y808417D01*
Y807917D01*
X506250Y807417D01*
X506667Y806917D01*
X507167Y806583D01*
X507750Y806500D01*
X508333Y806667D01*
X508917Y807167D01*
G01X514600Y804833D02*
Y809833D01*
G01Y809083D02*
X514183Y809500D01*
X513683Y809750D01*
X513100Y809833D01*
X512600Y809750D01*
X512017Y809333D01*
X511683Y808750D01*
X511600Y808167D01*
X511683Y807583D01*
X512017Y807000D01*
X512600Y806583D01*
X513100Y806500D01*
X513683Y806583D01*
X514183Y806833D01*
X514600Y807250D01*
G01X517283Y809833D02*
Y807500D01*
X517617Y806917D01*
X518117Y806583D01*
X518700Y806500D01*
X519283Y806583D01*
X519783Y806917D01*
X520117Y807500D01*
G01Y806500D02*
Y809833D01*
G01X524300D02*
Y806500D01*
G01Y811167D02*
X524133Y811250D01*
Y811417D01*
X524300Y811500D01*
X524467Y811417D01*
Y811250D01*
X524300Y811167D01*
G01X528733Y806500D02*
Y809833D01*
G01Y809167D02*
X529150Y809500D01*
X529567Y809750D01*
X530150Y809833D01*
X530567Y809750D01*
X531067Y809500D01*
G01X534250Y808750D02*
X536917D01*
X536667Y809333D01*
X536250Y809667D01*
X535667Y809833D01*
X535083Y809750D01*
X534583Y809500D01*
X534250Y808917D01*
X534083Y808417D01*
Y807917D01*
X534250Y807417D01*
X534667Y806917D01*
X535167Y806583D01*
X535750Y806500D01*
X536333Y806667D01*
X536917Y807167D01*
G01X542600Y811500D02*
Y806500D01*
G01Y807250D02*
X542267Y806833D01*
X541767Y806583D01*
X541183Y806500D01*
X540517Y806667D01*
X540017Y807083D01*
X539683Y807583D01*
X539600Y808167D01*
X539683Y808750D01*
X540017Y809250D01*
X540517Y809667D01*
X541183Y809833D01*
X541767Y809750D01*
X542183Y809583D01*
X542600Y809250D01*
G01X546533Y805583D02*
X546867Y806667D01*
G01X112333Y-60000D02*
Y-65000D01*
X115667D01*
G01X119600D02*
X119100Y-64917D01*
X118600Y-64583D01*
X118267Y-64000D01*
X118100Y-63333D01*
X118267Y-62667D01*
X118600Y-62083D01*
X119100Y-61750D01*
X119600Y-61667D01*
X120100Y-61750D01*
X120600Y-62083D01*
X120933Y-62667D01*
X121017Y-63333D01*
X120933Y-64000D01*
X120600Y-64583D01*
X120100Y-64917D01*
X119600Y-65000D01*
G01X124033Y-66250D02*
X124617Y-66583D01*
X125283Y-66667D01*
X125867Y-66583D01*
X126367Y-66167D01*
X126700Y-65583D01*
Y-61667D01*
G01Y-62333D02*
X126367Y-62000D01*
X125867Y-61750D01*
X125283Y-61667D01*
X124617Y-61833D01*
X124200Y-62167D01*
X123867Y-62750D01*
X123700Y-63333D01*
X123783Y-63833D01*
X124117Y-64417D01*
X124617Y-64833D01*
X125283Y-65000D01*
X125783Y-64917D01*
X126367Y-64583D01*
X126700Y-64250D01*
G01X130800Y-65000D02*
X130300Y-64917D01*
X129800Y-64583D01*
X129467Y-64000D01*
X129300Y-63333D01*
X129467Y-62667D01*
X129800Y-62083D01*
X130300Y-61750D01*
X130800Y-61667D01*
X131300Y-61750D01*
X131800Y-62083D01*
X132133Y-62667D01*
X132217Y-63333D01*
X132133Y-64000D01*
X131800Y-64583D01*
X131300Y-64917D01*
X130800Y-65000D01*
G01X112333Y-60000D02*
Y-65000D01*
X115667D01*
G01X119600D02*
X119100Y-64917D01*
X118600Y-64583D01*
X118267Y-64000D01*
X118100Y-63333D01*
X118267Y-62667D01*
X118600Y-62083D01*
X119100Y-61750D01*
X119600Y-61667D01*
X120100Y-61750D01*
X120600Y-62083D01*
X120933Y-62667D01*
X121017Y-63333D01*
X120933Y-64000D01*
X120600Y-64583D01*
X120100Y-64917D01*
X119600Y-65000D01*
G01X124033Y-66250D02*
X124617Y-66583D01*
X125283Y-66667D01*
X125867Y-66583D01*
X126367Y-66167D01*
X126700Y-65583D01*
Y-61667D01*
G01Y-62333D02*
X126367Y-62000D01*
X125867Y-61750D01*
X125283Y-61667D01*
X124617Y-61833D01*
X124200Y-62167D01*
X123867Y-62750D01*
X123700Y-63333D01*
X123783Y-63833D01*
X124117Y-64417D01*
X124617Y-64833D01*
X125283Y-65000D01*
X125783Y-64917D01*
X126367Y-64583D01*
X126700Y-64250D01*
G01X130800Y-65000D02*
X130300Y-64917D01*
X129800Y-64583D01*
X129467Y-64000D01*
X129300Y-63333D01*
X129467Y-62667D01*
X129800Y-62083D01*
X130300Y-61750D01*
X130800Y-61667D01*
X131300Y-61750D01*
X131800Y-62083D01*
X132133Y-62667D01*
X132217Y-63333D01*
X132133Y-64000D01*
X131800Y-64583D01*
X131300Y-64917D01*
X130800Y-65000D01*
G01X114000Y-36000D02*
Y-41000D01*
G01X112833Y-37667D02*
X115167D01*
G01X118183Y-41000D02*
Y-36000D01*
G01Y-38417D02*
X118600Y-38000D01*
X119017Y-37750D01*
X119683Y-37667D01*
X120183Y-37750D01*
X120767Y-38083D01*
X121017Y-38583D01*
Y-41000D01*
G01X125200Y-37667D02*
Y-41000D01*
G01Y-36333D02*
X125033Y-36250D01*
Y-36083D01*
X125200Y-36000D01*
X125367Y-36083D01*
Y-36250D01*
X125200Y-36333D01*
G01X132133Y-38083D02*
X131550Y-37750D01*
X131050Y-37667D01*
X130383Y-37833D01*
X129883Y-38167D01*
X129550Y-38750D01*
X129467Y-39333D01*
X129550Y-39917D01*
X129883Y-40417D01*
X130383Y-40833D01*
X131050Y-41000D01*
X131633Y-40833D01*
X132133Y-40500D01*
G01X134983Y-41000D02*
Y-36000D01*
G01X137650Y-37667D02*
X134983Y-39583D01*
G01X136067Y-38833D02*
X137817Y-41000D01*
G01X140583D02*
Y-37667D01*
G01Y-38500D02*
X140917Y-38083D01*
X141417Y-37750D01*
X142083Y-37667D01*
X142667Y-37750D01*
X143167Y-38083D01*
X143417Y-38667D01*
Y-41000D01*
G01X146350Y-38750D02*
X149017D01*
X148767Y-38167D01*
X148350Y-37833D01*
X147767Y-37667D01*
X147183Y-37750D01*
X146683Y-38000D01*
X146350Y-38583D01*
X146183Y-39083D01*
Y-39583D01*
X146350Y-40083D01*
X146767Y-40583D01*
X147267Y-40917D01*
X147850Y-41000D01*
X148433Y-40833D01*
X149017Y-40333D01*
G01X151950Y-40417D02*
X152367Y-40750D01*
X152950Y-41000D01*
X153450D01*
X153950Y-40833D01*
X154283Y-40583D01*
X154450Y-40250D01*
X154367Y-39750D01*
X154033Y-39500D01*
X152533Y-39000D01*
X152200Y-38417D01*
X152367Y-38000D01*
X152700Y-37750D01*
X153200Y-37667D01*
X153700Y-37750D01*
X154200Y-38000D01*
G01X157550Y-40417D02*
X157967Y-40750D01*
X158550Y-41000D01*
X159050D01*
X159550Y-40833D01*
X159883Y-40583D01*
X160050Y-40250D01*
X159967Y-39750D01*
X159633Y-39500D01*
X158133Y-39000D01*
X157800Y-38417D01*
X157967Y-38000D01*
X158300Y-37750D01*
X158800Y-37667D01*
X159300Y-37750D01*
X159800Y-38000D01*
G01X114000Y-15000D02*
Y-20000D01*
G01X112833Y-16667D02*
X115167D01*
G01X118183Y-20000D02*
Y-15000D01*
G01Y-17417D02*
X118600Y-17000D01*
X119017Y-16750D01*
X119683Y-16667D01*
X120183Y-16750D01*
X120767Y-17083D01*
X121017Y-17583D01*
Y-20000D01*
G01X125200Y-16667D02*
Y-20000D01*
G01Y-15333D02*
X125033Y-15250D01*
Y-15083D01*
X125200Y-15000D01*
X125367Y-15083D01*
Y-15250D01*
X125200Y-15333D01*
G01X132133Y-17083D02*
X131550Y-16750D01*
X131050Y-16667D01*
X130383Y-16833D01*
X129883Y-17167D01*
X129550Y-17750D01*
X129467Y-18333D01*
X129550Y-18917D01*
X129883Y-19417D01*
X130383Y-19833D01*
X131050Y-20000D01*
X131633Y-19833D01*
X132133Y-19500D01*
G01X134983Y-20000D02*
Y-15000D01*
G01X137650Y-16667D02*
X134983Y-18583D01*
G01X136067Y-17833D02*
X137817Y-20000D01*
G01X140583D02*
Y-16667D01*
G01Y-17500D02*
X140917Y-17083D01*
X141417Y-16750D01*
X142083Y-16667D01*
X142667Y-16750D01*
X143167Y-17083D01*
X143417Y-17667D01*
Y-20000D01*
G01X146350Y-17750D02*
X149017D01*
X148767Y-17167D01*
X148350Y-16833D01*
X147767Y-16667D01*
X147183Y-16750D01*
X146683Y-17000D01*
X146350Y-17583D01*
X146183Y-18083D01*
Y-18583D01*
X146350Y-19083D01*
X146767Y-19583D01*
X147267Y-19917D01*
X147850Y-20000D01*
X148433Y-19833D01*
X149017Y-19333D01*
G01X151950Y-19417D02*
X152367Y-19750D01*
X152950Y-20000D01*
X153450D01*
X153950Y-19833D01*
X154283Y-19583D01*
X154450Y-19250D01*
X154367Y-18750D01*
X154033Y-18500D01*
X152533Y-18000D01*
X152200Y-17417D01*
X152367Y-17000D01*
X152700Y-16750D01*
X153200Y-16667D01*
X153700Y-16750D01*
X154200Y-17000D01*
G01X157550Y-19417D02*
X157967Y-19750D01*
X158550Y-20000D01*
X159050D01*
X159550Y-19833D01*
X159883Y-19583D01*
X160050Y-19250D01*
X159967Y-18750D01*
X159633Y-18500D01*
X158133Y-18000D01*
X157800Y-17417D01*
X157967Y-17000D01*
X158300Y-16750D01*
X158800Y-16667D01*
X159300Y-16750D01*
X159800Y-17000D01*
G01X119183Y-2167D02*
X118350Y-1333D01*
X117933Y-500D01*
Y2833D01*
X118350Y3667D01*
X119183Y4500D01*
G01X123450Y167D02*
X124117Y-250D01*
X124867Y-500D01*
X125533D01*
X126200Y-250D01*
X126700Y167D01*
X126950Y750D01*
X126783Y1333D01*
X126367Y1833D01*
X125617Y2167D01*
X124617Y2333D01*
X124033Y2667D01*
X123783Y3250D01*
X123950Y3833D01*
X124367Y4250D01*
X124950Y4500D01*
X125533D01*
X126117Y4333D01*
X126617Y3917D01*
G01X128633Y-500D02*
Y4500D01*
X130800Y333D01*
X132967Y4500D01*
Y-500D01*
G01X134567D02*
Y4500D01*
X136233D01*
X136900Y4250D01*
X137400Y3917D01*
X137817Y3417D01*
X138150Y2833D01*
X138233Y2000D01*
X138150Y1167D01*
X137817Y583D01*
X137400Y83D01*
X136900Y-250D01*
X136233Y-500D01*
X134567D01*
G01X142417Y-2167D02*
X143250Y-1333D01*
X143667Y-500D01*
Y2833D01*
X143250Y3667D01*
X142417Y4500D01*
G01X112250Y12167D02*
X112917Y11750D01*
X113667Y11500D01*
X114333D01*
X115000Y11750D01*
X115500Y12167D01*
X115750Y12750D01*
X115583Y13333D01*
X115167Y13833D01*
X114417Y14167D01*
X113417Y14333D01*
X112833Y14667D01*
X112583Y15250D01*
X112750Y15833D01*
X113167Y16250D01*
X113750Y16500D01*
X114333D01*
X114917Y16333D01*
X115417Y15917D01*
G01X119600Y11500D02*
X119100Y11583D01*
X118600Y11917D01*
X118267Y12500D01*
X118100Y13167D01*
X118267Y13833D01*
X118600Y14417D01*
X119100Y14750D01*
X119600Y14833D01*
X120100Y14750D01*
X120600Y14417D01*
X120933Y13833D01*
X121017Y13167D01*
X120933Y12500D01*
X120600Y11917D01*
X120100Y11583D01*
X119600Y11500D01*
G01X125200D02*
Y16500D01*
G01X132300D02*
Y11500D01*
G01Y12250D02*
X131967Y11833D01*
X131467Y11583D01*
X130883Y11500D01*
X130217Y11667D01*
X129717Y12083D01*
X129383Y12583D01*
X129300Y13167D01*
X129383Y13750D01*
X129717Y14250D01*
X130217Y14667D01*
X130883Y14833D01*
X131467Y14750D01*
X131883Y14583D01*
X132300Y14250D01*
G01X135150Y13750D02*
X137817D01*
X137567Y14333D01*
X137150Y14667D01*
X136567Y14833D01*
X135983Y14750D01*
X135483Y14500D01*
X135150Y13917D01*
X134983Y13417D01*
Y12917D01*
X135150Y12417D01*
X135567Y11917D01*
X136067Y11583D01*
X136650Y11500D01*
X137233Y11667D01*
X137817Y12167D01*
G01X140833Y11500D02*
Y14833D01*
G01Y14167D02*
X141250Y14500D01*
X141667Y14750D01*
X142250Y14833D01*
X142667Y14750D01*
X143167Y14500D01*
G01X150700Y11500D02*
Y14833D01*
G01Y13917D02*
X150950Y14333D01*
X151367Y14667D01*
X151950Y14833D01*
X152533Y14667D01*
X152950Y14333D01*
X153200Y13917D01*
Y11500D01*
G01Y13917D02*
X153450Y14333D01*
X153867Y14667D01*
X154450Y14833D01*
X155033Y14667D01*
X155450Y14333D01*
X155700Y13833D01*
Y11500D01*
G01X160300D02*
Y14833D01*
G01Y14250D02*
X159967Y14583D01*
X159467Y14750D01*
X158883Y14833D01*
X158300Y14667D01*
X157800Y14333D01*
X157467Y13833D01*
X157300Y13167D01*
X157467Y12500D01*
X157800Y12000D01*
X158300Y11667D01*
X158883Y11500D01*
X159467Y11583D01*
X159967Y11833D01*
X160300Y12167D01*
G01X163150Y12083D02*
X163567Y11750D01*
X164150Y11500D01*
X164650D01*
X165150Y11667D01*
X165483Y11917D01*
X165650Y12250D01*
X165567Y12750D01*
X165233Y13000D01*
X163733Y13500D01*
X163400Y14083D01*
X163567Y14500D01*
X163900Y14750D01*
X164400Y14833D01*
X164900Y14750D01*
X165400Y14500D01*
G01X168583Y11500D02*
Y16500D01*
G01X171250Y14833D02*
X168583Y12917D01*
G01X169667Y13667D02*
X171417Y11500D01*
G01X182700Y16500D02*
Y11500D01*
G01Y12250D02*
X182367Y11833D01*
X181867Y11583D01*
X181283Y11500D01*
X180617Y11667D01*
X180117Y12083D01*
X179783Y12583D01*
X179700Y13167D01*
X179783Y13750D01*
X180117Y14250D01*
X180617Y14667D01*
X181283Y14833D01*
X181867Y14750D01*
X182283Y14583D01*
X182700Y14250D01*
G01X185550Y13750D02*
X188217D01*
X187967Y14333D01*
X187550Y14667D01*
X186967Y14833D01*
X186383Y14750D01*
X185883Y14500D01*
X185550Y13917D01*
X185383Y13417D01*
Y12917D01*
X185550Y12417D01*
X185967Y11917D01*
X186467Y11583D01*
X187050Y11500D01*
X187633Y11667D01*
X188217Y12167D01*
G01X191900Y11500D02*
Y15750D01*
X192067Y16167D01*
X192400Y16417D01*
X192900Y16500D01*
X193400Y16333D01*
X193650Y15917D01*
G01X192650Y14500D02*
X190983D01*
G01X198000Y14833D02*
Y11500D01*
G01Y16167D02*
X197833Y16250D01*
Y16417D01*
X198000Y16500D01*
X198167Y16417D01*
Y16250D01*
X198000Y16167D01*
G01X202183Y11500D02*
Y14833D01*
G01Y14000D02*
X202517Y14417D01*
X203017Y14750D01*
X203683Y14833D01*
X204267Y14750D01*
X204767Y14417D01*
X205017Y13833D01*
Y11500D01*
G01X207950Y13750D02*
X210617D01*
X210367Y14333D01*
X209950Y14667D01*
X209367Y14833D01*
X208783Y14750D01*
X208283Y14500D01*
X207950Y13917D01*
X207783Y13417D01*
Y12917D01*
X207950Y12417D01*
X208367Y11917D01*
X208867Y11583D01*
X209450Y11500D01*
X210033Y11667D01*
X210617Y12167D01*
G01X218900Y9833D02*
Y14833D01*
G01Y14083D02*
X219317Y14500D01*
X219733Y14750D01*
X220400Y14833D01*
X220983Y14750D01*
X221567Y14333D01*
X221817Y13750D01*
X221900Y13167D01*
X221817Y12583D01*
X221567Y12000D01*
X221067Y11667D01*
X220400Y11500D01*
X219817Y11583D01*
X219233Y11833D01*
X218900Y12167D01*
G01X227500Y11500D02*
Y14833D01*
G01Y14250D02*
X227167Y14583D01*
X226667Y14750D01*
X226083Y14833D01*
X225500Y14667D01*
X225000Y14333D01*
X224667Y13833D01*
X224500Y13167D01*
X224667Y12500D01*
X225000Y12000D01*
X225500Y11667D01*
X226083Y11500D01*
X226667Y11583D01*
X227167Y11833D01*
X227500Y12167D01*
G01X233100Y16500D02*
Y11500D01*
G01Y12250D02*
X232767Y11833D01*
X232267Y11583D01*
X231683Y11500D01*
X231017Y11667D01*
X230517Y12083D01*
X230183Y12583D01*
X230100Y13167D01*
X230183Y13750D01*
X230517Y14250D01*
X231017Y14667D01*
X231683Y14833D01*
X232267Y14750D01*
X232683Y14583D01*
X233100Y14250D01*
G01X114000Y-36000D02*
Y-41000D01*
G01X112833Y-37667D02*
X115167D01*
G01X118183Y-41000D02*
Y-36000D01*
G01Y-38417D02*
X118600Y-38000D01*
X119017Y-37750D01*
X119683Y-37667D01*
X120183Y-37750D01*
X120767Y-38083D01*
X121017Y-38583D01*
Y-41000D01*
G01X125200Y-37667D02*
Y-41000D01*
G01Y-36333D02*
X125033Y-36250D01*
Y-36083D01*
X125200Y-36000D01*
X125367Y-36083D01*
Y-36250D01*
X125200Y-36333D01*
G01X132133Y-38083D02*
X131550Y-37750D01*
X131050Y-37667D01*
X130383Y-37833D01*
X129883Y-38167D01*
X129550Y-38750D01*
X129467Y-39333D01*
X129550Y-39917D01*
X129883Y-40417D01*
X130383Y-40833D01*
X131050Y-41000D01*
X131633Y-40833D01*
X132133Y-40500D01*
G01X134983Y-41000D02*
Y-36000D01*
G01X137650Y-37667D02*
X134983Y-39583D01*
G01X136067Y-38833D02*
X137817Y-41000D01*
G01X140583D02*
Y-37667D01*
G01Y-38500D02*
X140917Y-38083D01*
X141417Y-37750D01*
X142083Y-37667D01*
X142667Y-37750D01*
X143167Y-38083D01*
X143417Y-38667D01*
Y-41000D01*
G01X146350Y-38750D02*
X149017D01*
X148767Y-38167D01*
X148350Y-37833D01*
X147767Y-37667D01*
X147183Y-37750D01*
X146683Y-38000D01*
X146350Y-38583D01*
X146183Y-39083D01*
Y-39583D01*
X146350Y-40083D01*
X146767Y-40583D01*
X147267Y-40917D01*
X147850Y-41000D01*
X148433Y-40833D01*
X149017Y-40333D01*
G01X151950Y-40417D02*
X152367Y-40750D01*
X152950Y-41000D01*
X153450D01*
X153950Y-40833D01*
X154283Y-40583D01*
X154450Y-40250D01*
X154367Y-39750D01*
X154033Y-39500D01*
X152533Y-39000D01*
X152200Y-38417D01*
X152367Y-38000D01*
X152700Y-37750D01*
X153200Y-37667D01*
X153700Y-37750D01*
X154200Y-38000D01*
G01X157550Y-40417D02*
X157967Y-40750D01*
X158550Y-41000D01*
X159050D01*
X159550Y-40833D01*
X159883Y-40583D01*
X160050Y-40250D01*
X159967Y-39750D01*
X159633Y-39500D01*
X158133Y-39000D01*
X157800Y-38417D01*
X157967Y-38000D01*
X158300Y-37750D01*
X158800Y-37667D01*
X159300Y-37750D01*
X159800Y-38000D01*
G01X114000Y-15000D02*
Y-20000D01*
G01X112833Y-16667D02*
X115167D01*
G01X118183Y-20000D02*
Y-15000D01*
G01Y-17417D02*
X118600Y-17000D01*
X119017Y-16750D01*
X119683Y-16667D01*
X120183Y-16750D01*
X120767Y-17083D01*
X121017Y-17583D01*
Y-20000D01*
G01X125200Y-16667D02*
Y-20000D01*
G01Y-15333D02*
X125033Y-15250D01*
Y-15083D01*
X125200Y-15000D01*
X125367Y-15083D01*
Y-15250D01*
X125200Y-15333D01*
G01X132133Y-17083D02*
X131550Y-16750D01*
X131050Y-16667D01*
X130383Y-16833D01*
X129883Y-17167D01*
X129550Y-17750D01*
X129467Y-18333D01*
X129550Y-18917D01*
X129883Y-19417D01*
X130383Y-19833D01*
X131050Y-20000D01*
X131633Y-19833D01*
X132133Y-19500D01*
G01X134983Y-20000D02*
Y-15000D01*
G01X137650Y-16667D02*
X134983Y-18583D01*
G01X136067Y-17833D02*
X137817Y-20000D01*
G01X140583D02*
Y-16667D01*
G01Y-17500D02*
X140917Y-17083D01*
X141417Y-16750D01*
X142083Y-16667D01*
X142667Y-16750D01*
X143167Y-17083D01*
X143417Y-17667D01*
Y-20000D01*
G01X146350Y-17750D02*
X149017D01*
X148767Y-17167D01*
X148350Y-16833D01*
X147767Y-16667D01*
X147183Y-16750D01*
X146683Y-17000D01*
X146350Y-17583D01*
X146183Y-18083D01*
Y-18583D01*
X146350Y-19083D01*
X146767Y-19583D01*
X147267Y-19917D01*
X147850Y-20000D01*
X148433Y-19833D01*
X149017Y-19333D01*
G01X151950Y-19417D02*
X152367Y-19750D01*
X152950Y-20000D01*
X153450D01*
X153950Y-19833D01*
X154283Y-19583D01*
X154450Y-19250D01*
X154367Y-18750D01*
X154033Y-18500D01*
X152533Y-18000D01*
X152200Y-17417D01*
X152367Y-17000D01*
X152700Y-16750D01*
X153200Y-16667D01*
X153700Y-16750D01*
X154200Y-17000D01*
G01X157550Y-19417D02*
X157967Y-19750D01*
X158550Y-20000D01*
X159050D01*
X159550Y-19833D01*
X159883Y-19583D01*
X160050Y-19250D01*
X159967Y-18750D01*
X159633Y-18500D01*
X158133Y-18000D01*
X157800Y-17417D01*
X157967Y-17000D01*
X158300Y-16750D01*
X158800Y-16667D01*
X159300Y-16750D01*
X159800Y-17000D01*
G01X119183Y-2167D02*
X118350Y-1333D01*
X117933Y-500D01*
Y2833D01*
X118350Y3667D01*
X119183Y4500D01*
G01X123450Y167D02*
X124117Y-250D01*
X124867Y-500D01*
X125533D01*
X126200Y-250D01*
X126700Y167D01*
X126950Y750D01*
X126783Y1333D01*
X126367Y1833D01*
X125617Y2167D01*
X124617Y2333D01*
X124033Y2667D01*
X123783Y3250D01*
X123950Y3833D01*
X124367Y4250D01*
X124950Y4500D01*
X125533D01*
X126117Y4333D01*
X126617Y3917D01*
G01X128633Y-500D02*
Y4500D01*
X130800Y333D01*
X132967Y4500D01*
Y-500D01*
G01X134567D02*
Y4500D01*
X136233D01*
X136900Y4250D01*
X137400Y3917D01*
X137817Y3417D01*
X138150Y2833D01*
X138233Y2000D01*
X138150Y1167D01*
X137817Y583D01*
X137400Y83D01*
X136900Y-250D01*
X136233Y-500D01*
X134567D01*
G01X142417Y-2167D02*
X143250Y-1333D01*
X143667Y-500D01*
Y2833D01*
X143250Y3667D01*
X142417Y4500D01*
G01X112250Y12167D02*
X112917Y11750D01*
X113667Y11500D01*
X114333D01*
X115000Y11750D01*
X115500Y12167D01*
X115750Y12750D01*
X115583Y13333D01*
X115167Y13833D01*
X114417Y14167D01*
X113417Y14333D01*
X112833Y14667D01*
X112583Y15250D01*
X112750Y15833D01*
X113167Y16250D01*
X113750Y16500D01*
X114333D01*
X114917Y16333D01*
X115417Y15917D01*
G01X119600Y11500D02*
X119100Y11583D01*
X118600Y11917D01*
X118267Y12500D01*
X118100Y13167D01*
X118267Y13833D01*
X118600Y14417D01*
X119100Y14750D01*
X119600Y14833D01*
X120100Y14750D01*
X120600Y14417D01*
X120933Y13833D01*
X121017Y13167D01*
X120933Y12500D01*
X120600Y11917D01*
X120100Y11583D01*
X119600Y11500D01*
G01X125200D02*
Y16500D01*
G01X132300D02*
Y11500D01*
G01Y12250D02*
X131967Y11833D01*
X131467Y11583D01*
X130883Y11500D01*
X130217Y11667D01*
X129717Y12083D01*
X129383Y12583D01*
X129300Y13167D01*
X129383Y13750D01*
X129717Y14250D01*
X130217Y14667D01*
X130883Y14833D01*
X131467Y14750D01*
X131883Y14583D01*
X132300Y14250D01*
G01X135150Y13750D02*
X137817D01*
X137567Y14333D01*
X137150Y14667D01*
X136567Y14833D01*
X135983Y14750D01*
X135483Y14500D01*
X135150Y13917D01*
X134983Y13417D01*
Y12917D01*
X135150Y12417D01*
X135567Y11917D01*
X136067Y11583D01*
X136650Y11500D01*
X137233Y11667D01*
X137817Y12167D01*
G01X140833Y11500D02*
Y14833D01*
G01Y14167D02*
X141250Y14500D01*
X141667Y14750D01*
X142250Y14833D01*
X142667Y14750D01*
X143167Y14500D01*
G01X150700Y11500D02*
Y14833D01*
G01Y13917D02*
X150950Y14333D01*
X151367Y14667D01*
X151950Y14833D01*
X152533Y14667D01*
X152950Y14333D01*
X153200Y13917D01*
Y11500D01*
G01Y13917D02*
X153450Y14333D01*
X153867Y14667D01*
X154450Y14833D01*
X155033Y14667D01*
X155450Y14333D01*
X155700Y13833D01*
Y11500D01*
G01X160300D02*
Y14833D01*
G01Y14250D02*
X159967Y14583D01*
X159467Y14750D01*
X158883Y14833D01*
X158300Y14667D01*
X157800Y14333D01*
X157467Y13833D01*
X157300Y13167D01*
X157467Y12500D01*
X157800Y12000D01*
X158300Y11667D01*
X158883Y11500D01*
X159467Y11583D01*
X159967Y11833D01*
X160300Y12167D01*
G01X163150Y12083D02*
X163567Y11750D01*
X164150Y11500D01*
X164650D01*
X165150Y11667D01*
X165483Y11917D01*
X165650Y12250D01*
X165567Y12750D01*
X165233Y13000D01*
X163733Y13500D01*
X163400Y14083D01*
X163567Y14500D01*
X163900Y14750D01*
X164400Y14833D01*
X164900Y14750D01*
X165400Y14500D01*
G01X168583Y11500D02*
Y16500D01*
G01X171250Y14833D02*
X168583Y12917D01*
G01X169667Y13667D02*
X171417Y11500D01*
G01X182700Y16500D02*
Y11500D01*
G01Y12250D02*
X182367Y11833D01*
X181867Y11583D01*
X181283Y11500D01*
X180617Y11667D01*
X180117Y12083D01*
X179783Y12583D01*
X179700Y13167D01*
X179783Y13750D01*
X180117Y14250D01*
X180617Y14667D01*
X181283Y14833D01*
X181867Y14750D01*
X182283Y14583D01*
X182700Y14250D01*
G01X185550Y13750D02*
X188217D01*
X187967Y14333D01*
X187550Y14667D01*
X186967Y14833D01*
X186383Y14750D01*
X185883Y14500D01*
X185550Y13917D01*
X185383Y13417D01*
Y12917D01*
X185550Y12417D01*
X185967Y11917D01*
X186467Y11583D01*
X187050Y11500D01*
X187633Y11667D01*
X188217Y12167D01*
G01X191900Y11500D02*
Y15750D01*
X192067Y16167D01*
X192400Y16417D01*
X192900Y16500D01*
X193400Y16333D01*
X193650Y15917D01*
G01X192650Y14500D02*
X190983D01*
G01X198000Y14833D02*
Y11500D01*
G01Y16167D02*
X197833Y16250D01*
Y16417D01*
X198000Y16500D01*
X198167Y16417D01*
Y16250D01*
X198000Y16167D01*
G01X202183Y11500D02*
Y14833D01*
G01Y14000D02*
X202517Y14417D01*
X203017Y14750D01*
X203683Y14833D01*
X204267Y14750D01*
X204767Y14417D01*
X205017Y13833D01*
Y11500D01*
G01X207950Y13750D02*
X210617D01*
X210367Y14333D01*
X209950Y14667D01*
X209367Y14833D01*
X208783Y14750D01*
X208283Y14500D01*
X207950Y13917D01*
X207783Y13417D01*
Y12917D01*
X207950Y12417D01*
X208367Y11917D01*
X208867Y11583D01*
X209450Y11500D01*
X210033Y11667D01*
X210617Y12167D01*
G01X218900Y9833D02*
Y14833D01*
G01Y14083D02*
X219317Y14500D01*
X219733Y14750D01*
X220400Y14833D01*
X220983Y14750D01*
X221567Y14333D01*
X221817Y13750D01*
X221900Y13167D01*
X221817Y12583D01*
X221567Y12000D01*
X221067Y11667D01*
X220400Y11500D01*
X219817Y11583D01*
X219233Y11833D01*
X218900Y12167D01*
G01X227500Y11500D02*
Y14833D01*
G01Y14250D02*
X227167Y14583D01*
X226667Y14750D01*
X226083Y14833D01*
X225500Y14667D01*
X225000Y14333D01*
X224667Y13833D01*
X224500Y13167D01*
X224667Y12500D01*
X225000Y12000D01*
X225500Y11667D01*
X226083Y11500D01*
X226667Y11583D01*
X227167Y11833D01*
X227500Y12167D01*
G01X233100Y16500D02*
Y11500D01*
G01Y12250D02*
X232767Y11833D01*
X232267Y11583D01*
X231683Y11500D01*
X231017Y11667D01*
X230517Y12083D01*
X230183Y12583D01*
X230100Y13167D01*
X230183Y13750D01*
X230517Y14250D01*
X231017Y14667D01*
X231683Y14833D01*
X232267Y14750D01*
X232683Y14583D01*
X233100Y14250D01*
G01X112483Y24700D02*
Y29700D01*
X114650Y25533D01*
X116817Y29700D01*
Y24700D01*
G01X121750D02*
Y28033D01*
G01Y27450D02*
X121417Y27783D01*
X120917Y27950D01*
X120333Y28033D01*
X119750Y27867D01*
X119250Y27533D01*
X118917Y27033D01*
X118750Y26367D01*
X118917Y25700D01*
X119250Y25200D01*
X119750Y24867D01*
X120333Y24700D01*
X120917Y24783D01*
X121417Y25033D01*
X121750Y25367D01*
G01X124683Y24700D02*
Y28033D01*
G01Y27367D02*
X125100Y27700D01*
X125517Y27950D01*
X126100Y28033D01*
X126517Y27950D01*
X127017Y27700D01*
G01X130033Y24700D02*
Y29700D01*
G01X132700Y28033D02*
X130033Y26117D01*
G01X131117Y26867D02*
X132867Y24700D01*
G01X137467Y23033D02*
X138300Y23867D01*
X138717Y24700D01*
Y28033D01*
X138300Y28867D01*
X137467Y29700D01*
G01X113070Y36130D02*
X114737D01*
Y34630D01*
X114237Y34130D01*
X113653Y33797D01*
X112820Y33630D01*
X111987Y33797D01*
X111403Y34130D01*
X110903Y34630D01*
X110570Y35213D01*
X110403Y35880D01*
Y36463D01*
X110570Y36963D01*
X110903Y37547D01*
X111403Y38047D01*
X111903Y38380D01*
X112570Y38630D01*
X113153D01*
X113820Y38463D01*
X114320Y38130D01*
G01X118170Y33630D02*
X117670Y33713D01*
X117170Y34047D01*
X116837Y34630D01*
X116670Y35297D01*
X116837Y35963D01*
X117170Y36547D01*
X117670Y36880D01*
X118170Y36963D01*
X118670Y36880D01*
X119170Y36547D01*
X119503Y35963D01*
X119587Y35297D01*
X119503Y34630D01*
X119170Y34047D01*
X118670Y33713D01*
X118170Y33630D01*
G01X123770D02*
Y38630D01*
G01X130870D02*
Y33630D01*
G01Y34380D02*
X130537Y33963D01*
X130037Y33713D01*
X129453Y33630D01*
X128787Y33797D01*
X128287Y34213D01*
X127953Y34713D01*
X127870Y35297D01*
X127953Y35880D01*
X128287Y36380D01*
X128787Y36797D01*
X129453Y36963D01*
X130037Y36880D01*
X130453Y36713D01*
X130870Y36380D01*
G01X133720Y35880D02*
X136387D01*
X136137Y36463D01*
X135720Y36797D01*
X135137Y36963D01*
X134553Y36880D01*
X134053Y36630D01*
X133720Y36047D01*
X133553Y35547D01*
Y35047D01*
X133720Y34547D01*
X134137Y34047D01*
X134637Y33713D01*
X135220Y33630D01*
X135803Y33797D01*
X136387Y34297D01*
G01X139153Y33630D02*
Y36963D01*
G01Y36130D02*
X139487Y36547D01*
X139987Y36880D01*
X140653Y36963D01*
X141237Y36880D01*
X141737Y36547D01*
X141987Y35963D01*
Y33630D01*
G01X151270D02*
Y37880D01*
X151437Y38297D01*
X151770Y38547D01*
X152270Y38630D01*
X152770Y38463D01*
X153020Y38047D01*
G01X152020Y36630D02*
X150353D01*
G01X157370Y36963D02*
Y33630D01*
G01Y38297D02*
X157203Y38380D01*
Y38547D01*
X157370Y38630D01*
X157537Y38547D01*
Y38380D01*
X157370Y38297D01*
G01X161553Y33630D02*
Y36963D01*
G01Y36130D02*
X161887Y36547D01*
X162387Y36880D01*
X163053Y36963D01*
X163637Y36880D01*
X164137Y36547D01*
X164387Y35963D01*
Y33630D01*
G01X167403Y32380D02*
X167987Y32047D01*
X168653Y31963D01*
X169237Y32047D01*
X169737Y32463D01*
X170070Y33047D01*
Y36963D01*
G01Y36297D02*
X169737Y36630D01*
X169237Y36880D01*
X168653Y36963D01*
X167987Y36797D01*
X167570Y36463D01*
X167237Y35880D01*
X167070Y35297D01*
X167153Y34797D01*
X167487Y34213D01*
X167987Y33797D01*
X168653Y33630D01*
X169153Y33713D01*
X169737Y34047D01*
X170070Y34380D01*
G01X172920Y35880D02*
X175587D01*
X175337Y36463D01*
X174920Y36797D01*
X174337Y36963D01*
X173753Y36880D01*
X173253Y36630D01*
X172920Y36047D01*
X172753Y35547D01*
Y35047D01*
X172920Y34547D01*
X173337Y34047D01*
X173837Y33713D01*
X174420Y33630D01*
X175003Y33797D01*
X175587Y34297D01*
G01X178603Y33630D02*
Y36963D01*
G01Y36297D02*
X179020Y36630D01*
X179437Y36880D01*
X180020Y36963D01*
X180437Y36880D01*
X180937Y36630D01*
G01X189303Y33630D02*
Y38630D01*
X191303D01*
X191970Y38380D01*
X192470Y37797D01*
X192637Y37130D01*
X192470Y36463D01*
X192053Y35963D01*
X191303Y35713D01*
X189303D01*
G01X194487Y33630D02*
X196570Y38630D01*
X198653Y33630D01*
G01X197903Y35380D02*
X195237D01*
G01X200337Y33630D02*
Y38630D01*
X202003D01*
X202670Y38380D01*
X203170Y38047D01*
X203587Y37547D01*
X203920Y36963D01*
X204003Y36130D01*
X203920Y35297D01*
X203587Y34713D01*
X203170Y34213D01*
X202670Y33880D01*
X202003Y33630D01*
X200337D01*
G01X211870Y33463D02*
X214870Y38630D01*
G01X217387Y33630D02*
Y38630D01*
X220553D01*
G01X219387Y36213D02*
X217387D01*
G01X224570Y36963D02*
Y33630D01*
G01Y38297D02*
X224403Y38380D01*
Y38547D01*
X224570Y38630D01*
X224737Y38547D01*
Y38380D01*
X224570Y38297D01*
G01X231670Y38630D02*
Y33630D01*
G01Y34380D02*
X231337Y33963D01*
X230837Y33713D01*
X230253Y33630D01*
X229587Y33797D01*
X229087Y34213D01*
X228753Y34713D01*
X228670Y35297D01*
X228753Y35880D01*
X229087Y36380D01*
X229587Y36797D01*
X230253Y36963D01*
X230837Y36880D01*
X231253Y36713D01*
X231670Y36380D01*
G01X234353Y36963D02*
Y34630D01*
X234687Y34047D01*
X235187Y33713D01*
X235770Y33630D01*
X236353Y33713D01*
X236853Y34047D01*
X237187Y34630D01*
G01Y33630D02*
Y36963D01*
G01X242703Y36547D02*
X242120Y36880D01*
X241620Y36963D01*
X240953Y36797D01*
X240453Y36463D01*
X240120Y35880D01*
X240037Y35297D01*
X240120Y34713D01*
X240453Y34213D01*
X240953Y33797D01*
X241620Y33630D01*
X242203Y33797D01*
X242703Y34130D01*
G01X246970Y36963D02*
Y33630D01*
G01Y38297D02*
X246803Y38380D01*
Y38547D01*
X246970Y38630D01*
X247137Y38547D01*
Y38380D01*
X246970Y38297D01*
G01X254070Y33630D02*
Y36963D01*
G01Y36380D02*
X253737Y36713D01*
X253237Y36880D01*
X252653Y36963D01*
X252070Y36797D01*
X251570Y36463D01*
X251237Y35963D01*
X251070Y35297D01*
X251237Y34630D01*
X251570Y34130D01*
X252070Y33797D01*
X252653Y33630D01*
X253237Y33713D01*
X253737Y33963D01*
X254070Y34297D01*
G01X258170Y33630D02*
Y38630D01*
G01X112743Y42673D02*
X111910Y43507D01*
X111493Y44340D01*
Y47673D01*
X111910Y48507D01*
X112743Y49340D01*
G01X116260Y44340D02*
Y47673D01*
G01Y46757D02*
X116510Y47173D01*
X116927Y47507D01*
X117510Y47673D01*
X118093Y47507D01*
X118510Y47173D01*
X118760Y46757D01*
Y44340D01*
G01Y46757D02*
X119010Y47173D01*
X119427Y47507D01*
X120010Y47673D01*
X120593Y47507D01*
X121010Y47173D01*
X121260Y46673D01*
Y44340D01*
G01X123110Y46590D02*
X125777D01*
X125527Y47173D01*
X125110Y47507D01*
X124527Y47673D01*
X123943Y47590D01*
X123443Y47340D01*
X123110Y46757D01*
X122943Y46257D01*
Y45757D01*
X123110Y45257D01*
X123527Y44757D01*
X124027Y44423D01*
X124610Y44340D01*
X125193Y44507D01*
X125777Y45007D01*
G01X131460Y44340D02*
Y47673D01*
G01Y47090D02*
X131127Y47423D01*
X130627Y47590D01*
X130043Y47673D01*
X129460Y47507D01*
X128960Y47173D01*
X128627Y46673D01*
X128460Y46007D01*
X128627Y45340D01*
X128960Y44840D01*
X129460Y44507D01*
X130043Y44340D01*
X130627Y44423D01*
X131127Y44673D01*
X131460Y45007D01*
G01X134310Y44923D02*
X134727Y44590D01*
X135310Y44340D01*
X135810D01*
X136310Y44507D01*
X136643Y44757D01*
X136810Y45090D01*
X136727Y45590D01*
X136393Y45840D01*
X134893Y46340D01*
X134560Y46923D01*
X134727Y47340D01*
X135060Y47590D01*
X135560Y47673D01*
X136060Y47590D01*
X136560Y47340D01*
G01X139743Y47673D02*
Y45340D01*
X140077Y44757D01*
X140577Y44423D01*
X141160Y44340D01*
X141743Y44423D01*
X142243Y44757D01*
X142577Y45340D01*
G01Y44340D02*
Y47673D01*
G01X145593Y44340D02*
Y47673D01*
G01Y47007D02*
X146010Y47340D01*
X146427Y47590D01*
X147010Y47673D01*
X147427Y47590D01*
X147927Y47340D01*
G01X151110Y46590D02*
X153777D01*
X153527Y47173D01*
X153110Y47507D01*
X152527Y47673D01*
X151943Y47590D01*
X151443Y47340D01*
X151110Y46757D01*
X150943Y46257D01*
Y45757D01*
X151110Y45257D01*
X151527Y44757D01*
X152027Y44423D01*
X152610Y44340D01*
X153193Y44507D01*
X153777Y45007D01*
G01X163560Y49340D02*
Y44340D01*
G01X162393Y47673D02*
X164727D01*
G01X169160Y44340D02*
X168660Y44423D01*
X168160Y44757D01*
X167827Y45340D01*
X167660Y46007D01*
X167827Y46673D01*
X168160Y47257D01*
X168660Y47590D01*
X169160Y47673D01*
X169660Y47590D01*
X170160Y47257D01*
X170493Y46673D01*
X170577Y46007D01*
X170493Y45340D01*
X170160Y44757D01*
X169660Y44423D01*
X169160Y44340D01*
G01X173260Y42673D02*
Y47673D01*
G01Y46923D02*
X173677Y47340D01*
X174093Y47590D01*
X174760Y47673D01*
X175343Y47590D01*
X175927Y47173D01*
X176177Y46590D01*
X176260Y46007D01*
X176177Y45423D01*
X175927Y44840D01*
X175427Y44507D01*
X174760Y44340D01*
X174177Y44423D01*
X173593Y44673D01*
X173260Y45007D01*
G01X184710Y44923D02*
X185127Y44590D01*
X185710Y44340D01*
X186210D01*
X186710Y44507D01*
X187043Y44757D01*
X187210Y45090D01*
X187127Y45590D01*
X186793Y45840D01*
X185293Y46340D01*
X184960Y46923D01*
X185127Y47340D01*
X185460Y47590D01*
X185960Y47673D01*
X186460Y47590D01*
X186960Y47340D01*
G01X191560Y47673D02*
Y44340D01*
G01Y49007D02*
X191393Y49090D01*
Y49257D01*
X191560Y49340D01*
X191727Y49257D01*
Y49090D01*
X191560Y49007D01*
G01X195910Y47673D02*
X198410D01*
X195910Y44340D01*
X198410D01*
G01X201510Y46590D02*
X204177D01*
X203927Y47173D01*
X203510Y47507D01*
X202927Y47673D01*
X202343Y47590D01*
X201843Y47340D01*
X201510Y46757D01*
X201343Y46257D01*
Y45757D01*
X201510Y45257D01*
X201927Y44757D01*
X202427Y44423D01*
X203010Y44340D01*
X203593Y44507D01*
X204177Y45007D01*
G01X213960Y44340D02*
X213460Y44423D01*
X212960Y44757D01*
X212627Y45340D01*
X212460Y46007D01*
X212627Y46673D01*
X212960Y47257D01*
X213460Y47590D01*
X213960Y47673D01*
X214460Y47590D01*
X214960Y47257D01*
X215293Y46673D01*
X215377Y46007D01*
X215293Y45340D01*
X214960Y44757D01*
X214460Y44423D01*
X213960Y44340D01*
G01X219060D02*
Y48590D01*
X219227Y49007D01*
X219560Y49257D01*
X220060Y49340D01*
X220560Y49173D01*
X220810Y48757D01*
G01X219810Y47340D02*
X218143D01*
G01X229093Y44340D02*
Y49340D01*
X231093D01*
X231760Y49090D01*
X232260Y48507D01*
X232427Y47840D01*
X232260Y47173D01*
X231843Y46673D01*
X231093Y46423D01*
X229093D01*
G01X234277Y44340D02*
X236360Y49340D01*
X238443Y44340D01*
G01X237693Y46090D02*
X235027D01*
G01X240127Y44340D02*
Y49340D01*
X241793D01*
X242460Y49090D01*
X242960Y48757D01*
X243377Y48257D01*
X243710Y47673D01*
X243793Y46840D01*
X243710Y46007D01*
X243377Y45423D01*
X242960Y44923D01*
X242460Y44590D01*
X241793Y44340D01*
X240127D01*
G01X251660Y44173D02*
X254660Y49340D01*
G01X112333Y51500D02*
Y56500D01*
X114333D01*
X115000Y56250D01*
X115500Y55667D01*
X115667Y55000D01*
X115500Y54333D01*
X115083Y53833D01*
X114333Y53583D01*
X112333D01*
G01X117517Y51500D02*
X119600Y56500D01*
X121683Y51500D01*
G01X120933Y53250D02*
X118267D01*
G01X123367Y51500D02*
Y56500D01*
X125033D01*
X125700Y56250D01*
X126200Y55917D01*
X126617Y55417D01*
X126950Y54833D01*
X127033Y54000D01*
X126950Y53167D01*
X126617Y52583D01*
X126200Y52083D01*
X125700Y51750D01*
X125033Y51500D01*
X123367D01*
G01X135150Y52083D02*
X135567Y51750D01*
X136150Y51500D01*
X136650D01*
X137150Y51667D01*
X137483Y51917D01*
X137650Y52250D01*
X137567Y52750D01*
X137233Y53000D01*
X135733Y53500D01*
X135400Y54083D01*
X135567Y54500D01*
X135900Y54750D01*
X136400Y54833D01*
X136900Y54750D01*
X137400Y54500D01*
G01X142000Y54833D02*
Y51500D01*
G01Y56167D02*
X141833Y56250D01*
Y56417D01*
X142000Y56500D01*
X142167Y56417D01*
Y56250D01*
X142000Y56167D01*
G01X146350Y54833D02*
X148850D01*
X146350Y51500D01*
X148850D01*
G01X151950Y53750D02*
X154617D01*
X154367Y54333D01*
X153950Y54667D01*
X153367Y54833D01*
X152783Y54750D01*
X152283Y54500D01*
X151950Y53917D01*
X151783Y53417D01*
Y52917D01*
X151950Y52417D01*
X152367Y51917D01*
X152867Y51583D01*
X153450Y51500D01*
X154033Y51667D01*
X154617Y52167D01*
G01X114000Y85000D02*
Y80000D01*
G01X112083Y85000D02*
X115917D01*
G01X118433Y80000D02*
Y83333D01*
G01Y82667D02*
X118850Y83000D01*
X119267Y83250D01*
X119850Y83333D01*
X120267Y83250D01*
X120767Y83000D01*
G01X126700Y80000D02*
Y83333D01*
G01Y82750D02*
X126367Y83083D01*
X125867Y83250D01*
X125283Y83333D01*
X124700Y83167D01*
X124200Y82833D01*
X123867Y82333D01*
X123700Y81667D01*
X123867Y81000D01*
X124200Y80500D01*
X124700Y80167D01*
X125283Y80000D01*
X125867Y80083D01*
X126367Y80333D01*
X126700Y80667D01*
G01X132133Y82917D02*
X131550Y83250D01*
X131050Y83333D01*
X130383Y83167D01*
X129883Y82833D01*
X129550Y82250D01*
X129467Y81667D01*
X129550Y81083D01*
X129883Y80583D01*
X130383Y80167D01*
X131050Y80000D01*
X131633Y80167D01*
X132133Y80500D01*
G01X135150Y82250D02*
X137817D01*
X137567Y82833D01*
X137150Y83167D01*
X136567Y83333D01*
X135983Y83250D01*
X135483Y83000D01*
X135150Y82417D01*
X134983Y81917D01*
Y81417D01*
X135150Y80917D01*
X135567Y80417D01*
X136067Y80083D01*
X136650Y80000D01*
X137233Y80167D01*
X137817Y80667D01*
G01X145517Y83333D02*
X146517Y80000D01*
X147600Y83333D01*
X148683Y80000D01*
X149683Y83333D01*
G01X153200D02*
Y80000D01*
G01Y84667D02*
X153033Y84750D01*
Y84917D01*
X153200Y85000D01*
X153367Y84917D01*
Y84750D01*
X153200Y84667D01*
G01X160300Y85000D02*
Y80000D01*
G01Y80750D02*
X159967Y80333D01*
X159467Y80083D01*
X158883Y80000D01*
X158217Y80167D01*
X157717Y80583D01*
X157383Y81083D01*
X157300Y81667D01*
X157383Y82250D01*
X157717Y82750D01*
X158217Y83167D01*
X158883Y83333D01*
X159467Y83250D01*
X159883Y83083D01*
X160300Y82750D01*
G01X164400Y85000D02*
Y80000D01*
G01X163233Y83333D02*
X165567D01*
G01X168583Y80000D02*
Y85000D01*
G01Y82583D02*
X169000Y83000D01*
X169417Y83250D01*
X170083Y83333D01*
X170583Y83250D01*
X171167Y82917D01*
X171417Y82417D01*
Y80000D01*
G01X112483Y24700D02*
Y29700D01*
X114650Y25533D01*
X116817Y29700D01*
Y24700D01*
G01X121750D02*
Y28033D01*
G01Y27450D02*
X121417Y27783D01*
X120917Y27950D01*
X120333Y28033D01*
X119750Y27867D01*
X119250Y27533D01*
X118917Y27033D01*
X118750Y26367D01*
X118917Y25700D01*
X119250Y25200D01*
X119750Y24867D01*
X120333Y24700D01*
X120917Y24783D01*
X121417Y25033D01*
X121750Y25367D01*
G01X124683Y24700D02*
Y28033D01*
G01Y27367D02*
X125100Y27700D01*
X125517Y27950D01*
X126100Y28033D01*
X126517Y27950D01*
X127017Y27700D01*
G01X130033Y24700D02*
Y29700D01*
G01X132700Y28033D02*
X130033Y26117D01*
G01X131117Y26867D02*
X132867Y24700D01*
G01X137467Y23033D02*
X138300Y23867D01*
X138717Y24700D01*
Y28033D01*
X138300Y28867D01*
X137467Y29700D01*
G01X113070Y36130D02*
X114737D01*
Y34630D01*
X114237Y34130D01*
X113653Y33797D01*
X112820Y33630D01*
X111987Y33797D01*
X111403Y34130D01*
X110903Y34630D01*
X110570Y35213D01*
X110403Y35880D01*
Y36463D01*
X110570Y36963D01*
X110903Y37547D01*
X111403Y38047D01*
X111903Y38380D01*
X112570Y38630D01*
X113153D01*
X113820Y38463D01*
X114320Y38130D01*
G01X118170Y33630D02*
X117670Y33713D01*
X117170Y34047D01*
X116837Y34630D01*
X116670Y35297D01*
X116837Y35963D01*
X117170Y36547D01*
X117670Y36880D01*
X118170Y36963D01*
X118670Y36880D01*
X119170Y36547D01*
X119503Y35963D01*
X119587Y35297D01*
X119503Y34630D01*
X119170Y34047D01*
X118670Y33713D01*
X118170Y33630D01*
G01X123770D02*
Y38630D01*
G01X130870D02*
Y33630D01*
G01Y34380D02*
X130537Y33963D01*
X130037Y33713D01*
X129453Y33630D01*
X128787Y33797D01*
X128287Y34213D01*
X127953Y34713D01*
X127870Y35297D01*
X127953Y35880D01*
X128287Y36380D01*
X128787Y36797D01*
X129453Y36963D01*
X130037Y36880D01*
X130453Y36713D01*
X130870Y36380D01*
G01X133720Y35880D02*
X136387D01*
X136137Y36463D01*
X135720Y36797D01*
X135137Y36963D01*
X134553Y36880D01*
X134053Y36630D01*
X133720Y36047D01*
X133553Y35547D01*
Y35047D01*
X133720Y34547D01*
X134137Y34047D01*
X134637Y33713D01*
X135220Y33630D01*
X135803Y33797D01*
X136387Y34297D01*
G01X139153Y33630D02*
Y36963D01*
G01Y36130D02*
X139487Y36547D01*
X139987Y36880D01*
X140653Y36963D01*
X141237Y36880D01*
X141737Y36547D01*
X141987Y35963D01*
Y33630D01*
G01X151270D02*
Y37880D01*
X151437Y38297D01*
X151770Y38547D01*
X152270Y38630D01*
X152770Y38463D01*
X153020Y38047D01*
G01X152020Y36630D02*
X150353D01*
G01X157370Y36963D02*
Y33630D01*
G01Y38297D02*
X157203Y38380D01*
Y38547D01*
X157370Y38630D01*
X157537Y38547D01*
Y38380D01*
X157370Y38297D01*
G01X161553Y33630D02*
Y36963D01*
G01Y36130D02*
X161887Y36547D01*
X162387Y36880D01*
X163053Y36963D01*
X163637Y36880D01*
X164137Y36547D01*
X164387Y35963D01*
Y33630D01*
G01X167403Y32380D02*
X167987Y32047D01*
X168653Y31963D01*
X169237Y32047D01*
X169737Y32463D01*
X170070Y33047D01*
Y36963D01*
G01Y36297D02*
X169737Y36630D01*
X169237Y36880D01*
X168653Y36963D01*
X167987Y36797D01*
X167570Y36463D01*
X167237Y35880D01*
X167070Y35297D01*
X167153Y34797D01*
X167487Y34213D01*
X167987Y33797D01*
X168653Y33630D01*
X169153Y33713D01*
X169737Y34047D01*
X170070Y34380D01*
G01X172920Y35880D02*
X175587D01*
X175337Y36463D01*
X174920Y36797D01*
X174337Y36963D01*
X173753Y36880D01*
X173253Y36630D01*
X172920Y36047D01*
X172753Y35547D01*
Y35047D01*
X172920Y34547D01*
X173337Y34047D01*
X173837Y33713D01*
X174420Y33630D01*
X175003Y33797D01*
X175587Y34297D01*
G01X178603Y33630D02*
Y36963D01*
G01Y36297D02*
X179020Y36630D01*
X179437Y36880D01*
X180020Y36963D01*
X180437Y36880D01*
X180937Y36630D01*
G01X189303Y33630D02*
Y38630D01*
X191303D01*
X191970Y38380D01*
X192470Y37797D01*
X192637Y37130D01*
X192470Y36463D01*
X192053Y35963D01*
X191303Y35713D01*
X189303D01*
G01X194487Y33630D02*
X196570Y38630D01*
X198653Y33630D01*
G01X197903Y35380D02*
X195237D01*
G01X200337Y33630D02*
Y38630D01*
X202003D01*
X202670Y38380D01*
X203170Y38047D01*
X203587Y37547D01*
X203920Y36963D01*
X204003Y36130D01*
X203920Y35297D01*
X203587Y34713D01*
X203170Y34213D01*
X202670Y33880D01*
X202003Y33630D01*
X200337D01*
G01X211870Y33463D02*
X214870Y38630D01*
G01X217387Y33630D02*
Y38630D01*
X220553D01*
G01X219387Y36213D02*
X217387D01*
G01X224570Y36963D02*
Y33630D01*
G01Y38297D02*
X224403Y38380D01*
Y38547D01*
X224570Y38630D01*
X224737Y38547D01*
Y38380D01*
X224570Y38297D01*
G01X231670Y38630D02*
Y33630D01*
G01Y34380D02*
X231337Y33963D01*
X230837Y33713D01*
X230253Y33630D01*
X229587Y33797D01*
X229087Y34213D01*
X228753Y34713D01*
X228670Y35297D01*
X228753Y35880D01*
X229087Y36380D01*
X229587Y36797D01*
X230253Y36963D01*
X230837Y36880D01*
X231253Y36713D01*
X231670Y36380D01*
G01X234353Y36963D02*
Y34630D01*
X234687Y34047D01*
X235187Y33713D01*
X235770Y33630D01*
X236353Y33713D01*
X236853Y34047D01*
X237187Y34630D01*
G01Y33630D02*
Y36963D01*
G01X242703Y36547D02*
X242120Y36880D01*
X241620Y36963D01*
X240953Y36797D01*
X240453Y36463D01*
X240120Y35880D01*
X240037Y35297D01*
X240120Y34713D01*
X240453Y34213D01*
X240953Y33797D01*
X241620Y33630D01*
X242203Y33797D01*
X242703Y34130D01*
G01X246970Y36963D02*
Y33630D01*
G01Y38297D02*
X246803Y38380D01*
Y38547D01*
X246970Y38630D01*
X247137Y38547D01*
Y38380D01*
X246970Y38297D01*
G01X254070Y33630D02*
Y36963D01*
G01Y36380D02*
X253737Y36713D01*
X253237Y36880D01*
X252653Y36963D01*
X252070Y36797D01*
X251570Y36463D01*
X251237Y35963D01*
X251070Y35297D01*
X251237Y34630D01*
X251570Y34130D01*
X252070Y33797D01*
X252653Y33630D01*
X253237Y33713D01*
X253737Y33963D01*
X254070Y34297D01*
G01X258170Y33630D02*
Y38630D01*
G01X112743Y42673D02*
X111910Y43507D01*
X111493Y44340D01*
Y47673D01*
X111910Y48507D01*
X112743Y49340D01*
G01X116260Y44340D02*
Y47673D01*
G01Y46757D02*
X116510Y47173D01*
X116927Y47507D01*
X117510Y47673D01*
X118093Y47507D01*
X118510Y47173D01*
X118760Y46757D01*
Y44340D01*
G01Y46757D02*
X119010Y47173D01*
X119427Y47507D01*
X120010Y47673D01*
X120593Y47507D01*
X121010Y47173D01*
X121260Y46673D01*
Y44340D01*
G01X123110Y46590D02*
X125777D01*
X125527Y47173D01*
X125110Y47507D01*
X124527Y47673D01*
X123943Y47590D01*
X123443Y47340D01*
X123110Y46757D01*
X122943Y46257D01*
Y45757D01*
X123110Y45257D01*
X123527Y44757D01*
X124027Y44423D01*
X124610Y44340D01*
X125193Y44507D01*
X125777Y45007D01*
G01X131460Y44340D02*
Y47673D01*
G01Y47090D02*
X131127Y47423D01*
X130627Y47590D01*
X130043Y47673D01*
X129460Y47507D01*
X128960Y47173D01*
X128627Y46673D01*
X128460Y46007D01*
X128627Y45340D01*
X128960Y44840D01*
X129460Y44507D01*
X130043Y44340D01*
X130627Y44423D01*
X131127Y44673D01*
X131460Y45007D01*
G01X134310Y44923D02*
X134727Y44590D01*
X135310Y44340D01*
X135810D01*
X136310Y44507D01*
X136643Y44757D01*
X136810Y45090D01*
X136727Y45590D01*
X136393Y45840D01*
X134893Y46340D01*
X134560Y46923D01*
X134727Y47340D01*
X135060Y47590D01*
X135560Y47673D01*
X136060Y47590D01*
X136560Y47340D01*
G01X139743Y47673D02*
Y45340D01*
X140077Y44757D01*
X140577Y44423D01*
X141160Y44340D01*
X141743Y44423D01*
X142243Y44757D01*
X142577Y45340D01*
G01Y44340D02*
Y47673D01*
G01X145593Y44340D02*
Y47673D01*
G01Y47007D02*
X146010Y47340D01*
X146427Y47590D01*
X147010Y47673D01*
X147427Y47590D01*
X147927Y47340D01*
G01X151110Y46590D02*
X153777D01*
X153527Y47173D01*
X153110Y47507D01*
X152527Y47673D01*
X151943Y47590D01*
X151443Y47340D01*
X151110Y46757D01*
X150943Y46257D01*
Y45757D01*
X151110Y45257D01*
X151527Y44757D01*
X152027Y44423D01*
X152610Y44340D01*
X153193Y44507D01*
X153777Y45007D01*
G01X163560Y49340D02*
Y44340D01*
G01X162393Y47673D02*
X164727D01*
G01X169160Y44340D02*
X168660Y44423D01*
X168160Y44757D01*
X167827Y45340D01*
X167660Y46007D01*
X167827Y46673D01*
X168160Y47257D01*
X168660Y47590D01*
X169160Y47673D01*
X169660Y47590D01*
X170160Y47257D01*
X170493Y46673D01*
X170577Y46007D01*
X170493Y45340D01*
X170160Y44757D01*
X169660Y44423D01*
X169160Y44340D01*
G01X173260Y42673D02*
Y47673D01*
G01Y46923D02*
X173677Y47340D01*
X174093Y47590D01*
X174760Y47673D01*
X175343Y47590D01*
X175927Y47173D01*
X176177Y46590D01*
X176260Y46007D01*
X176177Y45423D01*
X175927Y44840D01*
X175427Y44507D01*
X174760Y44340D01*
X174177Y44423D01*
X173593Y44673D01*
X173260Y45007D01*
G01X184710Y44923D02*
X185127Y44590D01*
X185710Y44340D01*
X186210D01*
X186710Y44507D01*
X187043Y44757D01*
X187210Y45090D01*
X187127Y45590D01*
X186793Y45840D01*
X185293Y46340D01*
X184960Y46923D01*
X185127Y47340D01*
X185460Y47590D01*
X185960Y47673D01*
X186460Y47590D01*
X186960Y47340D01*
G01X191560Y47673D02*
Y44340D01*
G01Y49007D02*
X191393Y49090D01*
Y49257D01*
X191560Y49340D01*
X191727Y49257D01*
Y49090D01*
X191560Y49007D01*
G01X195910Y47673D02*
X198410D01*
X195910Y44340D01*
X198410D01*
G01X201510Y46590D02*
X204177D01*
X203927Y47173D01*
X203510Y47507D01*
X202927Y47673D01*
X202343Y47590D01*
X201843Y47340D01*
X201510Y46757D01*
X201343Y46257D01*
Y45757D01*
X201510Y45257D01*
X201927Y44757D01*
X202427Y44423D01*
X203010Y44340D01*
X203593Y44507D01*
X204177Y45007D01*
G01X213960Y44340D02*
X213460Y44423D01*
X212960Y44757D01*
X212627Y45340D01*
X212460Y46007D01*
X212627Y46673D01*
X212960Y47257D01*
X213460Y47590D01*
X213960Y47673D01*
X214460Y47590D01*
X214960Y47257D01*
X215293Y46673D01*
X215377Y46007D01*
X215293Y45340D01*
X214960Y44757D01*
X214460Y44423D01*
X213960Y44340D01*
G01X219060D02*
Y48590D01*
X219227Y49007D01*
X219560Y49257D01*
X220060Y49340D01*
X220560Y49173D01*
X220810Y48757D01*
G01X219810Y47340D02*
X218143D01*
G01X229093Y44340D02*
Y49340D01*
X231093D01*
X231760Y49090D01*
X232260Y48507D01*
X232427Y47840D01*
X232260Y47173D01*
X231843Y46673D01*
X231093Y46423D01*
X229093D01*
G01X234277Y44340D02*
X236360Y49340D01*
X238443Y44340D01*
G01X237693Y46090D02*
X235027D01*
G01X240127Y44340D02*
Y49340D01*
X241793D01*
X242460Y49090D01*
X242960Y48757D01*
X243377Y48257D01*
X243710Y47673D01*
X243793Y46840D01*
X243710Y46007D01*
X243377Y45423D01*
X242960Y44923D01*
X242460Y44590D01*
X241793Y44340D01*
X240127D01*
G01X251660Y44173D02*
X254660Y49340D01*
G01X112333Y51500D02*
Y56500D01*
X114333D01*
X115000Y56250D01*
X115500Y55667D01*
X115667Y55000D01*
X115500Y54333D01*
X115083Y53833D01*
X114333Y53583D01*
X112333D01*
G01X117517Y51500D02*
X119600Y56500D01*
X121683Y51500D01*
G01X120933Y53250D02*
X118267D01*
G01X123367Y51500D02*
Y56500D01*
X125033D01*
X125700Y56250D01*
X126200Y55917D01*
X126617Y55417D01*
X126950Y54833D01*
X127033Y54000D01*
X126950Y53167D01*
X126617Y52583D01*
X126200Y52083D01*
X125700Y51750D01*
X125033Y51500D01*
X123367D01*
G01X135150Y52083D02*
X135567Y51750D01*
X136150Y51500D01*
X136650D01*
X137150Y51667D01*
X137483Y51917D01*
X137650Y52250D01*
X137567Y52750D01*
X137233Y53000D01*
X135733Y53500D01*
X135400Y54083D01*
X135567Y54500D01*
X135900Y54750D01*
X136400Y54833D01*
X136900Y54750D01*
X137400Y54500D01*
G01X142000Y54833D02*
Y51500D01*
G01Y56167D02*
X141833Y56250D01*
Y56417D01*
X142000Y56500D01*
X142167Y56417D01*
Y56250D01*
X142000Y56167D01*
G01X146350Y54833D02*
X148850D01*
X146350Y51500D01*
X148850D01*
G01X151950Y53750D02*
X154617D01*
X154367Y54333D01*
X153950Y54667D01*
X153367Y54833D01*
X152783Y54750D01*
X152283Y54500D01*
X151950Y53917D01*
X151783Y53417D01*
Y52917D01*
X151950Y52417D01*
X152367Y51917D01*
X152867Y51583D01*
X153450Y51500D01*
X154033Y51667D01*
X154617Y52167D01*
G01X114000Y85000D02*
Y80000D01*
G01X112083Y85000D02*
X115917D01*
G01X118433Y80000D02*
Y83333D01*
G01Y82667D02*
X118850Y83000D01*
X119267Y83250D01*
X119850Y83333D01*
X120267Y83250D01*
X120767Y83000D01*
G01X126700Y80000D02*
Y83333D01*
G01Y82750D02*
X126367Y83083D01*
X125867Y83250D01*
X125283Y83333D01*
X124700Y83167D01*
X124200Y82833D01*
X123867Y82333D01*
X123700Y81667D01*
X123867Y81000D01*
X124200Y80500D01*
X124700Y80167D01*
X125283Y80000D01*
X125867Y80083D01*
X126367Y80333D01*
X126700Y80667D01*
G01X132133Y82917D02*
X131550Y83250D01*
X131050Y83333D01*
X130383Y83167D01*
X129883Y82833D01*
X129550Y82250D01*
X129467Y81667D01*
X129550Y81083D01*
X129883Y80583D01*
X130383Y80167D01*
X131050Y80000D01*
X131633Y80167D01*
X132133Y80500D01*
G01X135150Y82250D02*
X137817D01*
X137567Y82833D01*
X137150Y83167D01*
X136567Y83333D01*
X135983Y83250D01*
X135483Y83000D01*
X135150Y82417D01*
X134983Y81917D01*
Y81417D01*
X135150Y80917D01*
X135567Y80417D01*
X136067Y80083D01*
X136650Y80000D01*
X137233Y80167D01*
X137817Y80667D01*
G01X145517Y83333D02*
X146517Y80000D01*
X147600Y83333D01*
X148683Y80000D01*
X149683Y83333D01*
G01X153200D02*
Y80000D01*
G01Y84667D02*
X153033Y84750D01*
Y84917D01*
X153200Y85000D01*
X153367Y84917D01*
Y84750D01*
X153200Y84667D01*
G01X160300Y85000D02*
Y80000D01*
G01Y80750D02*
X159967Y80333D01*
X159467Y80083D01*
X158883Y80000D01*
X158217Y80167D01*
X157717Y80583D01*
X157383Y81083D01*
X157300Y81667D01*
X157383Y82250D01*
X157717Y82750D01*
X158217Y83167D01*
X158883Y83333D01*
X159467Y83250D01*
X159883Y83083D01*
X160300Y82750D01*
G01X164400Y85000D02*
Y80000D01*
G01X163233Y83333D02*
X165567D01*
G01X168583Y80000D02*
Y85000D01*
G01Y82583D02*
X169000Y83000D01*
X169417Y83250D01*
X170083Y83333D01*
X170583Y83250D01*
X171167Y82917D01*
X171417Y82417D01*
Y80000D01*
G01X112333Y111500D02*
Y116500D01*
X114417D01*
X115083Y116250D01*
X115500Y115917D01*
X115667Y115250D01*
X115500Y114583D01*
X115000Y114167D01*
X114417Y113917D01*
X112333D01*
G01X114417D02*
X115667Y111500D01*
G01X118350Y113750D02*
X121017D01*
X120767Y114333D01*
X120350Y114667D01*
X119767Y114833D01*
X119183Y114750D01*
X118683Y114500D01*
X118350Y113917D01*
X118183Y113417D01*
Y112917D01*
X118350Y112417D01*
X118767Y111917D01*
X119267Y111583D01*
X119850Y111500D01*
X120433Y111667D01*
X121017Y112167D01*
G01X125200Y111500D02*
Y116500D01*
G01X132300Y111500D02*
Y114833D01*
G01Y114250D02*
X131967Y114583D01*
X131467Y114750D01*
X130883Y114833D01*
X130300Y114667D01*
X129800Y114333D01*
X129467Y113833D01*
X129300Y113167D01*
X129467Y112500D01*
X129800Y112000D01*
X130300Y111667D01*
X130883Y111500D01*
X131467Y111583D01*
X131967Y111833D01*
X132300Y112167D01*
G01X136400Y116500D02*
Y111500D01*
G01X135233Y114833D02*
X137567D01*
G01X142000D02*
Y111500D01*
G01Y116167D02*
X141833Y116250D01*
Y116417D01*
X142000Y116500D01*
X142167Y116417D01*
Y116250D01*
X142000Y116167D01*
G01X146100Y114833D02*
X147600Y111500D01*
X149100Y114833D01*
G01X151950Y113750D02*
X154617D01*
X154367Y114333D01*
X153950Y114667D01*
X153367Y114833D01*
X152783Y114750D01*
X152283Y114500D01*
X151950Y113917D01*
X151783Y113417D01*
Y112917D01*
X151950Y112417D01*
X152367Y111917D01*
X152867Y111583D01*
X153450Y111500D01*
X154033Y111667D01*
X154617Y112167D01*
G01X162900Y109833D02*
Y114833D01*
G01Y114083D02*
X163317Y114500D01*
X163733Y114750D01*
X164400Y114833D01*
X164983Y114750D01*
X165567Y114333D01*
X165817Y113750D01*
X165900Y113167D01*
X165817Y112583D01*
X165567Y112000D01*
X165067Y111667D01*
X164400Y111500D01*
X163817Y111583D01*
X163233Y111833D01*
X162900Y112167D01*
G01X170000Y111500D02*
X169500Y111583D01*
X169000Y111917D01*
X168667Y112500D01*
X168500Y113167D01*
X168667Y113833D01*
X169000Y114417D01*
X169500Y114750D01*
X170000Y114833D01*
X170500Y114750D01*
X171000Y114417D01*
X171333Y113833D01*
X171417Y113167D01*
X171333Y112500D01*
X171000Y111917D01*
X170500Y111583D01*
X170000Y111500D01*
G01X174350Y112083D02*
X174767Y111750D01*
X175350Y111500D01*
X175850D01*
X176350Y111667D01*
X176683Y111917D01*
X176850Y112250D01*
X176767Y112750D01*
X176433Y113000D01*
X174933Y113500D01*
X174600Y114083D01*
X174767Y114500D01*
X175100Y114750D01*
X175600Y114833D01*
X176100Y114750D01*
X176600Y114500D01*
G01X181200Y114833D02*
Y111500D01*
G01Y116167D02*
X181033Y116250D01*
Y116417D01*
X181200Y116500D01*
X181367Y116417D01*
Y116250D01*
X181200Y116167D01*
G01X186800Y116500D02*
Y111500D01*
G01X185633Y114833D02*
X187967D01*
G01X192400D02*
Y111500D01*
G01Y116167D02*
X192233Y116250D01*
Y116417D01*
X192400Y116500D01*
X192567Y116417D01*
Y116250D01*
X192400Y116167D01*
G01X198000Y111500D02*
X197500Y111583D01*
X197000Y111917D01*
X196667Y112500D01*
X196500Y113167D01*
X196667Y113833D01*
X197000Y114417D01*
X197500Y114750D01*
X198000Y114833D01*
X198500Y114750D01*
X199000Y114417D01*
X199333Y113833D01*
X199417Y113167D01*
X199333Y112500D01*
X199000Y111917D01*
X198500Y111583D01*
X198000Y111500D01*
G01X202183D02*
Y114833D01*
G01Y114000D02*
X202517Y114417D01*
X203017Y114750D01*
X203683Y114833D01*
X204267Y114750D01*
X204767Y114417D01*
X205017Y113833D01*
Y111500D01*
G01X114000Y143500D02*
Y138500D01*
G01X112833Y141833D02*
X115167D01*
G01X118183Y138500D02*
Y143500D01*
G01Y141083D02*
X118600Y141500D01*
X119017Y141750D01*
X119683Y141833D01*
X120183Y141750D01*
X120767Y141417D01*
X121017Y140917D01*
Y138500D01*
G01X125200Y141833D02*
Y138500D01*
G01Y143167D02*
X125033Y143250D01*
Y143417D01*
X125200Y143500D01*
X125367Y143417D01*
Y143250D01*
X125200Y143167D01*
G01X132133Y141417D02*
X131550Y141750D01*
X131050Y141833D01*
X130383Y141667D01*
X129883Y141333D01*
X129550Y140750D01*
X129467Y140167D01*
X129550Y139583D01*
X129883Y139083D01*
X130383Y138667D01*
X131050Y138500D01*
X131633Y138667D01*
X132133Y139000D01*
G01X134983Y138500D02*
Y143500D01*
G01X137650Y141833D02*
X134983Y139917D01*
G01X136067Y140667D02*
X137817Y138500D01*
G01X140583D02*
Y141833D01*
G01Y141000D02*
X140917Y141417D01*
X141417Y141750D01*
X142083Y141833D01*
X142667Y141750D01*
X143167Y141417D01*
X143417Y140833D01*
Y138500D01*
G01X146350Y140750D02*
X149017D01*
X148767Y141333D01*
X148350Y141667D01*
X147767Y141833D01*
X147183Y141750D01*
X146683Y141500D01*
X146350Y140917D01*
X146183Y140417D01*
Y139917D01*
X146350Y139417D01*
X146767Y138917D01*
X147267Y138583D01*
X147850Y138500D01*
X148433Y138667D01*
X149017Y139167D01*
G01X151950Y139083D02*
X152367Y138750D01*
X152950Y138500D01*
X153450D01*
X153950Y138667D01*
X154283Y138917D01*
X154450Y139250D01*
X154367Y139750D01*
X154033Y140000D01*
X152533Y140500D01*
X152200Y141083D01*
X152367Y141500D01*
X152700Y141750D01*
X153200Y141833D01*
X153700Y141750D01*
X154200Y141500D01*
G01X157550Y139083D02*
X157967Y138750D01*
X158550Y138500D01*
X159050D01*
X159550Y138667D01*
X159883Y138917D01*
X160050Y139250D01*
X159967Y139750D01*
X159633Y140000D01*
X158133Y140500D01*
X157800Y141083D01*
X157967Y141500D01*
X158300Y141750D01*
X158800Y141833D01*
X159300Y141750D01*
X159800Y141500D01*
G01X171500Y138500D02*
Y141833D01*
G01Y141250D02*
X171167Y141583D01*
X170667Y141750D01*
X170083Y141833D01*
X169500Y141667D01*
X169000Y141333D01*
X168667Y140833D01*
X168500Y140167D01*
X168667Y139500D01*
X169000Y139000D01*
X169500Y138667D01*
X170083Y138500D01*
X170667Y138583D01*
X171167Y138833D01*
X171500Y139167D01*
G01X175100Y138500D02*
Y142750D01*
X175267Y143167D01*
X175600Y143417D01*
X176100Y143500D01*
X176600Y143333D01*
X176850Y142917D01*
G01X175850Y141500D02*
X174183D01*
G01X181200Y143500D02*
Y138500D01*
G01X180033Y141833D02*
X182367D01*
G01X185550Y140750D02*
X188217D01*
X187967Y141333D01*
X187550Y141667D01*
X186967Y141833D01*
X186383Y141750D01*
X185883Y141500D01*
X185550Y140917D01*
X185383Y140417D01*
Y139917D01*
X185550Y139417D01*
X185967Y138917D01*
X186467Y138583D01*
X187050Y138500D01*
X187633Y138667D01*
X188217Y139167D01*
G01X191233Y138500D02*
Y141833D01*
G01Y141167D02*
X191650Y141500D01*
X192067Y141750D01*
X192650Y141833D01*
X193067Y141750D01*
X193567Y141500D01*
G01X202100Y136833D02*
Y141833D01*
G01Y141083D02*
X202517Y141500D01*
X202933Y141750D01*
X203600Y141833D01*
X204183Y141750D01*
X204767Y141333D01*
X205017Y140750D01*
X205100Y140167D01*
X205017Y139583D01*
X204767Y139000D01*
X204267Y138667D01*
X203600Y138500D01*
X203017Y138583D01*
X202433Y138833D01*
X202100Y139167D01*
G01X209200Y138500D02*
Y143500D01*
G01X216300Y138500D02*
Y141833D01*
G01Y141250D02*
X215967Y141583D01*
X215467Y141750D01*
X214883Y141833D01*
X214300Y141667D01*
X213800Y141333D01*
X213467Y140833D01*
X213300Y140167D01*
X213467Y139500D01*
X213800Y139000D01*
X214300Y138667D01*
X214883Y138500D01*
X215467Y138583D01*
X215967Y138833D01*
X216300Y139167D01*
G01X220400Y143500D02*
Y138500D01*
G01X219233Y141833D02*
X221567D01*
G01X226000D02*
Y138500D01*
G01Y143167D02*
X225833Y143250D01*
Y143417D01*
X226000Y143500D01*
X226167Y143417D01*
Y143250D01*
X226000Y143167D01*
G01X230183Y138500D02*
Y141833D01*
G01Y141000D02*
X230517Y141417D01*
X231017Y141750D01*
X231683Y141833D01*
X232267Y141750D01*
X232767Y141417D01*
X233017Y140833D01*
Y138500D01*
G01X236033Y137250D02*
X236617Y136917D01*
X237283Y136833D01*
X237867Y136917D01*
X238367Y137333D01*
X238700Y137917D01*
Y141833D01*
G01Y141167D02*
X238367Y141500D01*
X237867Y141750D01*
X237283Y141833D01*
X236617Y141667D01*
X236200Y141333D01*
X235867Y140750D01*
X235700Y140167D01*
X235783Y139667D01*
X236117Y139083D01*
X236617Y138667D01*
X237283Y138500D01*
X237783Y138583D01*
X238367Y138917D01*
X238700Y139250D01*
G01X115667Y148500D02*
X112333D01*
Y153500D01*
X115667D01*
G01X114333Y151083D02*
X112333D01*
G01X118350Y151833D02*
X120850Y148500D01*
G01Y151833D02*
X118350Y148500D01*
G01X125200Y153500D02*
Y148500D01*
G01X124033Y151833D02*
X126367D01*
G01X129550Y150750D02*
X132217D01*
X131967Y151333D01*
X131550Y151667D01*
X130967Y151833D01*
X130383Y151750D01*
X129883Y151500D01*
X129550Y150917D01*
X129383Y150417D01*
Y149917D01*
X129550Y149417D01*
X129967Y148917D01*
X130467Y148583D01*
X131050Y148500D01*
X131633Y148667D01*
X132217Y149167D01*
G01X135233Y148500D02*
Y151833D01*
G01Y151167D02*
X135650Y151500D01*
X136067Y151750D01*
X136650Y151833D01*
X137067Y151750D01*
X137567Y151500D01*
G01X140583Y148500D02*
Y151833D01*
G01Y151000D02*
X140917Y151417D01*
X141417Y151750D01*
X142083Y151833D01*
X142667Y151750D01*
X143167Y151417D01*
X143417Y150833D01*
Y148500D01*
G01X149100D02*
Y151833D01*
G01Y151250D02*
X148767Y151583D01*
X148267Y151750D01*
X147683Y151833D01*
X147100Y151667D01*
X146600Y151333D01*
X146267Y150833D01*
X146100Y150167D01*
X146267Y149500D01*
X146600Y149000D01*
X147100Y148667D01*
X147683Y148500D01*
X148267Y148583D01*
X148767Y148833D01*
X149100Y149167D01*
G01X153200Y148500D02*
Y153500D01*
G01X165733Y151417D02*
X165150Y151750D01*
X164650Y151833D01*
X163983Y151667D01*
X163483Y151333D01*
X163150Y150750D01*
X163067Y150167D01*
X163150Y149583D01*
X163483Y149083D01*
X163983Y148667D01*
X164650Y148500D01*
X165233Y148667D01*
X165733Y149000D01*
G01X170000Y148500D02*
X169500Y148583D01*
X169000Y148917D01*
X168667Y149500D01*
X168500Y150167D01*
X168667Y150833D01*
X169000Y151417D01*
X169500Y151750D01*
X170000Y151833D01*
X170500Y151750D01*
X171000Y151417D01*
X171333Y150833D01*
X171417Y150167D01*
X171333Y149500D01*
X171000Y148917D01*
X170500Y148583D01*
X170000Y148500D01*
G01X174183D02*
Y151833D01*
G01Y151000D02*
X174517Y151417D01*
X175017Y151750D01*
X175683Y151833D01*
X176267Y151750D01*
X176767Y151417D01*
X177017Y150833D01*
Y148500D01*
G01X182700Y153500D02*
Y148500D01*
G01Y149250D02*
X182367Y148833D01*
X181867Y148583D01*
X181283Y148500D01*
X180617Y148667D01*
X180117Y149083D01*
X179783Y149583D01*
X179700Y150167D01*
X179783Y150750D01*
X180117Y151250D01*
X180617Y151667D01*
X181283Y151833D01*
X181867Y151750D01*
X182283Y151583D01*
X182700Y151250D01*
G01X185383Y151833D02*
Y149500D01*
X185717Y148917D01*
X186217Y148583D01*
X186800Y148500D01*
X187383Y148583D01*
X187883Y148917D01*
X188217Y149500D01*
G01Y148500D02*
Y151833D01*
G01X193733Y151417D02*
X193150Y151750D01*
X192650Y151833D01*
X191983Y151667D01*
X191483Y151333D01*
X191150Y150750D01*
X191067Y150167D01*
X191150Y149583D01*
X191483Y149083D01*
X191983Y148667D01*
X192650Y148500D01*
X193233Y148667D01*
X193733Y149000D01*
G01X198000Y153500D02*
Y148500D01*
G01X196833Y151833D02*
X199167D01*
G01X203600Y148500D02*
X203100Y148583D01*
X202600Y148917D01*
X202267Y149500D01*
X202100Y150167D01*
X202267Y150833D01*
X202600Y151417D01*
X203100Y151750D01*
X203600Y151833D01*
X204100Y151750D01*
X204600Y151417D01*
X204933Y150833D01*
X205017Y150167D01*
X204933Y149500D01*
X204600Y148917D01*
X204100Y148583D01*
X203600Y148500D01*
G01X208033D02*
Y151833D01*
G01Y151167D02*
X208450Y151500D01*
X208867Y151750D01*
X209450Y151833D01*
X209867Y151750D01*
X210367Y151500D01*
G01X112333Y111500D02*
Y116500D01*
X114417D01*
X115083Y116250D01*
X115500Y115917D01*
X115667Y115250D01*
X115500Y114583D01*
X115000Y114167D01*
X114417Y113917D01*
X112333D01*
G01X114417D02*
X115667Y111500D01*
G01X118350Y113750D02*
X121017D01*
X120767Y114333D01*
X120350Y114667D01*
X119767Y114833D01*
X119183Y114750D01*
X118683Y114500D01*
X118350Y113917D01*
X118183Y113417D01*
Y112917D01*
X118350Y112417D01*
X118767Y111917D01*
X119267Y111583D01*
X119850Y111500D01*
X120433Y111667D01*
X121017Y112167D01*
G01X125200Y111500D02*
Y116500D01*
G01X132300Y111500D02*
Y114833D01*
G01Y114250D02*
X131967Y114583D01*
X131467Y114750D01*
X130883Y114833D01*
X130300Y114667D01*
X129800Y114333D01*
X129467Y113833D01*
X129300Y113167D01*
X129467Y112500D01*
X129800Y112000D01*
X130300Y111667D01*
X130883Y111500D01*
X131467Y111583D01*
X131967Y111833D01*
X132300Y112167D01*
G01X136400Y116500D02*
Y111500D01*
G01X135233Y114833D02*
X137567D01*
G01X142000D02*
Y111500D01*
G01Y116167D02*
X141833Y116250D01*
Y116417D01*
X142000Y116500D01*
X142167Y116417D01*
Y116250D01*
X142000Y116167D01*
G01X146100Y114833D02*
X147600Y111500D01*
X149100Y114833D01*
G01X151950Y113750D02*
X154617D01*
X154367Y114333D01*
X153950Y114667D01*
X153367Y114833D01*
X152783Y114750D01*
X152283Y114500D01*
X151950Y113917D01*
X151783Y113417D01*
Y112917D01*
X151950Y112417D01*
X152367Y111917D01*
X152867Y111583D01*
X153450Y111500D01*
X154033Y111667D01*
X154617Y112167D01*
G01X162900Y109833D02*
Y114833D01*
G01Y114083D02*
X163317Y114500D01*
X163733Y114750D01*
X164400Y114833D01*
X164983Y114750D01*
X165567Y114333D01*
X165817Y113750D01*
X165900Y113167D01*
X165817Y112583D01*
X165567Y112000D01*
X165067Y111667D01*
X164400Y111500D01*
X163817Y111583D01*
X163233Y111833D01*
X162900Y112167D01*
G01X170000Y111500D02*
X169500Y111583D01*
X169000Y111917D01*
X168667Y112500D01*
X168500Y113167D01*
X168667Y113833D01*
X169000Y114417D01*
X169500Y114750D01*
X170000Y114833D01*
X170500Y114750D01*
X171000Y114417D01*
X171333Y113833D01*
X171417Y113167D01*
X171333Y112500D01*
X171000Y111917D01*
X170500Y111583D01*
X170000Y111500D01*
G01X174350Y112083D02*
X174767Y111750D01*
X175350Y111500D01*
X175850D01*
X176350Y111667D01*
X176683Y111917D01*
X176850Y112250D01*
X176767Y112750D01*
X176433Y113000D01*
X174933Y113500D01*
X174600Y114083D01*
X174767Y114500D01*
X175100Y114750D01*
X175600Y114833D01*
X176100Y114750D01*
X176600Y114500D01*
G01X181200Y114833D02*
Y111500D01*
G01Y116167D02*
X181033Y116250D01*
Y116417D01*
X181200Y116500D01*
X181367Y116417D01*
Y116250D01*
X181200Y116167D01*
G01X186800Y116500D02*
Y111500D01*
G01X185633Y114833D02*
X187967D01*
G01X192400D02*
Y111500D01*
G01Y116167D02*
X192233Y116250D01*
Y116417D01*
X192400Y116500D01*
X192567Y116417D01*
Y116250D01*
X192400Y116167D01*
G01X198000Y111500D02*
X197500Y111583D01*
X197000Y111917D01*
X196667Y112500D01*
X196500Y113167D01*
X196667Y113833D01*
X197000Y114417D01*
X197500Y114750D01*
X198000Y114833D01*
X198500Y114750D01*
X199000Y114417D01*
X199333Y113833D01*
X199417Y113167D01*
X199333Y112500D01*
X199000Y111917D01*
X198500Y111583D01*
X198000Y111500D01*
G01X202183D02*
Y114833D01*
G01Y114000D02*
X202517Y114417D01*
X203017Y114750D01*
X203683Y114833D01*
X204267Y114750D01*
X204767Y114417D01*
X205017Y113833D01*
Y111500D01*
G01X114000Y143500D02*
Y138500D01*
G01X112833Y141833D02*
X115167D01*
G01X118183Y138500D02*
Y143500D01*
G01Y141083D02*
X118600Y141500D01*
X119017Y141750D01*
X119683Y141833D01*
X120183Y141750D01*
X120767Y141417D01*
X121017Y140917D01*
Y138500D01*
G01X125200Y141833D02*
Y138500D01*
G01Y143167D02*
X125033Y143250D01*
Y143417D01*
X125200Y143500D01*
X125367Y143417D01*
Y143250D01*
X125200Y143167D01*
G01X132133Y141417D02*
X131550Y141750D01*
X131050Y141833D01*
X130383Y141667D01*
X129883Y141333D01*
X129550Y140750D01*
X129467Y140167D01*
X129550Y139583D01*
X129883Y139083D01*
X130383Y138667D01*
X131050Y138500D01*
X131633Y138667D01*
X132133Y139000D01*
G01X134983Y138500D02*
Y143500D01*
G01X137650Y141833D02*
X134983Y139917D01*
G01X136067Y140667D02*
X137817Y138500D01*
G01X140583D02*
Y141833D01*
G01Y141000D02*
X140917Y141417D01*
X141417Y141750D01*
X142083Y141833D01*
X142667Y141750D01*
X143167Y141417D01*
X143417Y140833D01*
Y138500D01*
G01X146350Y140750D02*
X149017D01*
X148767Y141333D01*
X148350Y141667D01*
X147767Y141833D01*
X147183Y141750D01*
X146683Y141500D01*
X146350Y140917D01*
X146183Y140417D01*
Y139917D01*
X146350Y139417D01*
X146767Y138917D01*
X147267Y138583D01*
X147850Y138500D01*
X148433Y138667D01*
X149017Y139167D01*
G01X151950Y139083D02*
X152367Y138750D01*
X152950Y138500D01*
X153450D01*
X153950Y138667D01*
X154283Y138917D01*
X154450Y139250D01*
X154367Y139750D01*
X154033Y140000D01*
X152533Y140500D01*
X152200Y141083D01*
X152367Y141500D01*
X152700Y141750D01*
X153200Y141833D01*
X153700Y141750D01*
X154200Y141500D01*
G01X157550Y139083D02*
X157967Y138750D01*
X158550Y138500D01*
X159050D01*
X159550Y138667D01*
X159883Y138917D01*
X160050Y139250D01*
X159967Y139750D01*
X159633Y140000D01*
X158133Y140500D01*
X157800Y141083D01*
X157967Y141500D01*
X158300Y141750D01*
X158800Y141833D01*
X159300Y141750D01*
X159800Y141500D01*
G01X171500Y138500D02*
Y141833D01*
G01Y141250D02*
X171167Y141583D01*
X170667Y141750D01*
X170083Y141833D01*
X169500Y141667D01*
X169000Y141333D01*
X168667Y140833D01*
X168500Y140167D01*
X168667Y139500D01*
X169000Y139000D01*
X169500Y138667D01*
X170083Y138500D01*
X170667Y138583D01*
X171167Y138833D01*
X171500Y139167D01*
G01X175100Y138500D02*
Y142750D01*
X175267Y143167D01*
X175600Y143417D01*
X176100Y143500D01*
X176600Y143333D01*
X176850Y142917D01*
G01X175850Y141500D02*
X174183D01*
G01X181200Y143500D02*
Y138500D01*
G01X180033Y141833D02*
X182367D01*
G01X185550Y140750D02*
X188217D01*
X187967Y141333D01*
X187550Y141667D01*
X186967Y141833D01*
X186383Y141750D01*
X185883Y141500D01*
X185550Y140917D01*
X185383Y140417D01*
Y139917D01*
X185550Y139417D01*
X185967Y138917D01*
X186467Y138583D01*
X187050Y138500D01*
X187633Y138667D01*
X188217Y139167D01*
G01X191233Y138500D02*
Y141833D01*
G01Y141167D02*
X191650Y141500D01*
X192067Y141750D01*
X192650Y141833D01*
X193067Y141750D01*
X193567Y141500D01*
G01X202100Y136833D02*
Y141833D01*
G01Y141083D02*
X202517Y141500D01*
X202933Y141750D01*
X203600Y141833D01*
X204183Y141750D01*
X204767Y141333D01*
X205017Y140750D01*
X205100Y140167D01*
X205017Y139583D01*
X204767Y139000D01*
X204267Y138667D01*
X203600Y138500D01*
X203017Y138583D01*
X202433Y138833D01*
X202100Y139167D01*
G01X209200Y138500D02*
Y143500D01*
G01X216300Y138500D02*
Y141833D01*
G01Y141250D02*
X215967Y141583D01*
X215467Y141750D01*
X214883Y141833D01*
X214300Y141667D01*
X213800Y141333D01*
X213467Y140833D01*
X213300Y140167D01*
X213467Y139500D01*
X213800Y139000D01*
X214300Y138667D01*
X214883Y138500D01*
X215467Y138583D01*
X215967Y138833D01*
X216300Y139167D01*
G01X220400Y143500D02*
Y138500D01*
G01X219233Y141833D02*
X221567D01*
G01X226000D02*
Y138500D01*
G01Y143167D02*
X225833Y143250D01*
Y143417D01*
X226000Y143500D01*
X226167Y143417D01*
Y143250D01*
X226000Y143167D01*
G01X230183Y138500D02*
Y141833D01*
G01Y141000D02*
X230517Y141417D01*
X231017Y141750D01*
X231683Y141833D01*
X232267Y141750D01*
X232767Y141417D01*
X233017Y140833D01*
Y138500D01*
G01X236033Y137250D02*
X236617Y136917D01*
X237283Y136833D01*
X237867Y136917D01*
X238367Y137333D01*
X238700Y137917D01*
Y141833D01*
G01Y141167D02*
X238367Y141500D01*
X237867Y141750D01*
X237283Y141833D01*
X236617Y141667D01*
X236200Y141333D01*
X235867Y140750D01*
X235700Y140167D01*
X235783Y139667D01*
X236117Y139083D01*
X236617Y138667D01*
X237283Y138500D01*
X237783Y138583D01*
X238367Y138917D01*
X238700Y139250D01*
G01X115667Y148500D02*
X112333D01*
Y153500D01*
X115667D01*
G01X114333Y151083D02*
X112333D01*
G01X118350Y151833D02*
X120850Y148500D01*
G01Y151833D02*
X118350Y148500D01*
G01X125200Y153500D02*
Y148500D01*
G01X124033Y151833D02*
X126367D01*
G01X129550Y150750D02*
X132217D01*
X131967Y151333D01*
X131550Y151667D01*
X130967Y151833D01*
X130383Y151750D01*
X129883Y151500D01*
X129550Y150917D01*
X129383Y150417D01*
Y149917D01*
X129550Y149417D01*
X129967Y148917D01*
X130467Y148583D01*
X131050Y148500D01*
X131633Y148667D01*
X132217Y149167D01*
G01X135233Y148500D02*
Y151833D01*
G01Y151167D02*
X135650Y151500D01*
X136067Y151750D01*
X136650Y151833D01*
X137067Y151750D01*
X137567Y151500D01*
G01X140583Y148500D02*
Y151833D01*
G01Y151000D02*
X140917Y151417D01*
X141417Y151750D01*
X142083Y151833D01*
X142667Y151750D01*
X143167Y151417D01*
X143417Y150833D01*
Y148500D01*
G01X149100D02*
Y151833D01*
G01Y151250D02*
X148767Y151583D01*
X148267Y151750D01*
X147683Y151833D01*
X147100Y151667D01*
X146600Y151333D01*
X146267Y150833D01*
X146100Y150167D01*
X146267Y149500D01*
X146600Y149000D01*
X147100Y148667D01*
X147683Y148500D01*
X148267Y148583D01*
X148767Y148833D01*
X149100Y149167D01*
G01X153200Y148500D02*
Y153500D01*
G01X165733Y151417D02*
X165150Y151750D01*
X164650Y151833D01*
X163983Y151667D01*
X163483Y151333D01*
X163150Y150750D01*
X163067Y150167D01*
X163150Y149583D01*
X163483Y149083D01*
X163983Y148667D01*
X164650Y148500D01*
X165233Y148667D01*
X165733Y149000D01*
G01X170000Y148500D02*
X169500Y148583D01*
X169000Y148917D01*
X168667Y149500D01*
X168500Y150167D01*
X168667Y150833D01*
X169000Y151417D01*
X169500Y151750D01*
X170000Y151833D01*
X170500Y151750D01*
X171000Y151417D01*
X171333Y150833D01*
X171417Y150167D01*
X171333Y149500D01*
X171000Y148917D01*
X170500Y148583D01*
X170000Y148500D01*
G01X174183D02*
Y151833D01*
G01Y151000D02*
X174517Y151417D01*
X175017Y151750D01*
X175683Y151833D01*
X176267Y151750D01*
X176767Y151417D01*
X177017Y150833D01*
Y148500D01*
G01X182700Y153500D02*
Y148500D01*
G01Y149250D02*
X182367Y148833D01*
X181867Y148583D01*
X181283Y148500D01*
X180617Y148667D01*
X180117Y149083D01*
X179783Y149583D01*
X179700Y150167D01*
X179783Y150750D01*
X180117Y151250D01*
X180617Y151667D01*
X181283Y151833D01*
X181867Y151750D01*
X182283Y151583D01*
X182700Y151250D01*
G01X185383Y151833D02*
Y149500D01*
X185717Y148917D01*
X186217Y148583D01*
X186800Y148500D01*
X187383Y148583D01*
X187883Y148917D01*
X188217Y149500D01*
G01Y148500D02*
Y151833D01*
G01X193733Y151417D02*
X193150Y151750D01*
X192650Y151833D01*
X191983Y151667D01*
X191483Y151333D01*
X191150Y150750D01*
X191067Y150167D01*
X191150Y149583D01*
X191483Y149083D01*
X191983Y148667D01*
X192650Y148500D01*
X193233Y148667D01*
X193733Y149000D01*
G01X198000Y153500D02*
Y148500D01*
G01X196833Y151833D02*
X199167D01*
G01X203600Y148500D02*
X203100Y148583D01*
X202600Y148917D01*
X202267Y149500D01*
X202100Y150167D01*
X202267Y150833D01*
X202600Y151417D01*
X203100Y151750D01*
X203600Y151833D01*
X204100Y151750D01*
X204600Y151417D01*
X204933Y150833D01*
X205017Y150167D01*
X204933Y149500D01*
X204600Y148917D01*
X204100Y148583D01*
X203600Y148500D01*
G01X208033D02*
Y151833D01*
G01Y151167D02*
X208450Y151500D01*
X208867Y151750D01*
X209450Y151833D01*
X209867Y151750D01*
X210367Y151500D01*
G01X112333Y356500D02*
Y351500D01*
X115667D01*
G01X121100D02*
Y354833D01*
G01Y354250D02*
X120767Y354583D01*
X120267Y354750D01*
X119683Y354833D01*
X119100Y354667D01*
X118600Y354333D01*
X118267Y353833D01*
X118100Y353167D01*
X118267Y352500D01*
X118600Y352000D01*
X119100Y351667D01*
X119683Y351500D01*
X120267Y351583D01*
X120767Y351833D01*
X121100Y352167D01*
G01X123950Y352083D02*
X124367Y351750D01*
X124950Y351500D01*
X125450D01*
X125950Y351667D01*
X126283Y351917D01*
X126450Y352250D01*
X126367Y352750D01*
X126033Y353000D01*
X124533Y353500D01*
X124200Y354083D01*
X124367Y354500D01*
X124700Y354750D01*
X125200Y354833D01*
X125700Y354750D01*
X126200Y354500D01*
G01X129550Y353750D02*
X132217D01*
X131967Y354333D01*
X131550Y354667D01*
X130967Y354833D01*
X130383Y354750D01*
X129883Y354500D01*
X129550Y353917D01*
X129383Y353417D01*
Y352917D01*
X129550Y352417D01*
X129967Y351917D01*
X130467Y351583D01*
X131050Y351500D01*
X131633Y351667D01*
X132217Y352167D01*
G01X135233Y351500D02*
Y354833D01*
G01Y354167D02*
X135650Y354500D01*
X136067Y354750D01*
X136650Y354833D01*
X137067Y354750D01*
X137567Y354500D01*
G01X146100Y354833D02*
X147600Y351500D01*
X149100Y354833D01*
G01X153200D02*
Y351500D01*
G01Y356167D02*
X153033Y356250D01*
Y356417D01*
X153200Y356500D01*
X153367Y356417D01*
Y356250D01*
X153200Y356167D01*
G01X160300Y351500D02*
Y354833D01*
G01Y354250D02*
X159967Y354583D01*
X159467Y354750D01*
X158883Y354833D01*
X158300Y354667D01*
X157800Y354333D01*
X157467Y353833D01*
X157300Y353167D01*
X157467Y352500D01*
X157800Y352000D01*
X158300Y351667D01*
X158883Y351500D01*
X159467Y351583D01*
X159967Y351833D01*
X160300Y352167D01*
G01X168167Y351333D02*
X171833Y355000D01*
G01X170000Y355667D02*
Y350667D01*
G01X171833Y351333D02*
X168167Y355000D01*
G01X167500Y353167D02*
X172500D01*
G01X175183Y349833D02*
X174350Y350667D01*
X173933Y351500D01*
Y354833D01*
X174350Y355667D01*
X175183Y356500D01*
G01X179367Y352250D02*
X179867Y351833D01*
X180450Y351583D01*
X181200Y351500D01*
X181950Y351667D01*
X182533Y352000D01*
X182950Y352583D01*
X183033Y353250D01*
X182867Y353917D01*
X182450Y354333D01*
X181867Y354667D01*
X181283Y354750D01*
X180700Y354667D01*
X179950Y354333D01*
X180200Y356500D01*
X182450D01*
G01X186800Y351333D02*
X186633Y351417D01*
Y351583D01*
X186800Y351667D01*
X186967Y351583D01*
Y351417D01*
X186800Y351333D01*
G01X192400Y351500D02*
Y356500D01*
X191400Y355500D01*
G01Y351500D02*
X193400D01*
G01X198417Y349833D02*
X199250Y350667D01*
X199667Y351500D01*
Y354833D01*
X199250Y355667D01*
X198417Y356500D01*
G01X112333Y406500D02*
Y411500D01*
X114333D01*
X115000Y411250D01*
X115500Y410667D01*
X115667Y410000D01*
X115500Y409333D01*
X115083Y408833D01*
X114333Y408583D01*
X112333D01*
G01X119600Y411500D02*
Y406500D01*
G01X117683Y411500D02*
X121517D01*
G01X123450Y406500D02*
Y411500D01*
G01X126950D02*
Y406500D01*
G01Y409000D02*
X123450D01*
G01X135233Y406500D02*
Y409833D01*
G01Y409167D02*
X135650Y409500D01*
X136067Y409750D01*
X136650Y409833D01*
X137067Y409750D01*
X137567Y409500D01*
G01X140750Y408750D02*
X143417D01*
X143167Y409333D01*
X142750Y409667D01*
X142167Y409833D01*
X141583Y409750D01*
X141083Y409500D01*
X140750Y408917D01*
X140583Y408417D01*
Y407917D01*
X140750Y407417D01*
X141167Y406917D01*
X141667Y406583D01*
X142250Y406500D01*
X142833Y406667D01*
X143417Y407167D01*
G01X146433Y405250D02*
X147017Y404917D01*
X147683Y404833D01*
X148267Y404917D01*
X148767Y405333D01*
X149100Y405917D01*
Y409833D01*
G01Y409167D02*
X148767Y409500D01*
X148267Y409750D01*
X147683Y409833D01*
X147017Y409667D01*
X146600Y409333D01*
X146267Y408750D01*
X146100Y408167D01*
X146183Y407667D01*
X146517Y407083D01*
X147017Y406667D01*
X147683Y406500D01*
X148183Y406583D01*
X148767Y406917D01*
X149100Y407250D01*
G01X153200Y409833D02*
Y406500D01*
G01Y411167D02*
X153033Y411250D01*
Y411417D01*
X153200Y411500D01*
X153367Y411417D01*
Y411250D01*
X153200Y411167D01*
G01X157550Y407083D02*
X157967Y406750D01*
X158550Y406500D01*
X159050D01*
X159550Y406667D01*
X159883Y406917D01*
X160050Y407250D01*
X159967Y407750D01*
X159633Y408000D01*
X158133Y408500D01*
X157800Y409083D01*
X157967Y409500D01*
X158300Y409750D01*
X158800Y409833D01*
X159300Y409750D01*
X159800Y409500D01*
G01X164400Y411500D02*
Y406500D01*
G01X163233Y409833D02*
X165567D01*
G01X168833Y406500D02*
Y409833D01*
G01Y409167D02*
X169250Y409500D01*
X169667Y409750D01*
X170250Y409833D01*
X170667Y409750D01*
X171167Y409500D01*
G01X177100Y406500D02*
Y409833D01*
G01Y409250D02*
X176767Y409583D01*
X176267Y409750D01*
X175683Y409833D01*
X175100Y409667D01*
X174600Y409333D01*
X174267Y408833D01*
X174100Y408167D01*
X174267Y407500D01*
X174600Y407000D01*
X175100Y406667D01*
X175683Y406500D01*
X176267Y406583D01*
X176767Y406833D01*
X177100Y407167D01*
G01X181200Y411500D02*
Y406500D01*
G01X180033Y409833D02*
X182367D01*
G01X186800D02*
Y406500D01*
G01Y411167D02*
X186633Y411250D01*
Y411417D01*
X186800Y411500D01*
X186967Y411417D01*
Y411250D01*
X186800Y411167D01*
G01X192400Y406500D02*
X191900Y406583D01*
X191400Y406917D01*
X191067Y407500D01*
X190900Y408167D01*
X191067Y408833D01*
X191400Y409417D01*
X191900Y409750D01*
X192400Y409833D01*
X192900Y409750D01*
X193400Y409417D01*
X193733Y408833D01*
X193817Y408167D01*
X193733Y407500D01*
X193400Y406917D01*
X192900Y406583D01*
X192400Y406500D01*
G01X196583D02*
Y409833D01*
G01Y409000D02*
X196917Y409417D01*
X197417Y409750D01*
X198083Y409833D01*
X198667Y409750D01*
X199167Y409417D01*
X199417Y408833D01*
Y406500D01*
G01X112333Y356500D02*
Y351500D01*
X115667D01*
G01X121100D02*
Y354833D01*
G01Y354250D02*
X120767Y354583D01*
X120267Y354750D01*
X119683Y354833D01*
X119100Y354667D01*
X118600Y354333D01*
X118267Y353833D01*
X118100Y353167D01*
X118267Y352500D01*
X118600Y352000D01*
X119100Y351667D01*
X119683Y351500D01*
X120267Y351583D01*
X120767Y351833D01*
X121100Y352167D01*
G01X123950Y352083D02*
X124367Y351750D01*
X124950Y351500D01*
X125450D01*
X125950Y351667D01*
X126283Y351917D01*
X126450Y352250D01*
X126367Y352750D01*
X126033Y353000D01*
X124533Y353500D01*
X124200Y354083D01*
X124367Y354500D01*
X124700Y354750D01*
X125200Y354833D01*
X125700Y354750D01*
X126200Y354500D01*
G01X129550Y353750D02*
X132217D01*
X131967Y354333D01*
X131550Y354667D01*
X130967Y354833D01*
X130383Y354750D01*
X129883Y354500D01*
X129550Y353917D01*
X129383Y353417D01*
Y352917D01*
X129550Y352417D01*
X129967Y351917D01*
X130467Y351583D01*
X131050Y351500D01*
X131633Y351667D01*
X132217Y352167D01*
G01X135233Y351500D02*
Y354833D01*
G01Y354167D02*
X135650Y354500D01*
X136067Y354750D01*
X136650Y354833D01*
X137067Y354750D01*
X137567Y354500D01*
G01X146100Y354833D02*
X147600Y351500D01*
X149100Y354833D01*
G01X153200D02*
Y351500D01*
G01Y356167D02*
X153033Y356250D01*
Y356417D01*
X153200Y356500D01*
X153367Y356417D01*
Y356250D01*
X153200Y356167D01*
G01X160300Y351500D02*
Y354833D01*
G01Y354250D02*
X159967Y354583D01*
X159467Y354750D01*
X158883Y354833D01*
X158300Y354667D01*
X157800Y354333D01*
X157467Y353833D01*
X157300Y353167D01*
X157467Y352500D01*
X157800Y352000D01*
X158300Y351667D01*
X158883Y351500D01*
X159467Y351583D01*
X159967Y351833D01*
X160300Y352167D01*
G01X168167Y351333D02*
X171833Y355000D01*
G01X170000Y355667D02*
Y350667D01*
G01X171833Y351333D02*
X168167Y355000D01*
G01X167500Y353167D02*
X172500D01*
G01X175183Y349833D02*
X174350Y350667D01*
X173933Y351500D01*
Y354833D01*
X174350Y355667D01*
X175183Y356500D01*
G01X179367Y352250D02*
X179867Y351833D01*
X180450Y351583D01*
X181200Y351500D01*
X181950Y351667D01*
X182533Y352000D01*
X182950Y352583D01*
X183033Y353250D01*
X182867Y353917D01*
X182450Y354333D01*
X181867Y354667D01*
X181283Y354750D01*
X180700Y354667D01*
X179950Y354333D01*
X180200Y356500D01*
X182450D01*
G01X186800Y351333D02*
X186633Y351417D01*
Y351583D01*
X186800Y351667D01*
X186967Y351583D01*
Y351417D01*
X186800Y351333D01*
G01X192400Y351500D02*
Y356500D01*
X191400Y355500D01*
G01Y351500D02*
X193400D01*
G01X198417Y349833D02*
X199250Y350667D01*
X199667Y351500D01*
Y354833D01*
X199250Y355667D01*
X198417Y356500D01*
G01X112333Y406500D02*
Y411500D01*
X114333D01*
X115000Y411250D01*
X115500Y410667D01*
X115667Y410000D01*
X115500Y409333D01*
X115083Y408833D01*
X114333Y408583D01*
X112333D01*
G01X119600Y411500D02*
Y406500D01*
G01X117683Y411500D02*
X121517D01*
G01X123450Y406500D02*
Y411500D01*
G01X126950D02*
Y406500D01*
G01Y409000D02*
X123450D01*
G01X135233Y406500D02*
Y409833D01*
G01Y409167D02*
X135650Y409500D01*
X136067Y409750D01*
X136650Y409833D01*
X137067Y409750D01*
X137567Y409500D01*
G01X140750Y408750D02*
X143417D01*
X143167Y409333D01*
X142750Y409667D01*
X142167Y409833D01*
X141583Y409750D01*
X141083Y409500D01*
X140750Y408917D01*
X140583Y408417D01*
Y407917D01*
X140750Y407417D01*
X141167Y406917D01*
X141667Y406583D01*
X142250Y406500D01*
X142833Y406667D01*
X143417Y407167D01*
G01X146433Y405250D02*
X147017Y404917D01*
X147683Y404833D01*
X148267Y404917D01*
X148767Y405333D01*
X149100Y405917D01*
Y409833D01*
G01Y409167D02*
X148767Y409500D01*
X148267Y409750D01*
X147683Y409833D01*
X147017Y409667D01*
X146600Y409333D01*
X146267Y408750D01*
X146100Y408167D01*
X146183Y407667D01*
X146517Y407083D01*
X147017Y406667D01*
X147683Y406500D01*
X148183Y406583D01*
X148767Y406917D01*
X149100Y407250D01*
G01X153200Y409833D02*
Y406500D01*
G01Y411167D02*
X153033Y411250D01*
Y411417D01*
X153200Y411500D01*
X153367Y411417D01*
Y411250D01*
X153200Y411167D01*
G01X157550Y407083D02*
X157967Y406750D01*
X158550Y406500D01*
X159050D01*
X159550Y406667D01*
X159883Y406917D01*
X160050Y407250D01*
X159967Y407750D01*
X159633Y408000D01*
X158133Y408500D01*
X157800Y409083D01*
X157967Y409500D01*
X158300Y409750D01*
X158800Y409833D01*
X159300Y409750D01*
X159800Y409500D01*
G01X164400Y411500D02*
Y406500D01*
G01X163233Y409833D02*
X165567D01*
G01X168833Y406500D02*
Y409833D01*
G01Y409167D02*
X169250Y409500D01*
X169667Y409750D01*
X170250Y409833D01*
X170667Y409750D01*
X171167Y409500D01*
G01X177100Y406500D02*
Y409833D01*
G01Y409250D02*
X176767Y409583D01*
X176267Y409750D01*
X175683Y409833D01*
X175100Y409667D01*
X174600Y409333D01*
X174267Y408833D01*
X174100Y408167D01*
X174267Y407500D01*
X174600Y407000D01*
X175100Y406667D01*
X175683Y406500D01*
X176267Y406583D01*
X176767Y406833D01*
X177100Y407167D01*
G01X181200Y411500D02*
Y406500D01*
G01X180033Y409833D02*
X182367D01*
G01X186800D02*
Y406500D01*
G01Y411167D02*
X186633Y411250D01*
Y411417D01*
X186800Y411500D01*
X186967Y411417D01*
Y411250D01*
X186800Y411167D01*
G01X192400Y406500D02*
X191900Y406583D01*
X191400Y406917D01*
X191067Y407500D01*
X190900Y408167D01*
X191067Y408833D01*
X191400Y409417D01*
X191900Y409750D01*
X192400Y409833D01*
X192900Y409750D01*
X193400Y409417D01*
X193733Y408833D01*
X193817Y408167D01*
X193733Y407500D01*
X193400Y406917D01*
X192900Y406583D01*
X192400Y406500D01*
G01X196583D02*
Y409833D01*
G01Y409000D02*
X196917Y409417D01*
X197417Y409750D01*
X198083Y409833D01*
X198667Y409750D01*
X199167Y409417D01*
X199417Y408833D01*
Y406500D01*
G01X112167Y433000D02*
Y438000D01*
X113833D01*
X114500Y437750D01*
X115000Y437417D01*
X115417Y436917D01*
X115750Y436333D01*
X115833Y435500D01*
X115750Y434667D01*
X115417Y434083D01*
X115000Y433583D01*
X114500Y433250D01*
X113833Y433000D01*
X112167D01*
G01X118350Y435250D02*
X121017D01*
X120767Y435833D01*
X120350Y436167D01*
X119767Y436333D01*
X119183Y436250D01*
X118683Y436000D01*
X118350Y435417D01*
X118183Y434917D01*
Y434417D01*
X118350Y433917D01*
X118767Y433417D01*
X119267Y433083D01*
X119850Y433000D01*
X120433Y433167D01*
X121017Y433667D01*
G01X123700Y431333D02*
Y436333D01*
G01Y435583D02*
X124117Y436000D01*
X124533Y436250D01*
X125200Y436333D01*
X125783Y436250D01*
X126367Y435833D01*
X126617Y435250D01*
X126700Y434667D01*
X126617Y434083D01*
X126367Y433500D01*
X125867Y433167D01*
X125200Y433000D01*
X124617Y433083D01*
X124033Y433333D01*
X123700Y433667D01*
G01X130800Y438000D02*
Y433000D01*
G01X129633Y436333D02*
X131967D01*
G01X134983Y433000D02*
Y438000D01*
G01Y435583D02*
X135400Y436000D01*
X135817Y436250D01*
X136483Y436333D01*
X136983Y436250D01*
X137567Y435917D01*
X137817Y435417D01*
Y433000D01*
G01X148933Y435917D02*
X148350Y436250D01*
X147850Y436333D01*
X147183Y436167D01*
X146683Y435833D01*
X146350Y435250D01*
X146267Y434667D01*
X146350Y434083D01*
X146683Y433583D01*
X147183Y433167D01*
X147850Y433000D01*
X148433Y433167D01*
X148933Y433500D01*
G01X153200Y433000D02*
X152700Y433083D01*
X152200Y433417D01*
X151867Y434000D01*
X151700Y434667D01*
X151867Y435333D01*
X152200Y435917D01*
X152700Y436250D01*
X153200Y436333D01*
X153700Y436250D01*
X154200Y435917D01*
X154533Y435333D01*
X154617Y434667D01*
X154533Y434000D01*
X154200Y433417D01*
X153700Y433083D01*
X153200Y433000D01*
G01X157383D02*
Y436333D01*
G01Y435500D02*
X157717Y435917D01*
X158217Y436250D01*
X158883Y436333D01*
X159467Y436250D01*
X159967Y435917D01*
X160217Y435333D01*
Y433000D01*
G01X164400Y438000D02*
Y433000D01*
G01X163233Y436333D02*
X165567D01*
G01X168833Y433000D02*
Y436333D01*
G01Y435667D02*
X169250Y436000D01*
X169667Y436250D01*
X170250Y436333D01*
X170667Y436250D01*
X171167Y436000D01*
G01X175600Y433000D02*
X175100Y433083D01*
X174600Y433417D01*
X174267Y434000D01*
X174100Y434667D01*
X174267Y435333D01*
X174600Y435917D01*
X175100Y436250D01*
X175600Y436333D01*
X176100Y436250D01*
X176600Y435917D01*
X176933Y435333D01*
X177017Y434667D01*
X176933Y434000D01*
X176600Y433417D01*
X176100Y433083D01*
X175600Y433000D01*
G01X181200D02*
Y438000D01*
G01X190983Y433000D02*
Y438000D01*
G01Y435583D02*
X191400Y436000D01*
X191817Y436250D01*
X192483Y436333D01*
X192983Y436250D01*
X193567Y435917D01*
X193817Y435417D01*
Y433000D01*
G01X198000D02*
X197500Y433083D01*
X197000Y433417D01*
X196667Y434000D01*
X196500Y434667D01*
X196667Y435333D01*
X197000Y435917D01*
X197500Y436250D01*
X198000Y436333D01*
X198500Y436250D01*
X199000Y435917D01*
X199333Y435333D01*
X199417Y434667D01*
X199333Y434000D01*
X199000Y433417D01*
X198500Y433083D01*
X198000Y433000D01*
G01X203600D02*
Y438000D01*
G01X207950Y435250D02*
X210617D01*
X210367Y435833D01*
X209950Y436167D01*
X209367Y436333D01*
X208783Y436250D01*
X208283Y436000D01*
X207950Y435417D01*
X207783Y434917D01*
Y434417D01*
X207950Y433917D01*
X208367Y433417D01*
X208867Y433083D01*
X209450Y433000D01*
X210033Y433167D01*
X210617Y433667D01*
G01X112333Y455000D02*
Y460000D01*
X114417D01*
X115083Y459750D01*
X115500Y459417D01*
X115667Y458750D01*
X115500Y458083D01*
X115000Y457667D01*
X114417Y457417D01*
X112333D01*
G01X114417D02*
X115667Y455000D01*
G01X119600D02*
X119100Y455083D01*
X118600Y455417D01*
X118267Y456000D01*
X118100Y456667D01*
X118267Y457333D01*
X118600Y457917D01*
X119100Y458250D01*
X119600Y458333D01*
X120100Y458250D01*
X120600Y457917D01*
X120933Y457333D01*
X121017Y456667D01*
X120933Y456000D01*
X120600Y455417D01*
X120100Y455083D01*
X119600Y455000D01*
G01X123783Y458333D02*
Y456000D01*
X124117Y455417D01*
X124617Y455083D01*
X125200Y455000D01*
X125783Y455083D01*
X126283Y455417D01*
X126617Y456000D01*
G01Y455000D02*
Y458333D01*
G01X129633Y453750D02*
X130217Y453417D01*
X130883Y453333D01*
X131467Y453417D01*
X131967Y453833D01*
X132300Y454417D01*
Y458333D01*
G01Y457667D02*
X131967Y458000D01*
X131467Y458250D01*
X130883Y458333D01*
X130217Y458167D01*
X129800Y457833D01*
X129467Y457250D01*
X129300Y456667D01*
X129383Y456167D01*
X129717Y455583D01*
X130217Y455167D01*
X130883Y455000D01*
X131383Y455083D01*
X131967Y455417D01*
X132300Y455750D01*
G01X134983Y455000D02*
Y460000D01*
G01Y457583D02*
X135400Y458000D01*
X135817Y458250D01*
X136483Y458333D01*
X136983Y458250D01*
X137567Y457917D01*
X137817Y457417D01*
Y455000D01*
G01X140583D02*
Y458333D01*
G01Y457500D02*
X140917Y457917D01*
X141417Y458250D01*
X142083Y458333D01*
X142667Y458250D01*
X143167Y457917D01*
X143417Y457333D01*
Y455000D01*
G01X146350Y457250D02*
X149017D01*
X148767Y457833D01*
X148350Y458167D01*
X147767Y458333D01*
X147183Y458250D01*
X146683Y458000D01*
X146350Y457417D01*
X146183Y456917D01*
Y456417D01*
X146350Y455917D01*
X146767Y455417D01*
X147267Y455083D01*
X147850Y455000D01*
X148433Y455167D01*
X149017Y455667D01*
G01X151950Y455583D02*
X152367Y455250D01*
X152950Y455000D01*
X153450D01*
X153950Y455167D01*
X154283Y455417D01*
X154450Y455750D01*
X154367Y456250D01*
X154033Y456500D01*
X152533Y457000D01*
X152200Y457583D01*
X152367Y458000D01*
X152700Y458250D01*
X153200Y458333D01*
X153700Y458250D01*
X154200Y458000D01*
G01X157550Y455583D02*
X157967Y455250D01*
X158550Y455000D01*
X159050D01*
X159550Y455167D01*
X159883Y455417D01*
X160050Y455750D01*
X159967Y456250D01*
X159633Y456500D01*
X158133Y457000D01*
X157800Y457583D01*
X157967Y458000D01*
X158300Y458250D01*
X158800Y458333D01*
X159300Y458250D01*
X159800Y458000D01*
G01X112167Y433000D02*
Y438000D01*
X113833D01*
X114500Y437750D01*
X115000Y437417D01*
X115417Y436917D01*
X115750Y436333D01*
X115833Y435500D01*
X115750Y434667D01*
X115417Y434083D01*
X115000Y433583D01*
X114500Y433250D01*
X113833Y433000D01*
X112167D01*
G01X118350Y435250D02*
X121017D01*
X120767Y435833D01*
X120350Y436167D01*
X119767Y436333D01*
X119183Y436250D01*
X118683Y436000D01*
X118350Y435417D01*
X118183Y434917D01*
Y434417D01*
X118350Y433917D01*
X118767Y433417D01*
X119267Y433083D01*
X119850Y433000D01*
X120433Y433167D01*
X121017Y433667D01*
G01X123700Y431333D02*
Y436333D01*
G01Y435583D02*
X124117Y436000D01*
X124533Y436250D01*
X125200Y436333D01*
X125783Y436250D01*
X126367Y435833D01*
X126617Y435250D01*
X126700Y434667D01*
X126617Y434083D01*
X126367Y433500D01*
X125867Y433167D01*
X125200Y433000D01*
X124617Y433083D01*
X124033Y433333D01*
X123700Y433667D01*
G01X130800Y438000D02*
Y433000D01*
G01X129633Y436333D02*
X131967D01*
G01X134983Y433000D02*
Y438000D01*
G01Y435583D02*
X135400Y436000D01*
X135817Y436250D01*
X136483Y436333D01*
X136983Y436250D01*
X137567Y435917D01*
X137817Y435417D01*
Y433000D01*
G01X148933Y435917D02*
X148350Y436250D01*
X147850Y436333D01*
X147183Y436167D01*
X146683Y435833D01*
X146350Y435250D01*
X146267Y434667D01*
X146350Y434083D01*
X146683Y433583D01*
X147183Y433167D01*
X147850Y433000D01*
X148433Y433167D01*
X148933Y433500D01*
G01X153200Y433000D02*
X152700Y433083D01*
X152200Y433417D01*
X151867Y434000D01*
X151700Y434667D01*
X151867Y435333D01*
X152200Y435917D01*
X152700Y436250D01*
X153200Y436333D01*
X153700Y436250D01*
X154200Y435917D01*
X154533Y435333D01*
X154617Y434667D01*
X154533Y434000D01*
X154200Y433417D01*
X153700Y433083D01*
X153200Y433000D01*
G01X157383D02*
Y436333D01*
G01Y435500D02*
X157717Y435917D01*
X158217Y436250D01*
X158883Y436333D01*
X159467Y436250D01*
X159967Y435917D01*
X160217Y435333D01*
Y433000D01*
G01X164400Y438000D02*
Y433000D01*
G01X163233Y436333D02*
X165567D01*
G01X168833Y433000D02*
Y436333D01*
G01Y435667D02*
X169250Y436000D01*
X169667Y436250D01*
X170250Y436333D01*
X170667Y436250D01*
X171167Y436000D01*
G01X175600Y433000D02*
X175100Y433083D01*
X174600Y433417D01*
X174267Y434000D01*
X174100Y434667D01*
X174267Y435333D01*
X174600Y435917D01*
X175100Y436250D01*
X175600Y436333D01*
X176100Y436250D01*
X176600Y435917D01*
X176933Y435333D01*
X177017Y434667D01*
X176933Y434000D01*
X176600Y433417D01*
X176100Y433083D01*
X175600Y433000D01*
G01X181200D02*
Y438000D01*
G01X190983Y433000D02*
Y438000D01*
G01Y435583D02*
X191400Y436000D01*
X191817Y436250D01*
X192483Y436333D01*
X192983Y436250D01*
X193567Y435917D01*
X193817Y435417D01*
Y433000D01*
G01X198000D02*
X197500Y433083D01*
X197000Y433417D01*
X196667Y434000D01*
X196500Y434667D01*
X196667Y435333D01*
X197000Y435917D01*
X197500Y436250D01*
X198000Y436333D01*
X198500Y436250D01*
X199000Y435917D01*
X199333Y435333D01*
X199417Y434667D01*
X199333Y434000D01*
X199000Y433417D01*
X198500Y433083D01*
X198000Y433000D01*
G01X203600D02*
Y438000D01*
G01X207950Y435250D02*
X210617D01*
X210367Y435833D01*
X209950Y436167D01*
X209367Y436333D01*
X208783Y436250D01*
X208283Y436000D01*
X207950Y435417D01*
X207783Y434917D01*
Y434417D01*
X207950Y433917D01*
X208367Y433417D01*
X208867Y433083D01*
X209450Y433000D01*
X210033Y433167D01*
X210617Y433667D01*
G01X112333Y455000D02*
Y460000D01*
X114417D01*
X115083Y459750D01*
X115500Y459417D01*
X115667Y458750D01*
X115500Y458083D01*
X115000Y457667D01*
X114417Y457417D01*
X112333D01*
G01X114417D02*
X115667Y455000D01*
G01X119600D02*
X119100Y455083D01*
X118600Y455417D01*
X118267Y456000D01*
X118100Y456667D01*
X118267Y457333D01*
X118600Y457917D01*
X119100Y458250D01*
X119600Y458333D01*
X120100Y458250D01*
X120600Y457917D01*
X120933Y457333D01*
X121017Y456667D01*
X120933Y456000D01*
X120600Y455417D01*
X120100Y455083D01*
X119600Y455000D01*
G01X123783Y458333D02*
Y456000D01*
X124117Y455417D01*
X124617Y455083D01*
X125200Y455000D01*
X125783Y455083D01*
X126283Y455417D01*
X126617Y456000D01*
G01Y455000D02*
Y458333D01*
G01X129633Y453750D02*
X130217Y453417D01*
X130883Y453333D01*
X131467Y453417D01*
X131967Y453833D01*
X132300Y454417D01*
Y458333D01*
G01Y457667D02*
X131967Y458000D01*
X131467Y458250D01*
X130883Y458333D01*
X130217Y458167D01*
X129800Y457833D01*
X129467Y457250D01*
X129300Y456667D01*
X129383Y456167D01*
X129717Y455583D01*
X130217Y455167D01*
X130883Y455000D01*
X131383Y455083D01*
X131967Y455417D01*
X132300Y455750D01*
G01X134983Y455000D02*
Y460000D01*
G01Y457583D02*
X135400Y458000D01*
X135817Y458250D01*
X136483Y458333D01*
X136983Y458250D01*
X137567Y457917D01*
X137817Y457417D01*
Y455000D01*
G01X140583D02*
Y458333D01*
G01Y457500D02*
X140917Y457917D01*
X141417Y458250D01*
X142083Y458333D01*
X142667Y458250D01*
X143167Y457917D01*
X143417Y457333D01*
Y455000D01*
G01X146350Y457250D02*
X149017D01*
X148767Y457833D01*
X148350Y458167D01*
X147767Y458333D01*
X147183Y458250D01*
X146683Y458000D01*
X146350Y457417D01*
X146183Y456917D01*
Y456417D01*
X146350Y455917D01*
X146767Y455417D01*
X147267Y455083D01*
X147850Y455000D01*
X148433Y455167D01*
X149017Y455667D01*
G01X151950Y455583D02*
X152367Y455250D01*
X152950Y455000D01*
X153450D01*
X153950Y455167D01*
X154283Y455417D01*
X154450Y455750D01*
X154367Y456250D01*
X154033Y456500D01*
X152533Y457000D01*
X152200Y457583D01*
X152367Y458000D01*
X152700Y458250D01*
X153200Y458333D01*
X153700Y458250D01*
X154200Y458000D01*
G01X157550Y455583D02*
X157967Y455250D01*
X158550Y455000D01*
X159050D01*
X159550Y455167D01*
X159883Y455417D01*
X160050Y455750D01*
X159967Y456250D01*
X159633Y456500D01*
X158133Y457000D01*
X157800Y457583D01*
X157967Y458000D01*
X158300Y458250D01*
X158800Y458333D01*
X159300Y458250D01*
X159800Y458000D01*
G01X112250Y513500D02*
Y518500D01*
G01X115750D02*
Y513500D01*
G01Y516000D02*
X112250D01*
G01X119600Y513500D02*
X119100Y513583D01*
X118600Y513917D01*
X118267Y514500D01*
X118100Y515167D01*
X118267Y515833D01*
X118600Y516417D01*
X119100Y516750D01*
X119600Y516833D01*
X120100Y516750D01*
X120600Y516417D01*
X120933Y515833D01*
X121017Y515167D01*
X120933Y514500D01*
X120600Y513917D01*
X120100Y513583D01*
X119600Y513500D01*
G01X125200D02*
Y518500D01*
G01X129550Y515750D02*
X132217D01*
X131967Y516333D01*
X131550Y516667D01*
X130967Y516833D01*
X130383Y516750D01*
X129883Y516500D01*
X129550Y515917D01*
X129383Y515417D01*
Y514917D01*
X129550Y514417D01*
X129967Y513917D01*
X130467Y513583D01*
X131050Y513500D01*
X131633Y513667D01*
X132217Y514167D01*
G01X140750Y514083D02*
X141167Y513750D01*
X141750Y513500D01*
X142250D01*
X142750Y513667D01*
X143083Y513917D01*
X143250Y514250D01*
X143167Y514750D01*
X142833Y515000D01*
X141333Y515500D01*
X141000Y516083D01*
X141167Y516500D01*
X141500Y516750D01*
X142000Y516833D01*
X142500Y516750D01*
X143000Y516500D01*
G01X147600Y516833D02*
Y513500D01*
G01Y518167D02*
X147433Y518250D01*
Y518417D01*
X147600Y518500D01*
X147767Y518417D01*
Y518250D01*
X147600Y518167D01*
G01X151950Y516833D02*
X154450D01*
X151950Y513500D01*
X154450D01*
G01X157550Y515750D02*
X160217D01*
X159967Y516333D01*
X159550Y516667D01*
X158967Y516833D01*
X158383Y516750D01*
X157883Y516500D01*
X157550Y515917D01*
X157383Y515417D01*
Y514917D01*
X157550Y514417D01*
X157967Y513917D01*
X158467Y513583D01*
X159050Y513500D01*
X159633Y513667D01*
X160217Y514167D01*
G01X112250Y513500D02*
Y518500D01*
G01X115750D02*
Y513500D01*
G01Y516000D02*
X112250D01*
G01X119600Y513500D02*
X119100Y513583D01*
X118600Y513917D01*
X118267Y514500D01*
X118100Y515167D01*
X118267Y515833D01*
X118600Y516417D01*
X119100Y516750D01*
X119600Y516833D01*
X120100Y516750D01*
X120600Y516417D01*
X120933Y515833D01*
X121017Y515167D01*
X120933Y514500D01*
X120600Y513917D01*
X120100Y513583D01*
X119600Y513500D01*
G01X125200D02*
Y518500D01*
G01X129550Y515750D02*
X132217D01*
X131967Y516333D01*
X131550Y516667D01*
X130967Y516833D01*
X130383Y516750D01*
X129883Y516500D01*
X129550Y515917D01*
X129383Y515417D01*
Y514917D01*
X129550Y514417D01*
X129967Y513917D01*
X130467Y513583D01*
X131050Y513500D01*
X131633Y513667D01*
X132217Y514167D01*
G01X140750Y514083D02*
X141167Y513750D01*
X141750Y513500D01*
X142250D01*
X142750Y513667D01*
X143083Y513917D01*
X143250Y514250D01*
X143167Y514750D01*
X142833Y515000D01*
X141333Y515500D01*
X141000Y516083D01*
X141167Y516500D01*
X141500Y516750D01*
X142000Y516833D01*
X142500Y516750D01*
X143000Y516500D01*
G01X147600Y516833D02*
Y513500D01*
G01Y518167D02*
X147433Y518250D01*
Y518417D01*
X147600Y518500D01*
X147767Y518417D01*
Y518250D01*
X147600Y518167D01*
G01X151950Y516833D02*
X154450D01*
X151950Y513500D01*
X154450D01*
G01X157550Y515750D02*
X160217D01*
X159967Y516333D01*
X159550Y516667D01*
X158967Y516833D01*
X158383Y516750D01*
X157883Y516500D01*
X157550Y515917D01*
X157383Y515417D01*
Y514917D01*
X157550Y514417D01*
X157967Y513917D01*
X158467Y513583D01*
X159050Y513500D01*
X159633Y513667D01*
X160217Y514167D01*
G01X111917Y610000D02*
X114000Y605000D01*
X116083Y610000D01*
G01X119600Y608333D02*
Y605000D01*
G01Y609667D02*
X119433Y609750D01*
Y609917D01*
X119600Y610000D01*
X119767Y609917D01*
Y609750D01*
X119600Y609667D01*
G01X126700Y605000D02*
Y608333D01*
G01Y607750D02*
X126367Y608083D01*
X125867Y608250D01*
X125283Y608333D01*
X124700Y608167D01*
X124200Y607833D01*
X123867Y607333D01*
X123700Y606667D01*
X123867Y606000D01*
X124200Y605500D01*
X124700Y605167D01*
X125283Y605000D01*
X125867Y605083D01*
X126367Y605333D01*
X126700Y605667D01*
G01X134983Y605000D02*
Y610000D01*
G01Y607583D02*
X135400Y608000D01*
X135817Y608250D01*
X136483Y608333D01*
X136983Y608250D01*
X137567Y607917D01*
X137817Y607417D01*
Y605000D01*
G01X142000D02*
X141500Y605083D01*
X141000Y605417D01*
X140667Y606000D01*
X140500Y606667D01*
X140667Y607333D01*
X141000Y607917D01*
X141500Y608250D01*
X142000Y608333D01*
X142500Y608250D01*
X143000Y607917D01*
X143333Y607333D01*
X143417Y606667D01*
X143333Y606000D01*
X143000Y605417D01*
X142500Y605083D01*
X142000Y605000D01*
G01X147600D02*
Y610000D01*
G01X151950Y607250D02*
X154617D01*
X154367Y607833D01*
X153950Y608167D01*
X153367Y608333D01*
X152783Y608250D01*
X152283Y608000D01*
X151950Y607417D01*
X151783Y606917D01*
Y606417D01*
X151950Y605917D01*
X152367Y605417D01*
X152867Y605083D01*
X153450Y605000D01*
X154033Y605167D01*
X154617Y605667D01*
G01X164400Y610000D02*
Y605000D01*
G01X163233Y608333D02*
X165567D01*
G01X168583Y605000D02*
Y610000D01*
G01Y607583D02*
X169000Y608000D01*
X169417Y608250D01*
X170083Y608333D01*
X170583Y608250D01*
X171167Y607917D01*
X171417Y607417D01*
Y605000D01*
G01X174350Y607250D02*
X177017D01*
X176767Y607833D01*
X176350Y608167D01*
X175767Y608333D01*
X175183Y608250D01*
X174683Y608000D01*
X174350Y607417D01*
X174183Y606917D01*
Y606417D01*
X174350Y605917D01*
X174767Y605417D01*
X175267Y605083D01*
X175850Y605000D01*
X176433Y605167D01*
X177017Y605667D01*
G01X180033Y605000D02*
Y608333D01*
G01Y607667D02*
X180450Y608000D01*
X180867Y608250D01*
X181450Y608333D01*
X181867Y608250D01*
X182367Y608000D01*
G01X184300Y605000D02*
Y608333D01*
G01Y607417D02*
X184550Y607833D01*
X184967Y608167D01*
X185550Y608333D01*
X186133Y608167D01*
X186550Y607833D01*
X186800Y607417D01*
Y605000D01*
G01Y607417D02*
X187050Y607833D01*
X187467Y608167D01*
X188050Y608333D01*
X188633Y608167D01*
X189050Y607833D01*
X189300Y607333D01*
Y605000D01*
G01X193900D02*
Y608333D01*
G01Y607750D02*
X193567Y608083D01*
X193067Y608250D01*
X192483Y608333D01*
X191900Y608167D01*
X191400Y607833D01*
X191067Y607333D01*
X190900Y606667D01*
X191067Y606000D01*
X191400Y605500D01*
X191900Y605167D01*
X192483Y605000D01*
X193067Y605083D01*
X193567Y605333D01*
X193900Y605667D01*
G01X198000Y605000D02*
Y610000D01*
G01X207700Y603333D02*
Y608333D01*
G01Y607583D02*
X208117Y608000D01*
X208533Y608250D01*
X209200Y608333D01*
X209783Y608250D01*
X210367Y607833D01*
X210617Y607250D01*
X210700Y606667D01*
X210617Y606083D01*
X210367Y605500D01*
X209867Y605167D01*
X209200Y605000D01*
X208617Y605083D01*
X208033Y605333D01*
X207700Y605667D01*
G01X216300Y605000D02*
Y608333D01*
G01Y607750D02*
X215967Y608083D01*
X215467Y608250D01*
X214883Y608333D01*
X214300Y608167D01*
X213800Y607833D01*
X213467Y607333D01*
X213300Y606667D01*
X213467Y606000D01*
X213800Y605500D01*
X214300Y605167D01*
X214883Y605000D01*
X215467Y605083D01*
X215967Y605333D01*
X216300Y605667D01*
G01X221900Y610000D02*
Y605000D01*
G01Y605750D02*
X221567Y605333D01*
X221067Y605083D01*
X220483Y605000D01*
X219817Y605167D01*
X219317Y605583D01*
X218983Y606083D01*
X218900Y606667D01*
X218983Y607250D01*
X219317Y607750D01*
X219817Y608167D01*
X220483Y608333D01*
X221067Y608250D01*
X221483Y608083D01*
X221900Y607750D01*
G01X112250Y588500D02*
Y593500D01*
G01X115750D02*
Y588500D01*
G01Y591000D02*
X112250D01*
G01X119600Y588500D02*
X119100Y588583D01*
X118600Y588917D01*
X118267Y589500D01*
X118100Y590167D01*
X118267Y590833D01*
X118600Y591417D01*
X119100Y591750D01*
X119600Y591833D01*
X120100Y591750D01*
X120600Y591417D01*
X120933Y590833D01*
X121017Y590167D01*
X120933Y589500D01*
X120600Y588917D01*
X120100Y588583D01*
X119600Y588500D01*
G01X125200D02*
Y593500D01*
G01X129550Y590750D02*
X132217D01*
X131967Y591333D01*
X131550Y591667D01*
X130967Y591833D01*
X130383Y591750D01*
X129883Y591500D01*
X129550Y590917D01*
X129383Y590417D01*
Y589917D01*
X129550Y589417D01*
X129967Y588917D01*
X130467Y588583D01*
X131050Y588500D01*
X131633Y588667D01*
X132217Y589167D01*
G01X140500Y586833D02*
Y591833D01*
G01Y591083D02*
X140917Y591500D01*
X141333Y591750D01*
X142000Y591833D01*
X142583Y591750D01*
X143167Y591333D01*
X143417Y590750D01*
X143500Y590167D01*
X143417Y589583D01*
X143167Y589000D01*
X142667Y588667D01*
X142000Y588500D01*
X141417Y588583D01*
X140833Y588833D01*
X140500Y589167D01*
G01X147600Y588500D02*
X147100Y588583D01*
X146600Y588917D01*
X146267Y589500D01*
X146100Y590167D01*
X146267Y590833D01*
X146600Y591417D01*
X147100Y591750D01*
X147600Y591833D01*
X148100Y591750D01*
X148600Y591417D01*
X148933Y590833D01*
X149017Y590167D01*
X148933Y589500D01*
X148600Y588917D01*
X148100Y588583D01*
X147600Y588500D01*
G01X151950Y589083D02*
X152367Y588750D01*
X152950Y588500D01*
X153450D01*
X153950Y588667D01*
X154283Y588917D01*
X154450Y589250D01*
X154367Y589750D01*
X154033Y590000D01*
X152533Y590500D01*
X152200Y591083D01*
X152367Y591500D01*
X152700Y591750D01*
X153200Y591833D01*
X153700Y591750D01*
X154200Y591500D01*
G01X158800Y591833D02*
Y588500D01*
G01Y593167D02*
X158633Y593250D01*
Y593417D01*
X158800Y593500D01*
X158967Y593417D01*
Y593250D01*
X158800Y593167D01*
G01X164400Y593500D02*
Y588500D01*
G01X163233Y591833D02*
X165567D01*
G01X170000D02*
Y588500D01*
G01Y593167D02*
X169833Y593250D01*
Y593417D01*
X170000Y593500D01*
X170167Y593417D01*
Y593250D01*
X170000Y593167D01*
G01X175600Y588500D02*
X175100Y588583D01*
X174600Y588917D01*
X174267Y589500D01*
X174100Y590167D01*
X174267Y590833D01*
X174600Y591417D01*
X175100Y591750D01*
X175600Y591833D01*
X176100Y591750D01*
X176600Y591417D01*
X176933Y590833D01*
X177017Y590167D01*
X176933Y589500D01*
X176600Y588917D01*
X176100Y588583D01*
X175600Y588500D01*
G01X179783D02*
Y591833D01*
G01Y591000D02*
X180117Y591417D01*
X180617Y591750D01*
X181283Y591833D01*
X181867Y591750D01*
X182367Y591417D01*
X182617Y590833D01*
Y588500D01*
G01X192400Y593500D02*
Y588500D01*
G01X191233Y591833D02*
X193567D01*
G01X198000Y588500D02*
X197500Y588583D01*
X197000Y588917D01*
X196667Y589500D01*
X196500Y590167D01*
X196667Y590833D01*
X197000Y591417D01*
X197500Y591750D01*
X198000Y591833D01*
X198500Y591750D01*
X199000Y591417D01*
X199333Y590833D01*
X199417Y590167D01*
X199333Y589500D01*
X199000Y588917D01*
X198500Y588583D01*
X198000Y588500D01*
G01X203600D02*
Y593500D01*
G01X207950Y590750D02*
X210617D01*
X210367Y591333D01*
X209950Y591667D01*
X209367Y591833D01*
X208783Y591750D01*
X208283Y591500D01*
X207950Y590917D01*
X207783Y590417D01*
Y589917D01*
X207950Y589417D01*
X208367Y588917D01*
X208867Y588583D01*
X209450Y588500D01*
X210033Y588667D01*
X210617Y589167D01*
G01X213633Y588500D02*
Y591833D01*
G01Y591167D02*
X214050Y591500D01*
X214467Y591750D01*
X215050Y591833D01*
X215467Y591750D01*
X215967Y591500D01*
G01X221900Y588500D02*
Y591833D01*
G01Y591250D02*
X221567Y591583D01*
X221067Y591750D01*
X220483Y591833D01*
X219900Y591667D01*
X219400Y591333D01*
X219067Y590833D01*
X218900Y590167D01*
X219067Y589500D01*
X219400Y589000D01*
X219900Y588667D01*
X220483Y588500D01*
X221067Y588583D01*
X221567Y588833D01*
X221900Y589167D01*
G01X224583Y588500D02*
Y591833D01*
G01Y591000D02*
X224917Y591417D01*
X225417Y591750D01*
X226083Y591833D01*
X226667Y591750D01*
X227167Y591417D01*
X227417Y590833D01*
Y588500D01*
G01X232933Y591417D02*
X232350Y591750D01*
X231850Y591833D01*
X231183Y591667D01*
X230683Y591333D01*
X230350Y590750D01*
X230267Y590167D01*
X230350Y589583D01*
X230683Y589083D01*
X231183Y588667D01*
X231850Y588500D01*
X232433Y588667D01*
X232933Y589000D01*
G01X235950Y590750D02*
X238617D01*
X238367Y591333D01*
X237950Y591667D01*
X237367Y591833D01*
X236783Y591750D01*
X236283Y591500D01*
X235950Y590917D01*
X235783Y590417D01*
Y589917D01*
X235950Y589417D01*
X236367Y588917D01*
X236867Y588583D01*
X237450Y588500D01*
X238033Y588667D01*
X238617Y589167D01*
G01X111917Y620000D02*
X114000Y625000D01*
X116083Y620000D01*
G01X115333Y621750D02*
X112667D01*
G01X118183Y620000D02*
Y623333D01*
G01Y622500D02*
X118517Y622917D01*
X119017Y623250D01*
X119683Y623333D01*
X120267Y623250D01*
X120767Y622917D01*
X121017Y622333D01*
Y620000D01*
G01X125200Y625000D02*
Y620000D01*
G01X124033Y623333D02*
X126367D01*
G01X130800D02*
Y620000D01*
G01Y624667D02*
X130633Y624750D01*
Y624917D01*
X130800Y625000D01*
X130967Y624917D01*
Y624750D01*
X130800Y624667D01*
G01X135317Y621667D02*
X137483D01*
G01X146100Y618333D02*
Y623333D01*
G01Y622583D02*
X146517Y623000D01*
X146933Y623250D01*
X147600Y623333D01*
X148183Y623250D01*
X148767Y622833D01*
X149017Y622250D01*
X149100Y621667D01*
X149017Y621083D01*
X148767Y620500D01*
X148267Y620167D01*
X147600Y620000D01*
X147017Y620083D01*
X146433Y620333D01*
X146100Y620667D01*
G01X154700Y620000D02*
Y623333D01*
G01Y622750D02*
X154367Y623083D01*
X153867Y623250D01*
X153283Y623333D01*
X152700Y623167D01*
X152200Y622833D01*
X151867Y622333D01*
X151700Y621667D01*
X151867Y621000D01*
X152200Y620500D01*
X152700Y620167D01*
X153283Y620000D01*
X153867Y620083D01*
X154367Y620333D01*
X154700Y620667D01*
G01X160300Y625000D02*
Y620000D01*
G01Y620750D02*
X159967Y620333D01*
X159467Y620083D01*
X158883Y620000D01*
X158217Y620167D01*
X157717Y620583D01*
X157383Y621083D01*
X157300Y621667D01*
X157383Y622250D01*
X157717Y622750D01*
X158217Y623167D01*
X158883Y623333D01*
X159467Y623250D01*
X159883Y623083D01*
X160300Y622750D01*
G01X111843Y639590D02*
Y644590D01*
X115677Y639590D01*
Y644590D01*
G01X119360Y639590D02*
X118860Y639673D01*
X118360Y640007D01*
X118027Y640590D01*
X117860Y641257D01*
X118027Y641923D01*
X118360Y642507D01*
X118860Y642840D01*
X119360Y642923D01*
X119860Y642840D01*
X120360Y642507D01*
X120693Y641923D01*
X120777Y641257D01*
X120693Y640590D01*
X120360Y640007D01*
X119860Y639673D01*
X119360Y639590D01*
G01X123543D02*
Y642923D01*
G01Y642090D02*
X123877Y642507D01*
X124377Y642840D01*
X125043Y642923D01*
X125627Y642840D01*
X126127Y642507D01*
X126377Y641923D01*
Y639590D01*
G01X129477Y641257D02*
X131643D01*
G01X135660Y639590D02*
Y643840D01*
X135827Y644257D01*
X136160Y644507D01*
X136660Y644590D01*
X137160Y644423D01*
X137410Y644007D01*
G01X136410Y642590D02*
X134743D01*
G01X140343Y642923D02*
Y640590D01*
X140677Y640007D01*
X141177Y639673D01*
X141760Y639590D01*
X142343Y639673D01*
X142843Y640007D01*
X143177Y640590D01*
G01Y639590D02*
Y642923D01*
G01X145943Y639590D02*
Y642923D01*
G01Y642090D02*
X146277Y642507D01*
X146777Y642840D01*
X147443Y642923D01*
X148027Y642840D01*
X148527Y642507D01*
X148777Y641923D01*
Y639590D01*
G01X154293Y642507D02*
X153710Y642840D01*
X153210Y642923D01*
X152543Y642757D01*
X152043Y642423D01*
X151710Y641840D01*
X151627Y641257D01*
X151710Y640673D01*
X152043Y640173D01*
X152543Y639757D01*
X153210Y639590D01*
X153793Y639757D01*
X154293Y640090D01*
G01X158560Y644590D02*
Y639590D01*
G01X157393Y642923D02*
X159727D01*
G01X164160D02*
Y639590D01*
G01Y644257D02*
X163993Y644340D01*
Y644507D01*
X164160Y644590D01*
X164327Y644507D01*
Y644340D01*
X164160Y644257D01*
G01X169760Y639590D02*
X169260Y639673D01*
X168760Y640007D01*
X168427Y640590D01*
X168260Y641257D01*
X168427Y641923D01*
X168760Y642507D01*
X169260Y642840D01*
X169760Y642923D01*
X170260Y642840D01*
X170760Y642507D01*
X171093Y641923D01*
X171177Y641257D01*
X171093Y640590D01*
X170760Y640007D01*
X170260Y639673D01*
X169760Y639590D01*
G01X173943D02*
Y642923D01*
G01Y642090D02*
X174277Y642507D01*
X174777Y642840D01*
X175443Y642923D01*
X176027Y642840D01*
X176527Y642507D01*
X176777Y641923D01*
Y639590D01*
G01X182460D02*
Y642923D01*
G01Y642340D02*
X182127Y642673D01*
X181627Y642840D01*
X181043Y642923D01*
X180460Y642757D01*
X179960Y642423D01*
X179627Y641923D01*
X179460Y641257D01*
X179627Y640590D01*
X179960Y640090D01*
X180460Y639757D01*
X181043Y639590D01*
X181627Y639673D01*
X182127Y639923D01*
X182460Y640257D01*
G01X186560Y639590D02*
Y644590D01*
G01X196260Y637923D02*
Y642923D01*
G01Y642173D02*
X196677Y642590D01*
X197093Y642840D01*
X197760Y642923D01*
X198343Y642840D01*
X198927Y642423D01*
X199177Y641840D01*
X199260Y641257D01*
X199177Y640673D01*
X198927Y640090D01*
X198427Y639757D01*
X197760Y639590D01*
X197177Y639673D01*
X196593Y639923D01*
X196260Y640257D01*
G01X204860Y639590D02*
Y642923D01*
G01Y642340D02*
X204527Y642673D01*
X204027Y642840D01*
X203443Y642923D01*
X202860Y642757D01*
X202360Y642423D01*
X202027Y641923D01*
X201860Y641257D01*
X202027Y640590D01*
X202360Y640090D01*
X202860Y639757D01*
X203443Y639590D01*
X204027Y639673D01*
X204527Y639923D01*
X204860Y640257D01*
G01X210460Y644590D02*
Y639590D01*
G01Y640340D02*
X210127Y639923D01*
X209627Y639673D01*
X209043Y639590D01*
X208377Y639757D01*
X207877Y640173D01*
X207543Y640673D01*
X207460Y641257D01*
X207543Y641840D01*
X207877Y642340D01*
X208377Y642757D01*
X209043Y642923D01*
X209627Y642840D01*
X210043Y642673D01*
X210460Y642340D01*
G01X111917Y610000D02*
X114000Y605000D01*
X116083Y610000D01*
G01X119600Y608333D02*
Y605000D01*
G01Y609667D02*
X119433Y609750D01*
Y609917D01*
X119600Y610000D01*
X119767Y609917D01*
Y609750D01*
X119600Y609667D01*
G01X126700Y605000D02*
Y608333D01*
G01Y607750D02*
X126367Y608083D01*
X125867Y608250D01*
X125283Y608333D01*
X124700Y608167D01*
X124200Y607833D01*
X123867Y607333D01*
X123700Y606667D01*
X123867Y606000D01*
X124200Y605500D01*
X124700Y605167D01*
X125283Y605000D01*
X125867Y605083D01*
X126367Y605333D01*
X126700Y605667D01*
G01X134983Y605000D02*
Y610000D01*
G01Y607583D02*
X135400Y608000D01*
X135817Y608250D01*
X136483Y608333D01*
X136983Y608250D01*
X137567Y607917D01*
X137817Y607417D01*
Y605000D01*
G01X142000D02*
X141500Y605083D01*
X141000Y605417D01*
X140667Y606000D01*
X140500Y606667D01*
X140667Y607333D01*
X141000Y607917D01*
X141500Y608250D01*
X142000Y608333D01*
X142500Y608250D01*
X143000Y607917D01*
X143333Y607333D01*
X143417Y606667D01*
X143333Y606000D01*
X143000Y605417D01*
X142500Y605083D01*
X142000Y605000D01*
G01X147600D02*
Y610000D01*
G01X151950Y607250D02*
X154617D01*
X154367Y607833D01*
X153950Y608167D01*
X153367Y608333D01*
X152783Y608250D01*
X152283Y608000D01*
X151950Y607417D01*
X151783Y606917D01*
Y606417D01*
X151950Y605917D01*
X152367Y605417D01*
X152867Y605083D01*
X153450Y605000D01*
X154033Y605167D01*
X154617Y605667D01*
G01X164400Y610000D02*
Y605000D01*
G01X163233Y608333D02*
X165567D01*
G01X168583Y605000D02*
Y610000D01*
G01Y607583D02*
X169000Y608000D01*
X169417Y608250D01*
X170083Y608333D01*
X170583Y608250D01*
X171167Y607917D01*
X171417Y607417D01*
Y605000D01*
G01X174350Y607250D02*
X177017D01*
X176767Y607833D01*
X176350Y608167D01*
X175767Y608333D01*
X175183Y608250D01*
X174683Y608000D01*
X174350Y607417D01*
X174183Y606917D01*
Y606417D01*
X174350Y605917D01*
X174767Y605417D01*
X175267Y605083D01*
X175850Y605000D01*
X176433Y605167D01*
X177017Y605667D01*
G01X180033Y605000D02*
Y608333D01*
G01Y607667D02*
X180450Y608000D01*
X180867Y608250D01*
X181450Y608333D01*
X181867Y608250D01*
X182367Y608000D01*
G01X184300Y605000D02*
Y608333D01*
G01Y607417D02*
X184550Y607833D01*
X184967Y608167D01*
X185550Y608333D01*
X186133Y608167D01*
X186550Y607833D01*
X186800Y607417D01*
Y605000D01*
G01Y607417D02*
X187050Y607833D01*
X187467Y608167D01*
X188050Y608333D01*
X188633Y608167D01*
X189050Y607833D01*
X189300Y607333D01*
Y605000D01*
G01X193900D02*
Y608333D01*
G01Y607750D02*
X193567Y608083D01*
X193067Y608250D01*
X192483Y608333D01*
X191900Y608167D01*
X191400Y607833D01*
X191067Y607333D01*
X190900Y606667D01*
X191067Y606000D01*
X191400Y605500D01*
X191900Y605167D01*
X192483Y605000D01*
X193067Y605083D01*
X193567Y605333D01*
X193900Y605667D01*
G01X198000Y605000D02*
Y610000D01*
G01X207700Y603333D02*
Y608333D01*
G01Y607583D02*
X208117Y608000D01*
X208533Y608250D01*
X209200Y608333D01*
X209783Y608250D01*
X210367Y607833D01*
X210617Y607250D01*
X210700Y606667D01*
X210617Y606083D01*
X210367Y605500D01*
X209867Y605167D01*
X209200Y605000D01*
X208617Y605083D01*
X208033Y605333D01*
X207700Y605667D01*
G01X216300Y605000D02*
Y608333D01*
G01Y607750D02*
X215967Y608083D01*
X215467Y608250D01*
X214883Y608333D01*
X214300Y608167D01*
X213800Y607833D01*
X213467Y607333D01*
X213300Y606667D01*
X213467Y606000D01*
X213800Y605500D01*
X214300Y605167D01*
X214883Y605000D01*
X215467Y605083D01*
X215967Y605333D01*
X216300Y605667D01*
G01X221900Y610000D02*
Y605000D01*
G01Y605750D02*
X221567Y605333D01*
X221067Y605083D01*
X220483Y605000D01*
X219817Y605167D01*
X219317Y605583D01*
X218983Y606083D01*
X218900Y606667D01*
X218983Y607250D01*
X219317Y607750D01*
X219817Y608167D01*
X220483Y608333D01*
X221067Y608250D01*
X221483Y608083D01*
X221900Y607750D01*
G01X112250Y588500D02*
Y593500D01*
G01X115750D02*
Y588500D01*
G01Y591000D02*
X112250D01*
G01X119600Y588500D02*
X119100Y588583D01*
X118600Y588917D01*
X118267Y589500D01*
X118100Y590167D01*
X118267Y590833D01*
X118600Y591417D01*
X119100Y591750D01*
X119600Y591833D01*
X120100Y591750D01*
X120600Y591417D01*
X120933Y590833D01*
X121017Y590167D01*
X120933Y589500D01*
X120600Y588917D01*
X120100Y588583D01*
X119600Y588500D01*
G01X125200D02*
Y593500D01*
G01X129550Y590750D02*
X132217D01*
X131967Y591333D01*
X131550Y591667D01*
X130967Y591833D01*
X130383Y591750D01*
X129883Y591500D01*
X129550Y590917D01*
X129383Y590417D01*
Y589917D01*
X129550Y589417D01*
X129967Y588917D01*
X130467Y588583D01*
X131050Y588500D01*
X131633Y588667D01*
X132217Y589167D01*
G01X140500Y586833D02*
Y591833D01*
G01Y591083D02*
X140917Y591500D01*
X141333Y591750D01*
X142000Y591833D01*
X142583Y591750D01*
X143167Y591333D01*
X143417Y590750D01*
X143500Y590167D01*
X143417Y589583D01*
X143167Y589000D01*
X142667Y588667D01*
X142000Y588500D01*
X141417Y588583D01*
X140833Y588833D01*
X140500Y589167D01*
G01X147600Y588500D02*
X147100Y588583D01*
X146600Y588917D01*
X146267Y589500D01*
X146100Y590167D01*
X146267Y590833D01*
X146600Y591417D01*
X147100Y591750D01*
X147600Y591833D01*
X148100Y591750D01*
X148600Y591417D01*
X148933Y590833D01*
X149017Y590167D01*
X148933Y589500D01*
X148600Y588917D01*
X148100Y588583D01*
X147600Y588500D01*
G01X151950Y589083D02*
X152367Y588750D01*
X152950Y588500D01*
X153450D01*
X153950Y588667D01*
X154283Y588917D01*
X154450Y589250D01*
X154367Y589750D01*
X154033Y590000D01*
X152533Y590500D01*
X152200Y591083D01*
X152367Y591500D01*
X152700Y591750D01*
X153200Y591833D01*
X153700Y591750D01*
X154200Y591500D01*
G01X158800Y591833D02*
Y588500D01*
G01Y593167D02*
X158633Y593250D01*
Y593417D01*
X158800Y593500D01*
X158967Y593417D01*
Y593250D01*
X158800Y593167D01*
G01X164400Y593500D02*
Y588500D01*
G01X163233Y591833D02*
X165567D01*
G01X170000D02*
Y588500D01*
G01Y593167D02*
X169833Y593250D01*
Y593417D01*
X170000Y593500D01*
X170167Y593417D01*
Y593250D01*
X170000Y593167D01*
G01X175600Y588500D02*
X175100Y588583D01*
X174600Y588917D01*
X174267Y589500D01*
X174100Y590167D01*
X174267Y590833D01*
X174600Y591417D01*
X175100Y591750D01*
X175600Y591833D01*
X176100Y591750D01*
X176600Y591417D01*
X176933Y590833D01*
X177017Y590167D01*
X176933Y589500D01*
X176600Y588917D01*
X176100Y588583D01*
X175600Y588500D01*
G01X179783D02*
Y591833D01*
G01Y591000D02*
X180117Y591417D01*
X180617Y591750D01*
X181283Y591833D01*
X181867Y591750D01*
X182367Y591417D01*
X182617Y590833D01*
Y588500D01*
G01X192400Y593500D02*
Y588500D01*
G01X191233Y591833D02*
X193567D01*
G01X198000Y588500D02*
X197500Y588583D01*
X197000Y588917D01*
X196667Y589500D01*
X196500Y590167D01*
X196667Y590833D01*
X197000Y591417D01*
X197500Y591750D01*
X198000Y591833D01*
X198500Y591750D01*
X199000Y591417D01*
X199333Y590833D01*
X199417Y590167D01*
X199333Y589500D01*
X199000Y588917D01*
X198500Y588583D01*
X198000Y588500D01*
G01X203600D02*
Y593500D01*
G01X207950Y590750D02*
X210617D01*
X210367Y591333D01*
X209950Y591667D01*
X209367Y591833D01*
X208783Y591750D01*
X208283Y591500D01*
X207950Y590917D01*
X207783Y590417D01*
Y589917D01*
X207950Y589417D01*
X208367Y588917D01*
X208867Y588583D01*
X209450Y588500D01*
X210033Y588667D01*
X210617Y589167D01*
G01X213633Y588500D02*
Y591833D01*
G01Y591167D02*
X214050Y591500D01*
X214467Y591750D01*
X215050Y591833D01*
X215467Y591750D01*
X215967Y591500D01*
G01X221900Y588500D02*
Y591833D01*
G01Y591250D02*
X221567Y591583D01*
X221067Y591750D01*
X220483Y591833D01*
X219900Y591667D01*
X219400Y591333D01*
X219067Y590833D01*
X218900Y590167D01*
X219067Y589500D01*
X219400Y589000D01*
X219900Y588667D01*
X220483Y588500D01*
X221067Y588583D01*
X221567Y588833D01*
X221900Y589167D01*
G01X224583Y588500D02*
Y591833D01*
G01Y591000D02*
X224917Y591417D01*
X225417Y591750D01*
X226083Y591833D01*
X226667Y591750D01*
X227167Y591417D01*
X227417Y590833D01*
Y588500D01*
G01X232933Y591417D02*
X232350Y591750D01*
X231850Y591833D01*
X231183Y591667D01*
X230683Y591333D01*
X230350Y590750D01*
X230267Y590167D01*
X230350Y589583D01*
X230683Y589083D01*
X231183Y588667D01*
X231850Y588500D01*
X232433Y588667D01*
X232933Y589000D01*
G01X235950Y590750D02*
X238617D01*
X238367Y591333D01*
X237950Y591667D01*
X237367Y591833D01*
X236783Y591750D01*
X236283Y591500D01*
X235950Y590917D01*
X235783Y590417D01*
Y589917D01*
X235950Y589417D01*
X236367Y588917D01*
X236867Y588583D01*
X237450Y588500D01*
X238033Y588667D01*
X238617Y589167D01*
G01X111917Y620000D02*
X114000Y625000D01*
X116083Y620000D01*
G01X115333Y621750D02*
X112667D01*
G01X118183Y620000D02*
Y623333D01*
G01Y622500D02*
X118517Y622917D01*
X119017Y623250D01*
X119683Y623333D01*
X120267Y623250D01*
X120767Y622917D01*
X121017Y622333D01*
Y620000D01*
G01X125200Y625000D02*
Y620000D01*
G01X124033Y623333D02*
X126367D01*
G01X130800D02*
Y620000D01*
G01Y624667D02*
X130633Y624750D01*
Y624917D01*
X130800Y625000D01*
X130967Y624917D01*
Y624750D01*
X130800Y624667D01*
G01X135317Y621667D02*
X137483D01*
G01X146100Y618333D02*
Y623333D01*
G01Y622583D02*
X146517Y623000D01*
X146933Y623250D01*
X147600Y623333D01*
X148183Y623250D01*
X148767Y622833D01*
X149017Y622250D01*
X149100Y621667D01*
X149017Y621083D01*
X148767Y620500D01*
X148267Y620167D01*
X147600Y620000D01*
X147017Y620083D01*
X146433Y620333D01*
X146100Y620667D01*
G01X154700Y620000D02*
Y623333D01*
G01Y622750D02*
X154367Y623083D01*
X153867Y623250D01*
X153283Y623333D01*
X152700Y623167D01*
X152200Y622833D01*
X151867Y622333D01*
X151700Y621667D01*
X151867Y621000D01*
X152200Y620500D01*
X152700Y620167D01*
X153283Y620000D01*
X153867Y620083D01*
X154367Y620333D01*
X154700Y620667D01*
G01X160300Y625000D02*
Y620000D01*
G01Y620750D02*
X159967Y620333D01*
X159467Y620083D01*
X158883Y620000D01*
X158217Y620167D01*
X157717Y620583D01*
X157383Y621083D01*
X157300Y621667D01*
X157383Y622250D01*
X157717Y622750D01*
X158217Y623167D01*
X158883Y623333D01*
X159467Y623250D01*
X159883Y623083D01*
X160300Y622750D01*
G01X111843Y639590D02*
Y644590D01*
X115677Y639590D01*
Y644590D01*
G01X119360Y639590D02*
X118860Y639673D01*
X118360Y640007D01*
X118027Y640590D01*
X117860Y641257D01*
X118027Y641923D01*
X118360Y642507D01*
X118860Y642840D01*
X119360Y642923D01*
X119860Y642840D01*
X120360Y642507D01*
X120693Y641923D01*
X120777Y641257D01*
X120693Y640590D01*
X120360Y640007D01*
X119860Y639673D01*
X119360Y639590D01*
G01X123543D02*
Y642923D01*
G01Y642090D02*
X123877Y642507D01*
X124377Y642840D01*
X125043Y642923D01*
X125627Y642840D01*
X126127Y642507D01*
X126377Y641923D01*
Y639590D01*
G01X129477Y641257D02*
X131643D01*
G01X135660Y639590D02*
Y643840D01*
X135827Y644257D01*
X136160Y644507D01*
X136660Y644590D01*
X137160Y644423D01*
X137410Y644007D01*
G01X136410Y642590D02*
X134743D01*
G01X140343Y642923D02*
Y640590D01*
X140677Y640007D01*
X141177Y639673D01*
X141760Y639590D01*
X142343Y639673D01*
X142843Y640007D01*
X143177Y640590D01*
G01Y639590D02*
Y642923D01*
G01X145943Y639590D02*
Y642923D01*
G01Y642090D02*
X146277Y642507D01*
X146777Y642840D01*
X147443Y642923D01*
X148027Y642840D01*
X148527Y642507D01*
X148777Y641923D01*
Y639590D01*
G01X154293Y642507D02*
X153710Y642840D01*
X153210Y642923D01*
X152543Y642757D01*
X152043Y642423D01*
X151710Y641840D01*
X151627Y641257D01*
X151710Y640673D01*
X152043Y640173D01*
X152543Y639757D01*
X153210Y639590D01*
X153793Y639757D01*
X154293Y640090D01*
G01X158560Y644590D02*
Y639590D01*
G01X157393Y642923D02*
X159727D01*
G01X164160D02*
Y639590D01*
G01Y644257D02*
X163993Y644340D01*
Y644507D01*
X164160Y644590D01*
X164327Y644507D01*
Y644340D01*
X164160Y644257D01*
G01X169760Y639590D02*
X169260Y639673D01*
X168760Y640007D01*
X168427Y640590D01*
X168260Y641257D01*
X168427Y641923D01*
X168760Y642507D01*
X169260Y642840D01*
X169760Y642923D01*
X170260Y642840D01*
X170760Y642507D01*
X171093Y641923D01*
X171177Y641257D01*
X171093Y640590D01*
X170760Y640007D01*
X170260Y639673D01*
X169760Y639590D01*
G01X173943D02*
Y642923D01*
G01Y642090D02*
X174277Y642507D01*
X174777Y642840D01*
X175443Y642923D01*
X176027Y642840D01*
X176527Y642507D01*
X176777Y641923D01*
Y639590D01*
G01X182460D02*
Y642923D01*
G01Y642340D02*
X182127Y642673D01*
X181627Y642840D01*
X181043Y642923D01*
X180460Y642757D01*
X179960Y642423D01*
X179627Y641923D01*
X179460Y641257D01*
X179627Y640590D01*
X179960Y640090D01*
X180460Y639757D01*
X181043Y639590D01*
X181627Y639673D01*
X182127Y639923D01*
X182460Y640257D01*
G01X186560Y639590D02*
Y644590D01*
G01X196260Y637923D02*
Y642923D01*
G01Y642173D02*
X196677Y642590D01*
X197093Y642840D01*
X197760Y642923D01*
X198343Y642840D01*
X198927Y642423D01*
X199177Y641840D01*
X199260Y641257D01*
X199177Y640673D01*
X198927Y640090D01*
X198427Y639757D01*
X197760Y639590D01*
X197177Y639673D01*
X196593Y639923D01*
X196260Y640257D01*
G01X204860Y639590D02*
Y642923D01*
G01Y642340D02*
X204527Y642673D01*
X204027Y642840D01*
X203443Y642923D01*
X202860Y642757D01*
X202360Y642423D01*
X202027Y641923D01*
X201860Y641257D01*
X202027Y640590D01*
X202360Y640090D01*
X202860Y639757D01*
X203443Y639590D01*
X204027Y639673D01*
X204527Y639923D01*
X204860Y640257D01*
G01X210460Y644590D02*
Y639590D01*
G01Y640340D02*
X210127Y639923D01*
X209627Y639673D01*
X209043Y639590D01*
X208377Y639757D01*
X207877Y640173D01*
X207543Y640673D01*
X207460Y641257D01*
X207543Y641840D01*
X207877Y642340D01*
X208377Y642757D01*
X209043Y642923D01*
X209627Y642840D01*
X210043Y642673D01*
X210460Y642340D01*
G01X160333Y668083D02*
X159833Y668333D01*
X159250Y668500D01*
X158583D01*
X157833Y668250D01*
X157250Y667833D01*
X156833Y667333D01*
X156500Y666500D01*
X156417Y665750D01*
X156583Y665000D01*
X156833Y664500D01*
X157333Y664000D01*
X157917Y663667D01*
X158500Y663500D01*
X159083D01*
X159667Y663667D01*
X160167Y663917D01*
X160583Y664250D01*
G01X164100Y663500D02*
Y668500D01*
G01X171200Y663500D02*
Y666833D01*
G01Y666250D02*
X170867Y666583D01*
X170367Y666750D01*
X169783Y666833D01*
X169200Y666667D01*
X168700Y666333D01*
X168367Y665833D01*
X168200Y665167D01*
X168367Y664500D01*
X168700Y664000D01*
X169200Y663667D01*
X169783Y663500D01*
X170367Y663583D01*
X170867Y663833D01*
X171200Y664167D01*
G01X174050Y664083D02*
X174467Y663750D01*
X175050Y663500D01*
X175550D01*
X176050Y663667D01*
X176383Y663917D01*
X176550Y664250D01*
X176467Y664750D01*
X176133Y665000D01*
X174633Y665500D01*
X174300Y666083D01*
X174467Y666500D01*
X174800Y666750D01*
X175300Y666833D01*
X175800Y666750D01*
X176300Y666500D01*
G01X179650Y664083D02*
X180067Y663750D01*
X180650Y663500D01*
X181150D01*
X181650Y663667D01*
X181983Y663917D01*
X182150Y664250D01*
X182067Y664750D01*
X181733Y665000D01*
X180233Y665500D01*
X179900Y666083D01*
X180067Y666500D01*
X180400Y666750D01*
X180900Y666833D01*
X181400Y666750D01*
X181900Y666500D01*
G01X186500Y666833D02*
Y663500D01*
G01Y668167D02*
X186333Y668250D01*
Y668417D01*
X186500Y668500D01*
X186667Y668417D01*
Y668250D01*
X186500Y668167D01*
G01X191600Y663500D02*
Y667750D01*
X191767Y668167D01*
X192100Y668417D01*
X192600Y668500D01*
X193100Y668333D01*
X193350Y667917D01*
G01X192350Y666500D02*
X190683D01*
G01X195950Y662000D02*
X196450Y661833D01*
X197117Y662000D01*
X197533Y662333D01*
X197867Y662750D01*
X198367Y664083D01*
X199450Y666833D01*
G01X196783D02*
X198367Y664083D01*
G01X160333Y668083D02*
X159833Y668333D01*
X159250Y668500D01*
X158583D01*
X157833Y668250D01*
X157250Y667833D01*
X156833Y667333D01*
X156500Y666500D01*
X156417Y665750D01*
X156583Y665000D01*
X156833Y664500D01*
X157333Y664000D01*
X157917Y663667D01*
X158500Y663500D01*
X159083D01*
X159667Y663667D01*
X160167Y663917D01*
X160583Y664250D01*
G01X164100Y663500D02*
Y668500D01*
G01X171200Y663500D02*
Y666833D01*
G01Y666250D02*
X170867Y666583D01*
X170367Y666750D01*
X169783Y666833D01*
X169200Y666667D01*
X168700Y666333D01*
X168367Y665833D01*
X168200Y665167D01*
X168367Y664500D01*
X168700Y664000D01*
X169200Y663667D01*
X169783Y663500D01*
X170367Y663583D01*
X170867Y663833D01*
X171200Y664167D01*
G01X174050Y664083D02*
X174467Y663750D01*
X175050Y663500D01*
X175550D01*
X176050Y663667D01*
X176383Y663917D01*
X176550Y664250D01*
X176467Y664750D01*
X176133Y665000D01*
X174633Y665500D01*
X174300Y666083D01*
X174467Y666500D01*
X174800Y666750D01*
X175300Y666833D01*
X175800Y666750D01*
X176300Y666500D01*
G01X179650Y664083D02*
X180067Y663750D01*
X180650Y663500D01*
X181150D01*
X181650Y663667D01*
X181983Y663917D01*
X182150Y664250D01*
X182067Y664750D01*
X181733Y665000D01*
X180233Y665500D01*
X179900Y666083D01*
X180067Y666500D01*
X180400Y666750D01*
X180900Y666833D01*
X181400Y666750D01*
X181900Y666500D01*
G01X186500Y666833D02*
Y663500D01*
G01Y668167D02*
X186333Y668250D01*
Y668417D01*
X186500Y668500D01*
X186667Y668417D01*
Y668250D01*
X186500Y668167D01*
G01X191600Y663500D02*
Y667750D01*
X191767Y668167D01*
X192100Y668417D01*
X192600Y668500D01*
X193100Y668333D01*
X193350Y667917D01*
G01X192350Y666500D02*
X190683D01*
G01X195950Y662000D02*
X196450Y661833D01*
X197117Y662000D01*
X197533Y662333D01*
X197867Y662750D01*
X198367Y664083D01*
X199450Y666833D01*
G01X196783D02*
X198367Y664083D01*
G01X262500Y-69500D02*
Y439000D01*
G01Y-69500D02*
Y439000D01*
G01X264000Y-39500D02*
X694500D01*
G01X264000Y5500D02*
X694500D01*
G01X264000Y-39500D02*
X694500D01*
G01X264000Y5500D02*
X694500D01*
G01X264000Y40500D02*
X694500D01*
G01X264000Y75500D02*
X694500D01*
G01X264000Y90500D02*
X694500D01*
G01X264000Y40500D02*
X694500D01*
G01X264000Y75500D02*
X694500D01*
G01X264000Y90500D02*
X694500D01*
G01X264000Y135500D02*
X694500D01*
G01X264000Y160500D02*
X694500D01*
G01X264000Y135500D02*
X694500D01*
G01X264000Y160500D02*
X694500D01*
G01X262500Y237500D02*
X694500D01*
G01X262500D02*
X694500D01*
G01X262500Y290500D02*
X694500D01*
G01X262500D02*
X694500D01*
G01X262500Y397000D02*
Y679000D01*
G01Y397000D02*
Y679000D01*
G01Y479000D02*
X694500D01*
G01X262500Y494000D02*
X694500D01*
G01X262500Y479000D02*
X694500D01*
G01X262500Y494000D02*
X694500D01*
G01X262500Y509000D02*
X694500D01*
G01X262500Y524000D02*
X694500D01*
G01X262500Y539000D02*
X694500D01*
G01X262500Y554000D02*
X694500D01*
G01X262500Y569000D02*
X694500D01*
G01X262500Y509000D02*
X694500D01*
G01X262500Y524000D02*
X694500D01*
G01X262500Y539000D02*
X694500D01*
G01X262500Y554000D02*
X694500D01*
G01X262500Y569000D02*
X694500D01*
G01X274000Y-63500D02*
Y-60167D01*
G01Y-60750D02*
X273667Y-60417D01*
X273167Y-60250D01*
X272583Y-60167D01*
X272000Y-60333D01*
X271500Y-60667D01*
X271167Y-61167D01*
X271000Y-61833D01*
X271167Y-62500D01*
X271500Y-63000D01*
X272000Y-63333D01*
X272583Y-63500D01*
X273167Y-63417D01*
X273667Y-63167D01*
X274000Y-62833D01*
G01X279600Y-58500D02*
Y-63500D01*
G01Y-62750D02*
X279267Y-63167D01*
X278767Y-63417D01*
X278183Y-63500D01*
X277517Y-63333D01*
X277017Y-62917D01*
X276683Y-62417D01*
X276600Y-61833D01*
X276683Y-61250D01*
X277017Y-60750D01*
X277517Y-60333D01*
X278183Y-60167D01*
X278767Y-60250D01*
X279183Y-60417D01*
X279600Y-60750D01*
G01X285200Y-58500D02*
Y-63500D01*
G01Y-62750D02*
X284867Y-63167D01*
X284367Y-63417D01*
X283783Y-63500D01*
X283117Y-63333D01*
X282617Y-62917D01*
X282283Y-62417D01*
X282200Y-61833D01*
X282283Y-61250D01*
X282617Y-60750D01*
X283117Y-60333D01*
X283783Y-60167D01*
X284367Y-60250D01*
X284783Y-60417D01*
X285200Y-60750D01*
G01X293650Y-62917D02*
X294067Y-63250D01*
X294650Y-63500D01*
X295150D01*
X295650Y-63333D01*
X295983Y-63083D01*
X296150Y-62750D01*
X296067Y-62250D01*
X295733Y-62000D01*
X294233Y-61500D01*
X293900Y-60917D01*
X294067Y-60500D01*
X294400Y-60250D01*
X294900Y-60167D01*
X295400Y-60250D01*
X295900Y-60500D01*
G01X299083Y-60167D02*
Y-62500D01*
X299417Y-63083D01*
X299917Y-63417D01*
X300500Y-63500D01*
X301083Y-63417D01*
X301583Y-63083D01*
X301917Y-62500D01*
G01Y-63500D02*
Y-60167D01*
G01X304600Y-65167D02*
Y-60167D01*
G01Y-60917D02*
X305017Y-60500D01*
X305433Y-60250D01*
X306100Y-60167D01*
X306683Y-60250D01*
X307267Y-60667D01*
X307517Y-61250D01*
X307600Y-61833D01*
X307517Y-62417D01*
X307267Y-63000D01*
X306767Y-63333D01*
X306100Y-63500D01*
X305517Y-63417D01*
X304933Y-63167D01*
X304600Y-62833D01*
G01X310200Y-65167D02*
Y-60167D01*
G01Y-60917D02*
X310617Y-60500D01*
X311033Y-60250D01*
X311700Y-60167D01*
X312283Y-60250D01*
X312867Y-60667D01*
X313117Y-61250D01*
X313200Y-61833D01*
X313117Y-62417D01*
X312867Y-63000D01*
X312367Y-63333D01*
X311700Y-63500D01*
X311117Y-63417D01*
X310533Y-63167D01*
X310200Y-62833D01*
G01X317300Y-63500D02*
Y-58500D01*
G01X322900Y-60167D02*
Y-63500D01*
G01Y-58833D02*
X322733Y-58750D01*
Y-58583D01*
X322900Y-58500D01*
X323067Y-58583D01*
Y-58750D01*
X322900Y-58833D01*
G01X327250Y-61250D02*
X329917D01*
X329667Y-60667D01*
X329250Y-60333D01*
X328667Y-60167D01*
X328083Y-60250D01*
X327583Y-60500D01*
X327250Y-61083D01*
X327083Y-61583D01*
Y-62083D01*
X327250Y-62583D01*
X327667Y-63083D01*
X328167Y-63417D01*
X328750Y-63500D01*
X329333Y-63333D01*
X329917Y-62833D01*
G01X332933Y-63500D02*
Y-60167D01*
G01Y-60833D02*
X333350Y-60500D01*
X333767Y-60250D01*
X334350Y-60167D01*
X334767Y-60250D01*
X335267Y-60500D01*
G01X339700Y-60167D02*
X340533Y-59125D01*
Y-58500D01*
X339908D01*
Y-59125D01*
X340533D01*
G01X344050Y-62917D02*
X344467Y-63250D01*
X345050Y-63500D01*
X345550D01*
X346050Y-63333D01*
X346383Y-63083D01*
X346550Y-62750D01*
X346467Y-62250D01*
X346133Y-62000D01*
X344633Y-61500D01*
X344300Y-60917D01*
X344467Y-60500D01*
X344800Y-60250D01*
X345300Y-60167D01*
X345800Y-60250D01*
X346300Y-60500D01*
G01X354833Y-58500D02*
Y-63500D01*
X358167D01*
G01X362100D02*
X361600Y-63417D01*
X361100Y-63083D01*
X360767Y-62500D01*
X360600Y-61833D01*
X360767Y-61167D01*
X361100Y-60583D01*
X361600Y-60250D01*
X362100Y-60167D01*
X362600Y-60250D01*
X363100Y-60583D01*
X363433Y-61167D01*
X363517Y-61833D01*
X363433Y-62500D01*
X363100Y-63083D01*
X362600Y-63417D01*
X362100Y-63500D01*
G01X366533Y-64750D02*
X367117Y-65083D01*
X367783Y-65167D01*
X368367Y-65083D01*
X368867Y-64667D01*
X369200Y-64083D01*
Y-60167D01*
G01Y-60833D02*
X368867Y-60500D01*
X368367Y-60250D01*
X367783Y-60167D01*
X367117Y-60333D01*
X366700Y-60667D01*
X366367Y-61250D01*
X366200Y-61833D01*
X366283Y-62333D01*
X366617Y-62917D01*
X367117Y-63333D01*
X367783Y-63500D01*
X368283Y-63417D01*
X368867Y-63083D01*
X369200Y-62750D01*
G01X373300Y-63500D02*
X372800Y-63417D01*
X372300Y-63083D01*
X371967Y-62500D01*
X371800Y-61833D01*
X371967Y-61167D01*
X372300Y-60583D01*
X372800Y-60250D01*
X373300Y-60167D01*
X373800Y-60250D01*
X374300Y-60583D01*
X374633Y-61167D01*
X374717Y-61833D01*
X374633Y-62500D01*
X374300Y-63083D01*
X373800Y-63417D01*
X373300Y-63500D01*
G01X386000D02*
Y-60167D01*
G01Y-60750D02*
X385667Y-60417D01*
X385167Y-60250D01*
X384583Y-60167D01*
X384000Y-60333D01*
X383500Y-60667D01*
X383167Y-61167D01*
X383000Y-61833D01*
X383167Y-62500D01*
X383500Y-63000D01*
X384000Y-63333D01*
X384583Y-63500D01*
X385167Y-63417D01*
X385667Y-63167D01*
X386000Y-62833D01*
G01X388683Y-63500D02*
Y-60167D01*
G01Y-61000D02*
X389017Y-60583D01*
X389517Y-60250D01*
X390183Y-60167D01*
X390767Y-60250D01*
X391267Y-60583D01*
X391517Y-61167D01*
Y-63500D01*
G01X397200Y-58500D02*
Y-63500D01*
G01Y-62750D02*
X396867Y-63167D01*
X396367Y-63417D01*
X395783Y-63500D01*
X395117Y-63333D01*
X394617Y-62917D01*
X394283Y-62417D01*
X394200Y-61833D01*
X394283Y-61250D01*
X394617Y-60750D01*
X395117Y-60333D01*
X395783Y-60167D01*
X396367Y-60250D01*
X396783Y-60417D01*
X397200Y-60750D01*
G01X405067Y-58500D02*
Y-62083D01*
X405400Y-62833D01*
X406067Y-63333D01*
X406900Y-63500D01*
X407733Y-63333D01*
X408400Y-62833D01*
X408733Y-62083D01*
Y-58500D01*
G01X410833D02*
Y-63500D01*
X414167D01*
G01X423200D02*
Y-59250D01*
X423367Y-58833D01*
X423700Y-58583D01*
X424200Y-58500D01*
X424700Y-58667D01*
X424950Y-59083D01*
G01X423950Y-60500D02*
X422283D01*
G01X429300Y-60167D02*
Y-63500D01*
G01Y-58833D02*
X429133Y-58750D01*
Y-58583D01*
X429300Y-58500D01*
X429467Y-58583D01*
Y-58750D01*
X429300Y-58833D01*
G01X434900Y-63500D02*
Y-58500D01*
G01X439250Y-61250D02*
X441917D01*
X441667Y-60667D01*
X441250Y-60333D01*
X440667Y-60167D01*
X440083Y-60250D01*
X439583Y-60500D01*
X439250Y-61083D01*
X439083Y-61583D01*
Y-62083D01*
X439250Y-62583D01*
X439667Y-63083D01*
X440167Y-63417D01*
X440750Y-63500D01*
X441333Y-63333D01*
X441917Y-62833D01*
G01X449783Y-63500D02*
Y-58500D01*
X453617Y-63500D01*
Y-58500D01*
G01X455883Y-60167D02*
Y-62500D01*
X456217Y-63083D01*
X456717Y-63417D01*
X457300Y-63500D01*
X457883Y-63417D01*
X458383Y-63083D01*
X458717Y-62500D01*
G01Y-63500D02*
Y-60167D01*
G01X460400Y-63500D02*
Y-60167D01*
G01Y-61083D02*
X460650Y-60667D01*
X461067Y-60333D01*
X461650Y-60167D01*
X462233Y-60333D01*
X462650Y-60667D01*
X462900Y-61083D01*
Y-63500D01*
G01Y-61083D02*
X463150Y-60667D01*
X463567Y-60333D01*
X464150Y-60167D01*
X464733Y-60333D01*
X465150Y-60667D01*
X465400Y-61167D01*
Y-63500D01*
G01X467000D02*
Y-58500D01*
G01Y-61000D02*
X467417Y-60500D01*
X467917Y-60250D01*
X468417Y-60167D01*
X469167Y-60333D01*
X469667Y-60667D01*
X470000Y-61250D01*
Y-61917D01*
X469833Y-62583D01*
X469500Y-63083D01*
X468917Y-63417D01*
X468417Y-63500D01*
X467917Y-63417D01*
X467417Y-63167D01*
X467000Y-62750D01*
G01X472850Y-61250D02*
X475517D01*
X475267Y-60667D01*
X474850Y-60333D01*
X474267Y-60167D01*
X473683Y-60250D01*
X473183Y-60500D01*
X472850Y-61083D01*
X472683Y-61583D01*
Y-62083D01*
X472850Y-62583D01*
X473267Y-63083D01*
X473767Y-63417D01*
X474350Y-63500D01*
X474933Y-63333D01*
X475517Y-62833D01*
G01X478533Y-63500D02*
Y-60167D01*
G01Y-60833D02*
X478950Y-60500D01*
X479367Y-60250D01*
X479950Y-60167D01*
X480367Y-60250D01*
X480867Y-60500D01*
G01X490900Y-60167D02*
Y-63500D01*
G01Y-58833D02*
X490733Y-58750D01*
Y-58583D01*
X490900Y-58500D01*
X491067Y-58583D01*
Y-58750D01*
X490900Y-58833D01*
G01X495083Y-63500D02*
Y-60167D01*
G01Y-61000D02*
X495417Y-60583D01*
X495917Y-60250D01*
X496583Y-60167D01*
X497167Y-60250D01*
X497667Y-60583D01*
X497917Y-61167D01*
Y-63500D01*
G01X506450Y-62917D02*
X506867Y-63250D01*
X507450Y-63500D01*
X507950D01*
X508450Y-63333D01*
X508783Y-63083D01*
X508950Y-62750D01*
X508867Y-62250D01*
X508533Y-62000D01*
X507033Y-61500D01*
X506700Y-60917D01*
X506867Y-60500D01*
X507200Y-60250D01*
X507700Y-60167D01*
X508200Y-60250D01*
X508700Y-60500D01*
G01X513300Y-60167D02*
Y-63500D01*
G01Y-58833D02*
X513133Y-58750D01*
Y-58583D01*
X513300Y-58500D01*
X513467Y-58583D01*
Y-58750D01*
X513300Y-58833D01*
G01X518900Y-63500D02*
Y-58500D01*
G01X523083Y-63500D02*
Y-58500D01*
G01X525750Y-60167D02*
X523083Y-62083D01*
G01X524167Y-61333D02*
X525917Y-63500D01*
G01X528850Y-62917D02*
X529267Y-63250D01*
X529850Y-63500D01*
X530350D01*
X530850Y-63333D01*
X531183Y-63083D01*
X531350Y-62750D01*
X531267Y-62250D01*
X530933Y-62000D01*
X529433Y-61500D01*
X529100Y-60917D01*
X529267Y-60500D01*
X529600Y-60250D01*
X530100Y-60167D01*
X530600Y-60250D01*
X531100Y-60500D01*
G01X537033Y-60583D02*
X536450Y-60250D01*
X535950Y-60167D01*
X535283Y-60333D01*
X534783Y-60667D01*
X534450Y-61250D01*
X534367Y-61833D01*
X534450Y-62417D01*
X534783Y-62917D01*
X535283Y-63333D01*
X535950Y-63500D01*
X536533Y-63333D01*
X537033Y-63000D01*
G01X540133Y-63500D02*
Y-60167D01*
G01Y-60833D02*
X540550Y-60500D01*
X540967Y-60250D01*
X541550Y-60167D01*
X541967Y-60250D01*
X542467Y-60500D01*
G01X545650Y-61250D02*
X548317D01*
X548067Y-60667D01*
X547650Y-60333D01*
X547067Y-60167D01*
X546483Y-60250D01*
X545983Y-60500D01*
X545650Y-61083D01*
X545483Y-61583D01*
Y-62083D01*
X545650Y-62583D01*
X546067Y-63083D01*
X546567Y-63417D01*
X547150Y-63500D01*
X547733Y-63333D01*
X548317Y-62833D01*
G01X551250Y-61250D02*
X553917D01*
X553667Y-60667D01*
X553250Y-60333D01*
X552667Y-60167D01*
X552083Y-60250D01*
X551583Y-60500D01*
X551250Y-61083D01*
X551083Y-61583D01*
Y-62083D01*
X551250Y-62583D01*
X551667Y-63083D01*
X552167Y-63417D01*
X552750Y-63500D01*
X553333Y-63333D01*
X553917Y-62833D01*
G01X556683Y-63500D02*
Y-60167D01*
G01Y-61000D02*
X557017Y-60583D01*
X557517Y-60250D01*
X558183Y-60167D01*
X558767Y-60250D01*
X559267Y-60583D01*
X559517Y-61167D01*
Y-63500D01*
G01X274000D02*
Y-60167D01*
G01Y-60750D02*
X273667Y-60417D01*
X273167Y-60250D01*
X272583Y-60167D01*
X272000Y-60333D01*
X271500Y-60667D01*
X271167Y-61167D01*
X271000Y-61833D01*
X271167Y-62500D01*
X271500Y-63000D01*
X272000Y-63333D01*
X272583Y-63500D01*
X273167Y-63417D01*
X273667Y-63167D01*
X274000Y-62833D01*
G01X279600Y-58500D02*
Y-63500D01*
G01Y-62750D02*
X279267Y-63167D01*
X278767Y-63417D01*
X278183Y-63500D01*
X277517Y-63333D01*
X277017Y-62917D01*
X276683Y-62417D01*
X276600Y-61833D01*
X276683Y-61250D01*
X277017Y-60750D01*
X277517Y-60333D01*
X278183Y-60167D01*
X278767Y-60250D01*
X279183Y-60417D01*
X279600Y-60750D01*
G01X285200Y-58500D02*
Y-63500D01*
G01Y-62750D02*
X284867Y-63167D01*
X284367Y-63417D01*
X283783Y-63500D01*
X283117Y-63333D01*
X282617Y-62917D01*
X282283Y-62417D01*
X282200Y-61833D01*
X282283Y-61250D01*
X282617Y-60750D01*
X283117Y-60333D01*
X283783Y-60167D01*
X284367Y-60250D01*
X284783Y-60417D01*
X285200Y-60750D01*
G01X293650Y-62917D02*
X294067Y-63250D01*
X294650Y-63500D01*
X295150D01*
X295650Y-63333D01*
X295983Y-63083D01*
X296150Y-62750D01*
X296067Y-62250D01*
X295733Y-62000D01*
X294233Y-61500D01*
X293900Y-60917D01*
X294067Y-60500D01*
X294400Y-60250D01*
X294900Y-60167D01*
X295400Y-60250D01*
X295900Y-60500D01*
G01X299083Y-60167D02*
Y-62500D01*
X299417Y-63083D01*
X299917Y-63417D01*
X300500Y-63500D01*
X301083Y-63417D01*
X301583Y-63083D01*
X301917Y-62500D01*
G01Y-63500D02*
Y-60167D01*
G01X304600Y-65167D02*
Y-60167D01*
G01Y-60917D02*
X305017Y-60500D01*
X305433Y-60250D01*
X306100Y-60167D01*
X306683Y-60250D01*
X307267Y-60667D01*
X307517Y-61250D01*
X307600Y-61833D01*
X307517Y-62417D01*
X307267Y-63000D01*
X306767Y-63333D01*
X306100Y-63500D01*
X305517Y-63417D01*
X304933Y-63167D01*
X304600Y-62833D01*
G01X310200Y-65167D02*
Y-60167D01*
G01Y-60917D02*
X310617Y-60500D01*
X311033Y-60250D01*
X311700Y-60167D01*
X312283Y-60250D01*
X312867Y-60667D01*
X313117Y-61250D01*
X313200Y-61833D01*
X313117Y-62417D01*
X312867Y-63000D01*
X312367Y-63333D01*
X311700Y-63500D01*
X311117Y-63417D01*
X310533Y-63167D01*
X310200Y-62833D01*
G01X317300Y-63500D02*
Y-58500D01*
G01X322900Y-60167D02*
Y-63500D01*
G01Y-58833D02*
X322733Y-58750D01*
Y-58583D01*
X322900Y-58500D01*
X323067Y-58583D01*
Y-58750D01*
X322900Y-58833D01*
G01X327250Y-61250D02*
X329917D01*
X329667Y-60667D01*
X329250Y-60333D01*
X328667Y-60167D01*
X328083Y-60250D01*
X327583Y-60500D01*
X327250Y-61083D01*
X327083Y-61583D01*
Y-62083D01*
X327250Y-62583D01*
X327667Y-63083D01*
X328167Y-63417D01*
X328750Y-63500D01*
X329333Y-63333D01*
X329917Y-62833D01*
G01X332933Y-63500D02*
Y-60167D01*
G01Y-60833D02*
X333350Y-60500D01*
X333767Y-60250D01*
X334350Y-60167D01*
X334767Y-60250D01*
X335267Y-60500D01*
G01X339700Y-60167D02*
X340533Y-59125D01*
Y-58500D01*
X339908D01*
Y-59125D01*
X340533D01*
G01X344050Y-62917D02*
X344467Y-63250D01*
X345050Y-63500D01*
X345550D01*
X346050Y-63333D01*
X346383Y-63083D01*
X346550Y-62750D01*
X346467Y-62250D01*
X346133Y-62000D01*
X344633Y-61500D01*
X344300Y-60917D01*
X344467Y-60500D01*
X344800Y-60250D01*
X345300Y-60167D01*
X345800Y-60250D01*
X346300Y-60500D01*
G01X354833Y-58500D02*
Y-63500D01*
X358167D01*
G01X362100D02*
X361600Y-63417D01*
X361100Y-63083D01*
X360767Y-62500D01*
X360600Y-61833D01*
X360767Y-61167D01*
X361100Y-60583D01*
X361600Y-60250D01*
X362100Y-60167D01*
X362600Y-60250D01*
X363100Y-60583D01*
X363433Y-61167D01*
X363517Y-61833D01*
X363433Y-62500D01*
X363100Y-63083D01*
X362600Y-63417D01*
X362100Y-63500D01*
G01X366533Y-64750D02*
X367117Y-65083D01*
X367783Y-65167D01*
X368367Y-65083D01*
X368867Y-64667D01*
X369200Y-64083D01*
Y-60167D01*
G01Y-60833D02*
X368867Y-60500D01*
X368367Y-60250D01*
X367783Y-60167D01*
X367117Y-60333D01*
X366700Y-60667D01*
X366367Y-61250D01*
X366200Y-61833D01*
X366283Y-62333D01*
X366617Y-62917D01*
X367117Y-63333D01*
X367783Y-63500D01*
X368283Y-63417D01*
X368867Y-63083D01*
X369200Y-62750D01*
G01X373300Y-63500D02*
X372800Y-63417D01*
X372300Y-63083D01*
X371967Y-62500D01*
X371800Y-61833D01*
X371967Y-61167D01*
X372300Y-60583D01*
X372800Y-60250D01*
X373300Y-60167D01*
X373800Y-60250D01*
X374300Y-60583D01*
X374633Y-61167D01*
X374717Y-61833D01*
X374633Y-62500D01*
X374300Y-63083D01*
X373800Y-63417D01*
X373300Y-63500D01*
G01X386000D02*
Y-60167D01*
G01Y-60750D02*
X385667Y-60417D01*
X385167Y-60250D01*
X384583Y-60167D01*
X384000Y-60333D01*
X383500Y-60667D01*
X383167Y-61167D01*
X383000Y-61833D01*
X383167Y-62500D01*
X383500Y-63000D01*
X384000Y-63333D01*
X384583Y-63500D01*
X385167Y-63417D01*
X385667Y-63167D01*
X386000Y-62833D01*
G01X388683Y-63500D02*
Y-60167D01*
G01Y-61000D02*
X389017Y-60583D01*
X389517Y-60250D01*
X390183Y-60167D01*
X390767Y-60250D01*
X391267Y-60583D01*
X391517Y-61167D01*
Y-63500D01*
G01X397200Y-58500D02*
Y-63500D01*
G01Y-62750D02*
X396867Y-63167D01*
X396367Y-63417D01*
X395783Y-63500D01*
X395117Y-63333D01*
X394617Y-62917D01*
X394283Y-62417D01*
X394200Y-61833D01*
X394283Y-61250D01*
X394617Y-60750D01*
X395117Y-60333D01*
X395783Y-60167D01*
X396367Y-60250D01*
X396783Y-60417D01*
X397200Y-60750D01*
G01X405067Y-58500D02*
Y-62083D01*
X405400Y-62833D01*
X406067Y-63333D01*
X406900Y-63500D01*
X407733Y-63333D01*
X408400Y-62833D01*
X408733Y-62083D01*
Y-58500D01*
G01X410833D02*
Y-63500D01*
X414167D01*
G01X423200D02*
Y-59250D01*
X423367Y-58833D01*
X423700Y-58583D01*
X424200Y-58500D01*
X424700Y-58667D01*
X424950Y-59083D01*
G01X423950Y-60500D02*
X422283D01*
G01X429300Y-60167D02*
Y-63500D01*
G01Y-58833D02*
X429133Y-58750D01*
Y-58583D01*
X429300Y-58500D01*
X429467Y-58583D01*
Y-58750D01*
X429300Y-58833D01*
G01X434900Y-63500D02*
Y-58500D01*
G01X439250Y-61250D02*
X441917D01*
X441667Y-60667D01*
X441250Y-60333D01*
X440667Y-60167D01*
X440083Y-60250D01*
X439583Y-60500D01*
X439250Y-61083D01*
X439083Y-61583D01*
Y-62083D01*
X439250Y-62583D01*
X439667Y-63083D01*
X440167Y-63417D01*
X440750Y-63500D01*
X441333Y-63333D01*
X441917Y-62833D01*
G01X449783Y-63500D02*
Y-58500D01*
X453617Y-63500D01*
Y-58500D01*
G01X455883Y-60167D02*
Y-62500D01*
X456217Y-63083D01*
X456717Y-63417D01*
X457300Y-63500D01*
X457883Y-63417D01*
X458383Y-63083D01*
X458717Y-62500D01*
G01Y-63500D02*
Y-60167D01*
G01X460400Y-63500D02*
Y-60167D01*
G01Y-61083D02*
X460650Y-60667D01*
X461067Y-60333D01*
X461650Y-60167D01*
X462233Y-60333D01*
X462650Y-60667D01*
X462900Y-61083D01*
Y-63500D01*
G01Y-61083D02*
X463150Y-60667D01*
X463567Y-60333D01*
X464150Y-60167D01*
X464733Y-60333D01*
X465150Y-60667D01*
X465400Y-61167D01*
Y-63500D01*
G01X467000D02*
Y-58500D01*
G01Y-61000D02*
X467417Y-60500D01*
X467917Y-60250D01*
X468417Y-60167D01*
X469167Y-60333D01*
X469667Y-60667D01*
X470000Y-61250D01*
Y-61917D01*
X469833Y-62583D01*
X469500Y-63083D01*
X468917Y-63417D01*
X468417Y-63500D01*
X467917Y-63417D01*
X467417Y-63167D01*
X467000Y-62750D01*
G01X472850Y-61250D02*
X475517D01*
X475267Y-60667D01*
X474850Y-60333D01*
X474267Y-60167D01*
X473683Y-60250D01*
X473183Y-60500D01*
X472850Y-61083D01*
X472683Y-61583D01*
Y-62083D01*
X472850Y-62583D01*
X473267Y-63083D01*
X473767Y-63417D01*
X474350Y-63500D01*
X474933Y-63333D01*
X475517Y-62833D01*
G01X478533Y-63500D02*
Y-60167D01*
G01Y-60833D02*
X478950Y-60500D01*
X479367Y-60250D01*
X479950Y-60167D01*
X480367Y-60250D01*
X480867Y-60500D01*
G01X490900Y-60167D02*
Y-63500D01*
G01Y-58833D02*
X490733Y-58750D01*
Y-58583D01*
X490900Y-58500D01*
X491067Y-58583D01*
Y-58750D01*
X490900Y-58833D01*
G01X495083Y-63500D02*
Y-60167D01*
G01Y-61000D02*
X495417Y-60583D01*
X495917Y-60250D01*
X496583Y-60167D01*
X497167Y-60250D01*
X497667Y-60583D01*
X497917Y-61167D01*
Y-63500D01*
G01X506450Y-62917D02*
X506867Y-63250D01*
X507450Y-63500D01*
X507950D01*
X508450Y-63333D01*
X508783Y-63083D01*
X508950Y-62750D01*
X508867Y-62250D01*
X508533Y-62000D01*
X507033Y-61500D01*
X506700Y-60917D01*
X506867Y-60500D01*
X507200Y-60250D01*
X507700Y-60167D01*
X508200Y-60250D01*
X508700Y-60500D01*
G01X513300Y-60167D02*
Y-63500D01*
G01Y-58833D02*
X513133Y-58750D01*
Y-58583D01*
X513300Y-58500D01*
X513467Y-58583D01*
Y-58750D01*
X513300Y-58833D01*
G01X518900Y-63500D02*
Y-58500D01*
G01X523083Y-63500D02*
Y-58500D01*
G01X525750Y-60167D02*
X523083Y-62083D01*
G01X524167Y-61333D02*
X525917Y-63500D01*
G01X528850Y-62917D02*
X529267Y-63250D01*
X529850Y-63500D01*
X530350D01*
X530850Y-63333D01*
X531183Y-63083D01*
X531350Y-62750D01*
X531267Y-62250D01*
X530933Y-62000D01*
X529433Y-61500D01*
X529100Y-60917D01*
X529267Y-60500D01*
X529600Y-60250D01*
X530100Y-60167D01*
X530600Y-60250D01*
X531100Y-60500D01*
G01X537033Y-60583D02*
X536450Y-60250D01*
X535950Y-60167D01*
X535283Y-60333D01*
X534783Y-60667D01*
X534450Y-61250D01*
X534367Y-61833D01*
X534450Y-62417D01*
X534783Y-62917D01*
X535283Y-63333D01*
X535950Y-63500D01*
X536533Y-63333D01*
X537033Y-63000D01*
G01X540133Y-63500D02*
Y-60167D01*
G01Y-60833D02*
X540550Y-60500D01*
X540967Y-60250D01*
X541550Y-60167D01*
X541967Y-60250D01*
X542467Y-60500D01*
G01X545650Y-61250D02*
X548317D01*
X548067Y-60667D01*
X547650Y-60333D01*
X547067Y-60167D01*
X546483Y-60250D01*
X545983Y-60500D01*
X545650Y-61083D01*
X545483Y-61583D01*
Y-62083D01*
X545650Y-62583D01*
X546067Y-63083D01*
X546567Y-63417D01*
X547150Y-63500D01*
X547733Y-63333D01*
X548317Y-62833D01*
G01X551250Y-61250D02*
X553917D01*
X553667Y-60667D01*
X553250Y-60333D01*
X552667Y-60167D01*
X552083Y-60250D01*
X551583Y-60500D01*
X551250Y-61083D01*
X551083Y-61583D01*
Y-62083D01*
X551250Y-62583D01*
X551667Y-63083D01*
X552167Y-63417D01*
X552750Y-63500D01*
X553333Y-63333D01*
X553917Y-62833D01*
G01X556683Y-63500D02*
Y-60167D01*
G01Y-61000D02*
X557017Y-60583D01*
X557517Y-60250D01*
X558183Y-60167D01*
X558767Y-60250D01*
X559267Y-60583D01*
X559517Y-61167D01*
Y-63500D01*
G01X272500Y0D02*
Y-5000D01*
G01X270583Y0D02*
X274417D01*
G01X276683Y-5000D02*
Y0D01*
G01Y-2417D02*
X277100Y-2000D01*
X277517Y-1750D01*
X278183Y-1667D01*
X278683Y-1750D01*
X279267Y-2083D01*
X279517Y-2583D01*
Y-5000D01*
G01X282450Y-2750D02*
X285117D01*
X284867Y-2167D01*
X284450Y-1833D01*
X283867Y-1667D01*
X283283Y-1750D01*
X282783Y-2000D01*
X282450Y-2583D01*
X282283Y-3083D01*
Y-3583D01*
X282450Y-4083D01*
X282867Y-4583D01*
X283367Y-4917D01*
X283950Y-5000D01*
X284533Y-4833D01*
X285117Y-4333D01*
G01X294900Y-5000D02*
Y0D01*
G01X302000Y-5000D02*
Y-1667D01*
G01Y-2250D02*
X301667Y-1917D01*
X301167Y-1750D01*
X300583Y-1667D01*
X300000Y-1833D01*
X299500Y-2167D01*
X299167Y-2667D01*
X299000Y-3333D01*
X299167Y-4000D01*
X299500Y-4500D01*
X300000Y-4833D01*
X300583Y-5000D01*
X301167Y-4917D01*
X301667Y-4667D01*
X302000Y-4333D01*
G01X304933Y-5000D02*
Y-1667D01*
G01Y-2333D02*
X305350Y-2000D01*
X305767Y-1750D01*
X306350Y-1667D01*
X306767Y-1750D01*
X307267Y-2000D01*
G01X310533Y-6250D02*
X311117Y-6583D01*
X311783Y-6667D01*
X312367Y-6583D01*
X312867Y-6167D01*
X313200Y-5583D01*
Y-1667D01*
G01Y-2333D02*
X312867Y-2000D01*
X312367Y-1750D01*
X311783Y-1667D01*
X311117Y-1833D01*
X310700Y-2167D01*
X310367Y-2750D01*
X310200Y-3333D01*
X310283Y-3833D01*
X310617Y-4417D01*
X311117Y-4833D01*
X311783Y-5000D01*
X312283Y-4917D01*
X312867Y-4583D01*
X313200Y-4250D01*
G01X316050Y-2750D02*
X318717D01*
X318467Y-2167D01*
X318050Y-1833D01*
X317467Y-1667D01*
X316883Y-1750D01*
X316383Y-2000D01*
X316050Y-2583D01*
X315883Y-3083D01*
Y-3583D01*
X316050Y-4083D01*
X316467Y-4583D01*
X316967Y-4917D01*
X317550Y-5000D01*
X318133Y-4833D01*
X318717Y-4333D01*
G01X321650Y-4417D02*
X322067Y-4750D01*
X322650Y-5000D01*
X323150D01*
X323650Y-4833D01*
X323983Y-4583D01*
X324150Y-4250D01*
X324067Y-3750D01*
X323733Y-3500D01*
X322233Y-3000D01*
X321900Y-2417D01*
X322067Y-2000D01*
X322400Y-1750D01*
X322900Y-1667D01*
X323400Y-1750D01*
X323900Y-2000D01*
G01X328500Y0D02*
Y-5000D01*
G01X327333Y-1667D02*
X329667D01*
G01X341200Y0D02*
Y-5000D01*
G01Y-4250D02*
X340867Y-4667D01*
X340367Y-4917D01*
X339783Y-5000D01*
X339117Y-4833D01*
X338617Y-4417D01*
X338283Y-3917D01*
X338200Y-3333D01*
X338283Y-2750D01*
X338617Y-2250D01*
X339117Y-1833D01*
X339783Y-1667D01*
X340367Y-1750D01*
X340783Y-1917D01*
X341200Y-2250D01*
G01X345300Y-1667D02*
Y-5000D01*
G01Y-333D02*
X345133Y-250D01*
Y-83D01*
X345300Y0D01*
X345467Y-83D01*
Y-250D01*
X345300Y-333D01*
G01X348400Y-5000D02*
Y-1667D01*
G01Y-2583D02*
X348650Y-2167D01*
X349067Y-1833D01*
X349650Y-1667D01*
X350233Y-1833D01*
X350650Y-2167D01*
X350900Y-2583D01*
Y-5000D01*
G01Y-2583D02*
X351150Y-2167D01*
X351567Y-1833D01*
X352150Y-1667D01*
X352733Y-1833D01*
X353150Y-2167D01*
X353400Y-2667D01*
Y-5000D01*
G01X355250Y-2750D02*
X357917D01*
X357667Y-2167D01*
X357250Y-1833D01*
X356667Y-1667D01*
X356083Y-1750D01*
X355583Y-2000D01*
X355250Y-2583D01*
X355083Y-3083D01*
Y-3583D01*
X355250Y-4083D01*
X355667Y-4583D01*
X356167Y-4917D01*
X356750Y-5000D01*
X357333Y-4833D01*
X357917Y-4333D01*
G01X360683Y-5000D02*
Y-1667D01*
G01Y-2500D02*
X361017Y-2083D01*
X361517Y-1750D01*
X362183Y-1667D01*
X362767Y-1750D01*
X363267Y-2083D01*
X363517Y-2667D01*
Y-5000D01*
G01X366450Y-4417D02*
X366867Y-4750D01*
X367450Y-5000D01*
X367950D01*
X368450Y-4833D01*
X368783Y-4583D01*
X368950Y-4250D01*
X368867Y-3750D01*
X368533Y-3500D01*
X367033Y-3000D01*
X366700Y-2417D01*
X366867Y-2000D01*
X367200Y-1750D01*
X367700Y-1667D01*
X368200Y-1750D01*
X368700Y-2000D01*
G01X373300Y-1667D02*
Y-5000D01*
G01Y-333D02*
X373133Y-250D01*
Y-83D01*
X373300Y0D01*
X373467Y-83D01*
Y-250D01*
X373300Y-333D01*
G01X378900Y-5000D02*
X378400Y-4917D01*
X377900Y-4583D01*
X377567Y-4000D01*
X377400Y-3333D01*
X377567Y-2667D01*
X377900Y-2083D01*
X378400Y-1750D01*
X378900Y-1667D01*
X379400Y-1750D01*
X379900Y-2083D01*
X380233Y-2667D01*
X380317Y-3333D01*
X380233Y-4000D01*
X379900Y-4583D01*
X379400Y-4917D01*
X378900Y-5000D01*
G01X383083D02*
Y-1667D01*
G01Y-2500D02*
X383417Y-2083D01*
X383917Y-1750D01*
X384583Y-1667D01*
X385167Y-1750D01*
X385667Y-2083D01*
X385917Y-2667D01*
Y-5000D01*
G01X395700D02*
X395200Y-4917D01*
X394700Y-4583D01*
X394367Y-4000D01*
X394200Y-3333D01*
X394367Y-2667D01*
X394700Y-2083D01*
X395200Y-1750D01*
X395700Y-1667D01*
X396200Y-1750D01*
X396700Y-2083D01*
X397033Y-2667D01*
X397117Y-3333D01*
X397033Y-4000D01*
X396700Y-4583D01*
X396200Y-4917D01*
X395700Y-5000D01*
G01X400800D02*
Y-750D01*
X400967Y-333D01*
X401300Y-83D01*
X401800Y0D01*
X402300Y-167D01*
X402550Y-583D01*
G01X401550Y-2000D02*
X399883D01*
G01X411000Y-6667D02*
Y-1667D01*
G01Y-2417D02*
X411417Y-2000D01*
X411833Y-1750D01*
X412500Y-1667D01*
X413083Y-1750D01*
X413667Y-2167D01*
X413917Y-2750D01*
X414000Y-3333D01*
X413917Y-3917D01*
X413667Y-4500D01*
X413167Y-4833D01*
X412500Y-5000D01*
X411917Y-4917D01*
X411333Y-4667D01*
X411000Y-4333D01*
G01X419600Y-5000D02*
Y-1667D01*
G01Y-2250D02*
X419267Y-1917D01*
X418767Y-1750D01*
X418183Y-1667D01*
X417600Y-1833D01*
X417100Y-2167D01*
X416767Y-2667D01*
X416600Y-3333D01*
X416767Y-4000D01*
X417100Y-4500D01*
X417600Y-4833D01*
X418183Y-5000D01*
X418767Y-4917D01*
X419267Y-4667D01*
X419600Y-4333D01*
G01X425200Y0D02*
Y-5000D01*
G01Y-4250D02*
X424867Y-4667D01*
X424367Y-4917D01*
X423783Y-5000D01*
X423117Y-4833D01*
X422617Y-4417D01*
X422283Y-3917D01*
X422200Y-3333D01*
X422283Y-2750D01*
X422617Y-2250D01*
X423117Y-1833D01*
X423783Y-1667D01*
X424367Y-1750D01*
X424783Y-1917D01*
X425200Y-2250D01*
G01X434900Y-5000D02*
X434400Y-4917D01*
X433900Y-4583D01*
X433567Y-4000D01*
X433400Y-3333D01*
X433567Y-2667D01*
X433900Y-2083D01*
X434400Y-1750D01*
X434900Y-1667D01*
X435400Y-1750D01*
X435900Y-2083D01*
X436233Y-2667D01*
X436317Y-3333D01*
X436233Y-4000D01*
X435900Y-4583D01*
X435400Y-4917D01*
X434900Y-5000D01*
G01X439333D02*
Y-1667D01*
G01Y-2333D02*
X439750Y-2000D01*
X440167Y-1750D01*
X440750Y-1667D01*
X441167Y-1750D01*
X441667Y-2000D01*
G01X453200Y0D02*
Y-5000D01*
G01Y-4250D02*
X452867Y-4667D01*
X452367Y-4917D01*
X451783Y-5000D01*
X451117Y-4833D01*
X450617Y-4417D01*
X450283Y-3917D01*
X450200Y-3333D01*
X450283Y-2750D01*
X450617Y-2250D01*
X451117Y-1833D01*
X451783Y-1667D01*
X452367Y-1750D01*
X452783Y-1917D01*
X453200Y-2250D01*
G01X457300Y-1667D02*
Y-5000D01*
G01Y-333D02*
X457133Y-250D01*
Y-83D01*
X457300Y0D01*
X457467Y-83D01*
Y-250D01*
X457300Y-333D01*
G01X464400Y-5000D02*
Y-1667D01*
G01Y-2250D02*
X464067Y-1917D01*
X463567Y-1750D01*
X462983Y-1667D01*
X462400Y-1833D01*
X461900Y-2167D01*
X461567Y-2667D01*
X461400Y-3333D01*
X461567Y-4000D01*
X461900Y-4500D01*
X462400Y-4833D01*
X462983Y-5000D01*
X463567Y-4917D01*
X464067Y-4667D01*
X464400Y-4333D01*
G01X466000Y-5000D02*
Y-1667D01*
G01Y-2583D02*
X466250Y-2167D01*
X466667Y-1833D01*
X467250Y-1667D01*
X467833Y-1833D01*
X468250Y-2167D01*
X468500Y-2583D01*
Y-5000D01*
G01Y-2583D02*
X468750Y-2167D01*
X469167Y-1833D01*
X469750Y-1667D01*
X470333Y-1833D01*
X470750Y-2167D01*
X471000Y-2667D01*
Y-5000D01*
G01X472850Y-2750D02*
X475517D01*
X475267Y-2167D01*
X474850Y-1833D01*
X474267Y-1667D01*
X473683Y-1750D01*
X473183Y-2000D01*
X472850Y-2583D01*
X472683Y-3083D01*
Y-3583D01*
X472850Y-4083D01*
X473267Y-4583D01*
X473767Y-4917D01*
X474350Y-5000D01*
X474933Y-4833D01*
X475517Y-4333D01*
G01X479700Y0D02*
Y-5000D01*
G01X478533Y-1667D02*
X480867D01*
G01X484050Y-2750D02*
X486717D01*
X486467Y-2167D01*
X486050Y-1833D01*
X485467Y-1667D01*
X484883Y-1750D01*
X484383Y-2000D01*
X484050Y-2583D01*
X483883Y-3083D01*
Y-3583D01*
X484050Y-4083D01*
X484467Y-4583D01*
X484967Y-4917D01*
X485550Y-5000D01*
X486133Y-4833D01*
X486717Y-4333D01*
G01X489733Y-5000D02*
Y-1667D01*
G01Y-2333D02*
X490150Y-2000D01*
X490567Y-1750D01*
X491150Y-1667D01*
X491567Y-1750D01*
X492067Y-2000D01*
G01X503767Y-5000D02*
X500433Y-3333D01*
X503767Y-1667D01*
G01X506617Y-4083D02*
X508783D01*
G01Y-2583D02*
X506617D01*
G01X518900Y-5000D02*
Y0D01*
X517900Y-1000D01*
G01Y-5000D02*
X519900D01*
G01X525500D02*
Y0D01*
X522417Y-3583D01*
X526583D01*
G01X533200Y-5000D02*
Y-1667D01*
G01Y-2583D02*
X533450Y-2167D01*
X533867Y-1833D01*
X534450Y-1667D01*
X535033Y-1833D01*
X535450Y-2167D01*
X535700Y-2583D01*
Y-5000D01*
G01Y-2583D02*
X535950Y-2167D01*
X536367Y-1833D01*
X536950Y-1667D01*
X537533Y-1833D01*
X537950Y-2167D01*
X538200Y-2667D01*
Y-5000D01*
G01X541300Y-1667D02*
Y-5000D01*
G01Y-333D02*
X541133Y-250D01*
Y-83D01*
X541300Y0D01*
X541467Y-83D01*
Y-250D01*
X541300Y-333D01*
G01X546900Y-5000D02*
Y0D01*
G01X270750Y-47833D02*
X271417Y-48250D01*
X272167Y-48500D01*
X272833D01*
X273500Y-48250D01*
X274000Y-47833D01*
X274250Y-47250D01*
X274083Y-46667D01*
X273667Y-46167D01*
X272917Y-45833D01*
X271917Y-45667D01*
X271333Y-45333D01*
X271083Y-44750D01*
X271250Y-44167D01*
X271667Y-43750D01*
X272250Y-43500D01*
X272833D01*
X273417Y-43667D01*
X273917Y-44083D01*
G01X278100Y-48500D02*
X277600Y-48417D01*
X277100Y-48083D01*
X276767Y-47500D01*
X276600Y-46833D01*
X276767Y-46167D01*
X277100Y-45583D01*
X277600Y-45250D01*
X278100Y-45167D01*
X278600Y-45250D01*
X279100Y-45583D01*
X279433Y-46167D01*
X279517Y-46833D01*
X279433Y-47500D01*
X279100Y-48083D01*
X278600Y-48417D01*
X278100Y-48500D01*
G01X283700D02*
Y-43500D01*
G01X290800D02*
Y-48500D01*
G01Y-47750D02*
X290467Y-48167D01*
X289967Y-48417D01*
X289383Y-48500D01*
X288717Y-48333D01*
X288217Y-47917D01*
X287883Y-47417D01*
X287800Y-46833D01*
X287883Y-46250D01*
X288217Y-45750D01*
X288717Y-45333D01*
X289383Y-45167D01*
X289967Y-45250D01*
X290383Y-45417D01*
X290800Y-45750D01*
G01X293650Y-46250D02*
X296317D01*
X296067Y-45667D01*
X295650Y-45333D01*
X295067Y-45167D01*
X294483Y-45250D01*
X293983Y-45500D01*
X293650Y-46083D01*
X293483Y-46583D01*
Y-47083D01*
X293650Y-47583D01*
X294067Y-48083D01*
X294567Y-48417D01*
X295150Y-48500D01*
X295733Y-48333D01*
X296317Y-47833D01*
G01X299333Y-48500D02*
Y-45167D01*
G01Y-45833D02*
X299750Y-45500D01*
X300167Y-45250D01*
X300750Y-45167D01*
X301167Y-45250D01*
X301667Y-45500D01*
G01X309200Y-48500D02*
Y-45167D01*
G01Y-46083D02*
X309450Y-45667D01*
X309867Y-45333D01*
X310450Y-45167D01*
X311033Y-45333D01*
X311450Y-45667D01*
X311700Y-46083D01*
Y-48500D01*
G01Y-46083D02*
X311950Y-45667D01*
X312367Y-45333D01*
X312950Y-45167D01*
X313533Y-45333D01*
X313950Y-45667D01*
X314200Y-46167D01*
Y-48500D01*
G01X318800D02*
Y-45167D01*
G01Y-45750D02*
X318467Y-45417D01*
X317967Y-45250D01*
X317383Y-45167D01*
X316800Y-45333D01*
X316300Y-45667D01*
X315967Y-46167D01*
X315800Y-46833D01*
X315967Y-47500D01*
X316300Y-48000D01*
X316800Y-48333D01*
X317383Y-48500D01*
X317967Y-48417D01*
X318467Y-48167D01*
X318800Y-47833D01*
G01X321650Y-47917D02*
X322067Y-48250D01*
X322650Y-48500D01*
X323150D01*
X323650Y-48333D01*
X323983Y-48083D01*
X324150Y-47750D01*
X324067Y-47250D01*
X323733Y-47000D01*
X322233Y-46500D01*
X321900Y-45917D01*
X322067Y-45500D01*
X322400Y-45250D01*
X322900Y-45167D01*
X323400Y-45250D01*
X323900Y-45500D01*
G01X327083Y-48500D02*
Y-43500D01*
G01X329750Y-45167D02*
X327083Y-47083D01*
G01X328167Y-46333D02*
X329917Y-48500D01*
G01X339700Y-43500D02*
Y-48500D01*
G01X338533Y-45167D02*
X340867D01*
G01X343883Y-48500D02*
Y-43500D01*
G01Y-45917D02*
X344300Y-45500D01*
X344717Y-45250D01*
X345383Y-45167D01*
X345883Y-45250D01*
X346467Y-45583D01*
X346717Y-46083D01*
Y-48500D01*
G01X350900Y-45167D02*
Y-48500D01*
G01Y-43833D02*
X350733Y-43750D01*
Y-43583D01*
X350900Y-43500D01*
X351067Y-43583D01*
Y-43750D01*
X350900Y-43833D01*
G01X357833Y-45583D02*
X357250Y-45250D01*
X356750Y-45167D01*
X356083Y-45333D01*
X355583Y-45667D01*
X355250Y-46250D01*
X355167Y-46833D01*
X355250Y-47417D01*
X355583Y-47917D01*
X356083Y-48333D01*
X356750Y-48500D01*
X357333Y-48333D01*
X357833Y-48000D01*
G01X360683Y-48500D02*
Y-43500D01*
G01X363350Y-45167D02*
X360683Y-47083D01*
G01X361767Y-46333D02*
X363517Y-48500D01*
G01X366283D02*
Y-45167D01*
G01Y-46000D02*
X366617Y-45583D01*
X367117Y-45250D01*
X367783Y-45167D01*
X368367Y-45250D01*
X368867Y-45583D01*
X369117Y-46167D01*
Y-48500D01*
G01X372050Y-46250D02*
X374717D01*
X374467Y-45667D01*
X374050Y-45333D01*
X373467Y-45167D01*
X372883Y-45250D01*
X372383Y-45500D01*
X372050Y-46083D01*
X371883Y-46583D01*
Y-47083D01*
X372050Y-47583D01*
X372467Y-48083D01*
X372967Y-48417D01*
X373550Y-48500D01*
X374133Y-48333D01*
X374717Y-47833D01*
G01X377650Y-47917D02*
X378067Y-48250D01*
X378650Y-48500D01*
X379150D01*
X379650Y-48333D01*
X379983Y-48083D01*
X380150Y-47750D01*
X380067Y-47250D01*
X379733Y-47000D01*
X378233Y-46500D01*
X377900Y-45917D01*
X378067Y-45500D01*
X378400Y-45250D01*
X378900Y-45167D01*
X379400Y-45250D01*
X379900Y-45500D01*
G01X383250Y-47917D02*
X383667Y-48250D01*
X384250Y-48500D01*
X384750D01*
X385250Y-48333D01*
X385583Y-48083D01*
X385750Y-47750D01*
X385667Y-47250D01*
X385333Y-47000D01*
X383833Y-46500D01*
X383500Y-45917D01*
X383667Y-45500D01*
X384000Y-45250D01*
X384500Y-45167D01*
X385000Y-45250D01*
X385500Y-45500D01*
G01X394200Y-50167D02*
Y-45167D01*
G01Y-45917D02*
X394617Y-45500D01*
X395033Y-45250D01*
X395700Y-45167D01*
X396283Y-45250D01*
X396867Y-45667D01*
X397117Y-46250D01*
X397200Y-46833D01*
X397117Y-47417D01*
X396867Y-48000D01*
X396367Y-48333D01*
X395700Y-48500D01*
X395117Y-48417D01*
X394533Y-48167D01*
X394200Y-47833D01*
G01X401300Y-48500D02*
Y-43500D01*
G01X405483Y-45167D02*
Y-47500D01*
X405817Y-48083D01*
X406317Y-48417D01*
X406900Y-48500D01*
X407483Y-48417D01*
X407983Y-48083D01*
X408317Y-47500D01*
G01Y-48500D02*
Y-45167D01*
G01X411250Y-47917D02*
X411667Y-48250D01*
X412250Y-48500D01*
X412750D01*
X413250Y-48333D01*
X413583Y-48083D01*
X413750Y-47750D01*
X413667Y-47250D01*
X413333Y-47000D01*
X411833Y-46500D01*
X411500Y-45917D01*
X411667Y-45500D01*
X412000Y-45250D01*
X412500Y-45167D01*
X413000Y-45250D01*
X413500Y-45500D01*
G01X423700Y-48500D02*
Y-43500D01*
G01X428050Y-46250D02*
X430717D01*
X430467Y-45667D01*
X430050Y-45333D01*
X429467Y-45167D01*
X428883Y-45250D01*
X428383Y-45500D01*
X428050Y-46083D01*
X427883Y-46583D01*
Y-47083D01*
X428050Y-47583D01*
X428467Y-48083D01*
X428967Y-48417D01*
X429550Y-48500D01*
X430133Y-48333D01*
X430717Y-47833D01*
G01X433733Y-49750D02*
X434317Y-50083D01*
X434983Y-50167D01*
X435567Y-50083D01*
X436067Y-49667D01*
X436400Y-49083D01*
Y-45167D01*
G01Y-45833D02*
X436067Y-45500D01*
X435567Y-45250D01*
X434983Y-45167D01*
X434317Y-45333D01*
X433900Y-45667D01*
X433567Y-46250D01*
X433400Y-46833D01*
X433483Y-47333D01*
X433817Y-47917D01*
X434317Y-48333D01*
X434983Y-48500D01*
X435483Y-48417D01*
X436067Y-48083D01*
X436400Y-47750D01*
G01X439250Y-46250D02*
X441917D01*
X441667Y-45667D01*
X441250Y-45333D01*
X440667Y-45167D01*
X440083Y-45250D01*
X439583Y-45500D01*
X439250Y-46083D01*
X439083Y-46583D01*
Y-47083D01*
X439250Y-47583D01*
X439667Y-48083D01*
X440167Y-48417D01*
X440750Y-48500D01*
X441333Y-48333D01*
X441917Y-47833D01*
G01X444683Y-48500D02*
Y-45167D01*
G01Y-46000D02*
X445017Y-45583D01*
X445517Y-45250D01*
X446183Y-45167D01*
X446767Y-45250D01*
X447267Y-45583D01*
X447517Y-46167D01*
Y-48500D01*
G01X453200Y-43500D02*
Y-48500D01*
G01Y-47750D02*
X452867Y-48167D01*
X452367Y-48417D01*
X451783Y-48500D01*
X451117Y-48333D01*
X450617Y-47917D01*
X450283Y-47417D01*
X450200Y-46833D01*
X450283Y-46250D01*
X450617Y-45750D01*
X451117Y-45333D01*
X451783Y-45167D01*
X452367Y-45250D01*
X452783Y-45417D01*
X453200Y-45750D01*
G01X462900Y-43500D02*
Y-48500D01*
G01X461733Y-45167D02*
X464067D01*
G01X467083Y-48500D02*
Y-43500D01*
G01Y-45917D02*
X467500Y-45500D01*
X467917Y-45250D01*
X468583Y-45167D01*
X469083Y-45250D01*
X469667Y-45583D01*
X469917Y-46083D01*
Y-48500D01*
G01X474100Y-45167D02*
Y-48500D01*
G01Y-43833D02*
X473933Y-43750D01*
Y-43583D01*
X474100Y-43500D01*
X474267Y-43583D01*
Y-43750D01*
X474100Y-43833D01*
G01X481033Y-45583D02*
X480450Y-45250D01*
X479950Y-45167D01*
X479283Y-45333D01*
X478783Y-45667D01*
X478450Y-46250D01*
X478367Y-46833D01*
X478450Y-47417D01*
X478783Y-47917D01*
X479283Y-48333D01*
X479950Y-48500D01*
X480533Y-48333D01*
X481033Y-48000D01*
G01X483883Y-48500D02*
Y-43500D01*
G01X486550Y-45167D02*
X483883Y-47083D01*
G01X484967Y-46333D02*
X486717Y-48500D01*
G01X489483D02*
Y-45167D01*
G01Y-46000D02*
X489817Y-45583D01*
X490317Y-45250D01*
X490983Y-45167D01*
X491567Y-45250D01*
X492067Y-45583D01*
X492317Y-46167D01*
Y-48500D01*
G01X495250Y-46250D02*
X497917D01*
X497667Y-45667D01*
X497250Y-45333D01*
X496667Y-45167D01*
X496083Y-45250D01*
X495583Y-45500D01*
X495250Y-46083D01*
X495083Y-46583D01*
Y-47083D01*
X495250Y-47583D01*
X495667Y-48083D01*
X496167Y-48417D01*
X496750Y-48500D01*
X497333Y-48333D01*
X497917Y-47833D01*
G01X500850Y-47917D02*
X501267Y-48250D01*
X501850Y-48500D01*
X502350D01*
X502850Y-48333D01*
X503183Y-48083D01*
X503350Y-47750D01*
X503267Y-47250D01*
X502933Y-47000D01*
X501433Y-46500D01*
X501100Y-45917D01*
X501267Y-45500D01*
X501600Y-45250D01*
X502100Y-45167D01*
X502600Y-45250D01*
X503100Y-45500D01*
G01X506450Y-47917D02*
X506867Y-48250D01*
X507450Y-48500D01*
X507950D01*
X508450Y-48333D01*
X508783Y-48083D01*
X508950Y-47750D01*
X508867Y-47250D01*
X508533Y-47000D01*
X507033Y-46500D01*
X506700Y-45917D01*
X506867Y-45500D01*
X507200Y-45250D01*
X507700Y-45167D01*
X508200Y-45250D01*
X508700Y-45500D01*
G01X518900Y-48500D02*
X518400Y-48417D01*
X517900Y-48083D01*
X517567Y-47500D01*
X517400Y-46833D01*
X517567Y-46167D01*
X517900Y-45583D01*
X518400Y-45250D01*
X518900Y-45167D01*
X519400Y-45250D01*
X519900Y-45583D01*
X520233Y-46167D01*
X520317Y-46833D01*
X520233Y-47500D01*
X519900Y-48083D01*
X519400Y-48417D01*
X518900Y-48500D01*
G01X523083D02*
Y-45167D01*
G01Y-46000D02*
X523417Y-45583D01*
X523917Y-45250D01*
X524583Y-45167D01*
X525167Y-45250D01*
X525667Y-45583D01*
X525917Y-46167D01*
Y-48500D01*
G01X535700Y-43500D02*
Y-48500D01*
G01X534533Y-45167D02*
X536867D01*
G01X540133Y-48500D02*
Y-45167D01*
G01Y-45833D02*
X540550Y-45500D01*
X540967Y-45250D01*
X541550Y-45167D01*
X541967Y-45250D01*
X542467Y-45500D01*
G01X548400Y-48500D02*
Y-45167D01*
G01Y-45750D02*
X548067Y-45417D01*
X547567Y-45250D01*
X546983Y-45167D01*
X546400Y-45333D01*
X545900Y-45667D01*
X545567Y-46167D01*
X545400Y-46833D01*
X545567Y-47500D01*
X545900Y-48000D01*
X546400Y-48333D01*
X546983Y-48500D01*
X547567Y-48417D01*
X548067Y-48167D01*
X548400Y-47833D01*
G01X553833Y-45583D02*
X553250Y-45250D01*
X552750Y-45167D01*
X552083Y-45333D01*
X551583Y-45667D01*
X551250Y-46250D01*
X551167Y-46833D01*
X551250Y-47417D01*
X551583Y-47917D01*
X552083Y-48333D01*
X552750Y-48500D01*
X553333Y-48333D01*
X553833Y-48000D01*
G01X556850Y-46250D02*
X559517D01*
X559267Y-45667D01*
X558850Y-45333D01*
X558267Y-45167D01*
X557683Y-45250D01*
X557183Y-45500D01*
X556850Y-46083D01*
X556683Y-46583D01*
Y-47083D01*
X556850Y-47583D01*
X557267Y-48083D01*
X557767Y-48417D01*
X558350Y-48500D01*
X558933Y-48333D01*
X559517Y-47833D01*
G01X563700Y-48667D02*
X563533Y-48583D01*
Y-48417D01*
X563700Y-48333D01*
X563867Y-48417D01*
Y-48583D01*
X563700Y-48667D01*
G01X272500Y-33500D02*
Y-28500D01*
G01X276850Y-31250D02*
X279517D01*
X279267Y-30667D01*
X278850Y-30333D01*
X278267Y-30167D01*
X277683Y-30250D01*
X277183Y-30500D01*
X276850Y-31083D01*
X276683Y-31583D01*
Y-32083D01*
X276850Y-32583D01*
X277267Y-33083D01*
X277767Y-33417D01*
X278350Y-33500D01*
X278933Y-33333D01*
X279517Y-32833D01*
G01X282533Y-34750D02*
X283117Y-35083D01*
X283783Y-35167D01*
X284367Y-35083D01*
X284867Y-34667D01*
X285200Y-34083D01*
Y-30167D01*
G01Y-30833D02*
X284867Y-30500D01*
X284367Y-30250D01*
X283783Y-30167D01*
X283117Y-30333D01*
X282700Y-30667D01*
X282367Y-31250D01*
X282200Y-31833D01*
X282283Y-32333D01*
X282617Y-32917D01*
X283117Y-33333D01*
X283783Y-33500D01*
X284283Y-33417D01*
X284867Y-33083D01*
X285200Y-32750D01*
G01X288050Y-31250D02*
X290717D01*
X290467Y-30667D01*
X290050Y-30333D01*
X289467Y-30167D01*
X288883Y-30250D01*
X288383Y-30500D01*
X288050Y-31083D01*
X287883Y-31583D01*
Y-32083D01*
X288050Y-32583D01*
X288467Y-33083D01*
X288967Y-33417D01*
X289550Y-33500D01*
X290133Y-33333D01*
X290717Y-32833D01*
G01X293483Y-33500D02*
Y-30167D01*
G01Y-31000D02*
X293817Y-30583D01*
X294317Y-30250D01*
X294983Y-30167D01*
X295567Y-30250D01*
X296067Y-30583D01*
X296317Y-31167D01*
Y-33500D01*
G01X302000Y-28500D02*
Y-33500D01*
G01Y-32750D02*
X301667Y-33167D01*
X301167Y-33417D01*
X300583Y-33500D01*
X299917Y-33333D01*
X299417Y-32917D01*
X299083Y-32417D01*
X299000Y-31833D01*
X299083Y-31250D01*
X299417Y-30750D01*
X299917Y-30333D01*
X300583Y-30167D01*
X301167Y-30250D01*
X301583Y-30417D01*
X302000Y-30750D01*
G01X311700Y-28500D02*
Y-33500D01*
G01X310533Y-30167D02*
X312867D01*
G01X315883Y-33500D02*
Y-28500D01*
G01Y-30917D02*
X316300Y-30500D01*
X316717Y-30250D01*
X317383Y-30167D01*
X317883Y-30250D01*
X318467Y-30583D01*
X318717Y-31083D01*
Y-33500D01*
G01X322900Y-30167D02*
Y-33500D01*
G01Y-28833D02*
X322733Y-28750D01*
Y-28583D01*
X322900Y-28500D01*
X323067Y-28583D01*
Y-28750D01*
X322900Y-28833D01*
G01X329833Y-30583D02*
X329250Y-30250D01*
X328750Y-30167D01*
X328083Y-30333D01*
X327583Y-30667D01*
X327250Y-31250D01*
X327167Y-31833D01*
X327250Y-32417D01*
X327583Y-32917D01*
X328083Y-33333D01*
X328750Y-33500D01*
X329333Y-33333D01*
X329833Y-33000D01*
G01X332683Y-33500D02*
Y-28500D01*
G01X335350Y-30167D02*
X332683Y-32083D01*
G01X333767Y-31333D02*
X335517Y-33500D01*
G01X338283D02*
Y-30167D01*
G01Y-31000D02*
X338617Y-30583D01*
X339117Y-30250D01*
X339783Y-30167D01*
X340367Y-30250D01*
X340867Y-30583D01*
X341117Y-31167D01*
Y-33500D01*
G01X344050Y-31250D02*
X346717D01*
X346467Y-30667D01*
X346050Y-30333D01*
X345467Y-30167D01*
X344883Y-30250D01*
X344383Y-30500D01*
X344050Y-31083D01*
X343883Y-31583D01*
Y-32083D01*
X344050Y-32583D01*
X344467Y-33083D01*
X344967Y-33417D01*
X345550Y-33500D01*
X346133Y-33333D01*
X346717Y-32833D01*
G01X349650Y-32917D02*
X350067Y-33250D01*
X350650Y-33500D01*
X351150D01*
X351650Y-33333D01*
X351983Y-33083D01*
X352150Y-32750D01*
X352067Y-32250D01*
X351733Y-32000D01*
X350233Y-31500D01*
X349900Y-30917D01*
X350067Y-30500D01*
X350400Y-30250D01*
X350900Y-30167D01*
X351400Y-30250D01*
X351900Y-30500D01*
G01X355250Y-32917D02*
X355667Y-33250D01*
X356250Y-33500D01*
X356750D01*
X357250Y-33333D01*
X357583Y-33083D01*
X357750Y-32750D01*
X357667Y-32250D01*
X357333Y-32000D01*
X355833Y-31500D01*
X355500Y-30917D01*
X355667Y-30500D01*
X356000Y-30250D01*
X356500Y-30167D01*
X357000Y-30250D01*
X357500Y-30500D01*
G01X367700Y-33500D02*
X367200Y-33417D01*
X366700Y-33083D01*
X366367Y-32500D01*
X366200Y-31833D01*
X366367Y-31167D01*
X366700Y-30583D01*
X367200Y-30250D01*
X367700Y-30167D01*
X368200Y-30250D01*
X368700Y-30583D01*
X369033Y-31167D01*
X369117Y-31833D01*
X369033Y-32500D01*
X368700Y-33083D01*
X368200Y-33417D01*
X367700Y-33500D01*
G01X371883D02*
Y-30167D01*
G01Y-31000D02*
X372217Y-30583D01*
X372717Y-30250D01*
X373383Y-30167D01*
X373967Y-30250D01*
X374467Y-30583D01*
X374717Y-31167D01*
Y-33500D01*
G01X385833Y-30583D02*
X385250Y-30250D01*
X384750Y-30167D01*
X384083Y-30333D01*
X383583Y-30667D01*
X383250Y-31250D01*
X383167Y-31833D01*
X383250Y-32417D01*
X383583Y-32917D01*
X384083Y-33333D01*
X384750Y-33500D01*
X385333Y-33333D01*
X385833Y-33000D01*
G01X390100Y-33500D02*
X389600Y-33417D01*
X389100Y-33083D01*
X388767Y-32500D01*
X388600Y-31833D01*
X388767Y-31167D01*
X389100Y-30583D01*
X389600Y-30250D01*
X390100Y-30167D01*
X390600Y-30250D01*
X391100Y-30583D01*
X391433Y-31167D01*
X391517Y-31833D01*
X391433Y-32500D01*
X391100Y-33083D01*
X390600Y-33417D01*
X390100Y-33500D01*
G01X394200Y-35167D02*
Y-30167D01*
G01Y-30917D02*
X394617Y-30500D01*
X395033Y-30250D01*
X395700Y-30167D01*
X396283Y-30250D01*
X396867Y-30667D01*
X397117Y-31250D01*
X397200Y-31833D01*
X397117Y-32417D01*
X396867Y-33000D01*
X396367Y-33333D01*
X395700Y-33500D01*
X395117Y-33417D01*
X394533Y-33167D01*
X394200Y-32833D01*
G01X399800Y-35167D02*
Y-30167D01*
G01Y-30917D02*
X400217Y-30500D01*
X400633Y-30250D01*
X401300Y-30167D01*
X401883Y-30250D01*
X402467Y-30667D01*
X402717Y-31250D01*
X402800Y-31833D01*
X402717Y-32417D01*
X402467Y-33000D01*
X401967Y-33333D01*
X401300Y-33500D01*
X400717Y-33417D01*
X400133Y-33167D01*
X399800Y-32833D01*
G01X405650Y-31250D02*
X408317D01*
X408067Y-30667D01*
X407650Y-30333D01*
X407067Y-30167D01*
X406483Y-30250D01*
X405983Y-30500D01*
X405650Y-31083D01*
X405483Y-31583D01*
Y-32083D01*
X405650Y-32583D01*
X406067Y-33083D01*
X406567Y-33417D01*
X407150Y-33500D01*
X407733Y-33333D01*
X408317Y-32833D01*
G01X411333Y-33500D02*
Y-30167D01*
G01Y-30833D02*
X411750Y-30500D01*
X412167Y-30250D01*
X412750Y-30167D01*
X413167Y-30250D01*
X413667Y-30500D01*
G01X423283Y-35167D02*
X422450Y-34333D01*
X422033Y-33500D01*
Y-30167D01*
X422450Y-29333D01*
X423283Y-28500D01*
G01X427217Y-30167D02*
X428217Y-33500D01*
X429300Y-30167D01*
X430383Y-33500D01*
X431383Y-30167D01*
G01X433483Y-33500D02*
Y-28500D01*
G01Y-30917D02*
X433900Y-30500D01*
X434317Y-30250D01*
X434983Y-30167D01*
X435483Y-30250D01*
X436067Y-30583D01*
X436317Y-31083D01*
Y-33500D01*
G01X440500Y-30167D02*
Y-33500D01*
G01Y-28833D02*
X440333Y-28750D01*
Y-28583D01*
X440500Y-28500D01*
X440667Y-28583D01*
Y-28750D01*
X440500Y-28833D01*
G01X447433Y-30583D02*
X446850Y-30250D01*
X446350Y-30167D01*
X445683Y-30333D01*
X445183Y-30667D01*
X444850Y-31250D01*
X444767Y-31833D01*
X444850Y-32417D01*
X445183Y-32917D01*
X445683Y-33333D01*
X446350Y-33500D01*
X446933Y-33333D01*
X447433Y-33000D01*
G01X450283Y-33500D02*
Y-28500D01*
G01Y-30917D02*
X450700Y-30500D01*
X451117Y-30250D01*
X451783Y-30167D01*
X452283Y-30250D01*
X452867Y-30583D01*
X453117Y-31083D01*
Y-33500D01*
G01X462900Y-30167D02*
Y-33500D01*
G01Y-28833D02*
X462733Y-28750D01*
Y-28583D01*
X462900Y-28500D01*
X463067Y-28583D01*
Y-28750D01*
X462900Y-28833D01*
G01X467250Y-32917D02*
X467667Y-33250D01*
X468250Y-33500D01*
X468750D01*
X469250Y-33333D01*
X469583Y-33083D01*
X469750Y-32750D01*
X469667Y-32250D01*
X469333Y-32000D01*
X467833Y-31500D01*
X467500Y-30917D01*
X467667Y-30500D01*
X468000Y-30250D01*
X468500Y-30167D01*
X469000Y-30250D01*
X469500Y-30500D01*
G01X478200Y-33500D02*
Y-28500D01*
G01Y-31000D02*
X478617Y-30500D01*
X479117Y-30250D01*
X479617Y-30167D01*
X480367Y-30333D01*
X480867Y-30667D01*
X481200Y-31250D01*
Y-31917D01*
X481033Y-32583D01*
X480700Y-33083D01*
X480117Y-33417D01*
X479617Y-33500D01*
X479117Y-33417D01*
X478617Y-33167D01*
X478200Y-32750D01*
G01X484050Y-31250D02*
X486717D01*
X486467Y-30667D01*
X486050Y-30333D01*
X485467Y-30167D01*
X484883Y-30250D01*
X484383Y-30500D01*
X484050Y-31083D01*
X483883Y-31583D01*
Y-32083D01*
X484050Y-32583D01*
X484467Y-33083D01*
X484967Y-33417D01*
X485550Y-33500D01*
X486133Y-33333D01*
X486717Y-32833D01*
G01X490900Y-28500D02*
Y-33500D01*
G01X489733Y-30167D02*
X492067D01*
G01X496500Y-28500D02*
Y-33500D01*
G01X495333Y-30167D02*
X497667D01*
G01X500850Y-31250D02*
X503517D01*
X503267Y-30667D01*
X502850Y-30333D01*
X502267Y-30167D01*
X501683Y-30250D01*
X501183Y-30500D01*
X500850Y-31083D01*
X500683Y-31583D01*
Y-32083D01*
X500850Y-32583D01*
X501267Y-33083D01*
X501767Y-33417D01*
X502350Y-33500D01*
X502933Y-33333D01*
X503517Y-32833D01*
G01X506533Y-33500D02*
Y-30167D01*
G01Y-30833D02*
X506950Y-30500D01*
X507367Y-30250D01*
X507950Y-30167D01*
X508367Y-30250D01*
X508867Y-30500D01*
G01X513717Y-35167D02*
X514550Y-34333D01*
X514967Y-33500D01*
Y-30167D01*
X514550Y-29333D01*
X513717Y-28500D01*
G01X271250Y-19417D02*
X271667Y-19750D01*
X272250Y-20000D01*
X272750D01*
X273250Y-19833D01*
X273583Y-19583D01*
X273750Y-19250D01*
X273667Y-18750D01*
X273333Y-18500D01*
X271833Y-18000D01*
X271500Y-17417D01*
X271667Y-17000D01*
X272000Y-16750D01*
X272500Y-16667D01*
X273000Y-16750D01*
X273500Y-17000D01*
G01X278100Y-20000D02*
X277600Y-19917D01*
X277100Y-19583D01*
X276767Y-19000D01*
X276600Y-18333D01*
X276767Y-17667D01*
X277100Y-17083D01*
X277600Y-16750D01*
X278100Y-16667D01*
X278600Y-16750D01*
X279100Y-17083D01*
X279433Y-17667D01*
X279517Y-18333D01*
X279433Y-19000D01*
X279100Y-19583D01*
X278600Y-19917D01*
X278100Y-20000D01*
G01X283700D02*
Y-15000D01*
G01X290800D02*
Y-20000D01*
G01Y-19250D02*
X290467Y-19667D01*
X289967Y-19917D01*
X289383Y-20000D01*
X288717Y-19833D01*
X288217Y-19417D01*
X287883Y-18917D01*
X287800Y-18333D01*
X287883Y-17750D01*
X288217Y-17250D01*
X288717Y-16833D01*
X289383Y-16667D01*
X289967Y-16750D01*
X290383Y-16917D01*
X290800Y-17250D01*
G01X293650Y-17750D02*
X296317D01*
X296067Y-17167D01*
X295650Y-16833D01*
X295067Y-16667D01*
X294483Y-16750D01*
X293983Y-17000D01*
X293650Y-17583D01*
X293483Y-18083D01*
Y-18583D01*
X293650Y-19083D01*
X294067Y-19583D01*
X294567Y-19917D01*
X295150Y-20000D01*
X295733Y-19833D01*
X296317Y-19333D01*
G01X299333Y-20000D02*
Y-16667D01*
G01Y-17333D02*
X299750Y-17000D01*
X300167Y-16750D01*
X300750Y-16667D01*
X301167Y-16750D01*
X301667Y-17000D01*
G01X309200Y-20000D02*
Y-16667D01*
G01Y-17583D02*
X309450Y-17167D01*
X309867Y-16833D01*
X310450Y-16667D01*
X311033Y-16833D01*
X311450Y-17167D01*
X311700Y-17583D01*
Y-20000D01*
G01Y-17583D02*
X311950Y-17167D01*
X312367Y-16833D01*
X312950Y-16667D01*
X313533Y-16833D01*
X313950Y-17167D01*
X314200Y-17667D01*
Y-20000D01*
G01X318800D02*
Y-16667D01*
G01Y-17250D02*
X318467Y-16917D01*
X317967Y-16750D01*
X317383Y-16667D01*
X316800Y-16833D01*
X316300Y-17167D01*
X315967Y-17667D01*
X315800Y-18333D01*
X315967Y-19000D01*
X316300Y-19500D01*
X316800Y-19833D01*
X317383Y-20000D01*
X317967Y-19917D01*
X318467Y-19667D01*
X318800Y-19333D01*
G01X321650Y-19417D02*
X322067Y-19750D01*
X322650Y-20000D01*
X323150D01*
X323650Y-19833D01*
X323983Y-19583D01*
X324150Y-19250D01*
X324067Y-18750D01*
X323733Y-18500D01*
X322233Y-18000D01*
X321900Y-17417D01*
X322067Y-17000D01*
X322400Y-16750D01*
X322900Y-16667D01*
X323400Y-16750D01*
X323900Y-17000D01*
G01X327083Y-20000D02*
Y-15000D01*
G01X329750Y-16667D02*
X327083Y-18583D01*
G01X328167Y-17833D02*
X329917Y-20000D01*
G01X339700Y-15000D02*
Y-20000D01*
G01X338533Y-16667D02*
X340867D01*
G01X343883Y-20000D02*
Y-15000D01*
G01Y-17417D02*
X344300Y-17000D01*
X344717Y-16750D01*
X345383Y-16667D01*
X345883Y-16750D01*
X346467Y-17083D01*
X346717Y-17583D01*
Y-20000D01*
G01X350900Y-16667D02*
Y-20000D01*
G01Y-15333D02*
X350733Y-15250D01*
Y-15083D01*
X350900Y-15000D01*
X351067Y-15083D01*
Y-15250D01*
X350900Y-15333D01*
G01X357833Y-17083D02*
X357250Y-16750D01*
X356750Y-16667D01*
X356083Y-16833D01*
X355583Y-17167D01*
X355250Y-17750D01*
X355167Y-18333D01*
X355250Y-18917D01*
X355583Y-19417D01*
X356083Y-19833D01*
X356750Y-20000D01*
X357333Y-19833D01*
X357833Y-19500D01*
G01X360683Y-20000D02*
Y-15000D01*
G01X363350Y-16667D02*
X360683Y-18583D01*
G01X361767Y-17833D02*
X363517Y-20000D01*
G01X366283D02*
Y-16667D01*
G01Y-17500D02*
X366617Y-17083D01*
X367117Y-16750D01*
X367783Y-16667D01*
X368367Y-16750D01*
X368867Y-17083D01*
X369117Y-17667D01*
Y-20000D01*
G01X372050Y-17750D02*
X374717D01*
X374467Y-17167D01*
X374050Y-16833D01*
X373467Y-16667D01*
X372883Y-16750D01*
X372383Y-17000D01*
X372050Y-17583D01*
X371883Y-18083D01*
Y-18583D01*
X372050Y-19083D01*
X372467Y-19583D01*
X372967Y-19917D01*
X373550Y-20000D01*
X374133Y-19833D01*
X374717Y-19333D01*
G01X377650Y-19417D02*
X378067Y-19750D01*
X378650Y-20000D01*
X379150D01*
X379650Y-19833D01*
X379983Y-19583D01*
X380150Y-19250D01*
X380067Y-18750D01*
X379733Y-18500D01*
X378233Y-18000D01*
X377900Y-17417D01*
X378067Y-17000D01*
X378400Y-16750D01*
X378900Y-16667D01*
X379400Y-16750D01*
X379900Y-17000D01*
G01X383250Y-19417D02*
X383667Y-19750D01*
X384250Y-20000D01*
X384750D01*
X385250Y-19833D01*
X385583Y-19583D01*
X385750Y-19250D01*
X385667Y-18750D01*
X385333Y-18500D01*
X383833Y-18000D01*
X383500Y-17417D01*
X383667Y-17000D01*
X384000Y-16750D01*
X384500Y-16667D01*
X385000Y-16750D01*
X385500Y-17000D01*
G01X272500Y15000D02*
Y10000D01*
G01X270583Y15000D02*
X274417D01*
G01X276683Y10000D02*
Y15000D01*
G01Y12583D02*
X277100Y13000D01*
X277517Y13250D01*
X278183Y13333D01*
X278683Y13250D01*
X279267Y12917D01*
X279517Y12417D01*
Y10000D01*
G01X282450Y12250D02*
X285117D01*
X284867Y12833D01*
X284450Y13167D01*
X283867Y13333D01*
X283283Y13250D01*
X282783Y13000D01*
X282450Y12417D01*
X282283Y11917D01*
Y11417D01*
X282450Y10917D01*
X282867Y10417D01*
X283367Y10083D01*
X283950Y10000D01*
X284533Y10167D01*
X285117Y10667D01*
G01X294900Y10000D02*
Y15000D01*
G01X302000Y10000D02*
Y13333D01*
G01Y12750D02*
X301667Y13083D01*
X301167Y13250D01*
X300583Y13333D01*
X300000Y13167D01*
X299500Y12833D01*
X299167Y12333D01*
X299000Y11667D01*
X299167Y11000D01*
X299500Y10500D01*
X300000Y10167D01*
X300583Y10000D01*
X301167Y10083D01*
X301667Y10333D01*
X302000Y10667D01*
G01X304933Y10000D02*
Y13333D01*
G01Y12667D02*
X305350Y13000D01*
X305767Y13250D01*
X306350Y13333D01*
X306767Y13250D01*
X307267Y13000D01*
G01X310533Y8750D02*
X311117Y8417D01*
X311783Y8333D01*
X312367Y8417D01*
X312867Y8833D01*
X313200Y9417D01*
Y13333D01*
G01Y12667D02*
X312867Y13000D01*
X312367Y13250D01*
X311783Y13333D01*
X311117Y13167D01*
X310700Y12833D01*
X310367Y12250D01*
X310200Y11667D01*
X310283Y11167D01*
X310617Y10583D01*
X311117Y10167D01*
X311783Y10000D01*
X312283Y10083D01*
X312867Y10417D01*
X313200Y10750D01*
G01X316050Y12250D02*
X318717D01*
X318467Y12833D01*
X318050Y13167D01*
X317467Y13333D01*
X316883Y13250D01*
X316383Y13000D01*
X316050Y12417D01*
X315883Y11917D01*
Y11417D01*
X316050Y10917D01*
X316467Y10417D01*
X316967Y10083D01*
X317550Y10000D01*
X318133Y10167D01*
X318717Y10667D01*
G01X321650Y10583D02*
X322067Y10250D01*
X322650Y10000D01*
X323150D01*
X323650Y10167D01*
X323983Y10417D01*
X324150Y10750D01*
X324067Y11250D01*
X323733Y11500D01*
X322233Y12000D01*
X321900Y12583D01*
X322067Y13000D01*
X322400Y13250D01*
X322900Y13333D01*
X323400Y13250D01*
X323900Y13000D01*
G01X328500Y15000D02*
Y10000D01*
G01X327333Y13333D02*
X329667D01*
G01X341200Y15000D02*
Y10000D01*
G01Y10750D02*
X340867Y10333D01*
X340367Y10083D01*
X339783Y10000D01*
X339117Y10167D01*
X338617Y10583D01*
X338283Y11083D01*
X338200Y11667D01*
X338283Y12250D01*
X338617Y12750D01*
X339117Y13167D01*
X339783Y13333D01*
X340367Y13250D01*
X340783Y13083D01*
X341200Y12750D01*
G01X345300Y13333D02*
Y10000D01*
G01Y14667D02*
X345133Y14750D01*
Y14917D01*
X345300Y15000D01*
X345467Y14917D01*
Y14750D01*
X345300Y14667D01*
G01X348400Y10000D02*
Y13333D01*
G01Y12417D02*
X348650Y12833D01*
X349067Y13167D01*
X349650Y13333D01*
X350233Y13167D01*
X350650Y12833D01*
X350900Y12417D01*
Y10000D01*
G01Y12417D02*
X351150Y12833D01*
X351567Y13167D01*
X352150Y13333D01*
X352733Y13167D01*
X353150Y12833D01*
X353400Y12333D01*
Y10000D01*
G01X355250Y12250D02*
X357917D01*
X357667Y12833D01*
X357250Y13167D01*
X356667Y13333D01*
X356083Y13250D01*
X355583Y13000D01*
X355250Y12417D01*
X355083Y11917D01*
Y11417D01*
X355250Y10917D01*
X355667Y10417D01*
X356167Y10083D01*
X356750Y10000D01*
X357333Y10167D01*
X357917Y10667D01*
G01X360683Y10000D02*
Y13333D01*
G01Y12500D02*
X361017Y12917D01*
X361517Y13250D01*
X362183Y13333D01*
X362767Y13250D01*
X363267Y12917D01*
X363517Y12333D01*
Y10000D01*
G01X366450Y10583D02*
X366867Y10250D01*
X367450Y10000D01*
X367950D01*
X368450Y10167D01*
X368783Y10417D01*
X368950Y10750D01*
X368867Y11250D01*
X368533Y11500D01*
X367033Y12000D01*
X366700Y12583D01*
X366867Y13000D01*
X367200Y13250D01*
X367700Y13333D01*
X368200Y13250D01*
X368700Y13000D01*
G01X373300Y13333D02*
Y10000D01*
G01Y14667D02*
X373133Y14750D01*
Y14917D01*
X373300Y15000D01*
X373467Y14917D01*
Y14750D01*
X373300Y14667D01*
G01X378900Y10000D02*
X378400Y10083D01*
X377900Y10417D01*
X377567Y11000D01*
X377400Y11667D01*
X377567Y12333D01*
X377900Y12917D01*
X378400Y13250D01*
X378900Y13333D01*
X379400Y13250D01*
X379900Y12917D01*
X380233Y12333D01*
X380317Y11667D01*
X380233Y11000D01*
X379900Y10417D01*
X379400Y10083D01*
X378900Y10000D01*
G01X383083D02*
Y13333D01*
G01Y12500D02*
X383417Y12917D01*
X383917Y13250D01*
X384583Y13333D01*
X385167Y13250D01*
X385667Y12917D01*
X385917Y12333D01*
Y10000D01*
G01X395700D02*
X395200Y10083D01*
X394700Y10417D01*
X394367Y11000D01*
X394200Y11667D01*
X394367Y12333D01*
X394700Y12917D01*
X395200Y13250D01*
X395700Y13333D01*
X396200Y13250D01*
X396700Y12917D01*
X397033Y12333D01*
X397117Y11667D01*
X397033Y11000D01*
X396700Y10417D01*
X396200Y10083D01*
X395700Y10000D01*
G01X400800D02*
Y14250D01*
X400967Y14667D01*
X401300Y14917D01*
X401800Y15000D01*
X402300Y14833D01*
X402550Y14417D01*
G01X401550Y13000D02*
X399883D01*
G01X411000Y8333D02*
Y13333D01*
G01Y12583D02*
X411417Y13000D01*
X411833Y13250D01*
X412500Y13333D01*
X413083Y13250D01*
X413667Y12833D01*
X413917Y12250D01*
X414000Y11667D01*
X413917Y11083D01*
X413667Y10500D01*
X413167Y10167D01*
X412500Y10000D01*
X411917Y10083D01*
X411333Y10333D01*
X411000Y10667D01*
G01X419600Y10000D02*
Y13333D01*
G01Y12750D02*
X419267Y13083D01*
X418767Y13250D01*
X418183Y13333D01*
X417600Y13167D01*
X417100Y12833D01*
X416767Y12333D01*
X416600Y11667D01*
X416767Y11000D01*
X417100Y10500D01*
X417600Y10167D01*
X418183Y10000D01*
X418767Y10083D01*
X419267Y10333D01*
X419600Y10667D01*
G01X425200Y15000D02*
Y10000D01*
G01Y10750D02*
X424867Y10333D01*
X424367Y10083D01*
X423783Y10000D01*
X423117Y10167D01*
X422617Y10583D01*
X422283Y11083D01*
X422200Y11667D01*
X422283Y12250D01*
X422617Y12750D01*
X423117Y13167D01*
X423783Y13333D01*
X424367Y13250D01*
X424783Y13083D01*
X425200Y12750D01*
G01X434900Y10000D02*
X434400Y10083D01*
X433900Y10417D01*
X433567Y11000D01*
X433400Y11667D01*
X433567Y12333D01*
X433900Y12917D01*
X434400Y13250D01*
X434900Y13333D01*
X435400Y13250D01*
X435900Y12917D01*
X436233Y12333D01*
X436317Y11667D01*
X436233Y11000D01*
X435900Y10417D01*
X435400Y10083D01*
X434900Y10000D01*
G01X439333D02*
Y13333D01*
G01Y12667D02*
X439750Y13000D01*
X440167Y13250D01*
X440750Y13333D01*
X441167Y13250D01*
X441667Y13000D01*
G01X453200Y15000D02*
Y10000D01*
G01Y10750D02*
X452867Y10333D01*
X452367Y10083D01*
X451783Y10000D01*
X451117Y10167D01*
X450617Y10583D01*
X450283Y11083D01*
X450200Y11667D01*
X450283Y12250D01*
X450617Y12750D01*
X451117Y13167D01*
X451783Y13333D01*
X452367Y13250D01*
X452783Y13083D01*
X453200Y12750D01*
G01X457300Y13333D02*
Y10000D01*
G01Y14667D02*
X457133Y14750D01*
Y14917D01*
X457300Y15000D01*
X457467Y14917D01*
Y14750D01*
X457300Y14667D01*
G01X464400Y10000D02*
Y13333D01*
G01Y12750D02*
X464067Y13083D01*
X463567Y13250D01*
X462983Y13333D01*
X462400Y13167D01*
X461900Y12833D01*
X461567Y12333D01*
X461400Y11667D01*
X461567Y11000D01*
X461900Y10500D01*
X462400Y10167D01*
X462983Y10000D01*
X463567Y10083D01*
X464067Y10333D01*
X464400Y10667D01*
G01X466000Y10000D02*
Y13333D01*
G01Y12417D02*
X466250Y12833D01*
X466667Y13167D01*
X467250Y13333D01*
X467833Y13167D01*
X468250Y12833D01*
X468500Y12417D01*
Y10000D01*
G01Y12417D02*
X468750Y12833D01*
X469167Y13167D01*
X469750Y13333D01*
X470333Y13167D01*
X470750Y12833D01*
X471000Y12333D01*
Y10000D01*
G01X472850Y12250D02*
X475517D01*
X475267Y12833D01*
X474850Y13167D01*
X474267Y13333D01*
X473683Y13250D01*
X473183Y13000D01*
X472850Y12417D01*
X472683Y11917D01*
Y11417D01*
X472850Y10917D01*
X473267Y10417D01*
X473767Y10083D01*
X474350Y10000D01*
X474933Y10167D01*
X475517Y10667D01*
G01X479700Y15000D02*
Y10000D01*
G01X478533Y13333D02*
X480867D01*
G01X484050Y12250D02*
X486717D01*
X486467Y12833D01*
X486050Y13167D01*
X485467Y13333D01*
X484883Y13250D01*
X484383Y13000D01*
X484050Y12417D01*
X483883Y11917D01*
Y11417D01*
X484050Y10917D01*
X484467Y10417D01*
X484967Y10083D01*
X485550Y10000D01*
X486133Y10167D01*
X486717Y10667D01*
G01X489733Y10000D02*
Y13333D01*
G01Y12667D02*
X490150Y13000D01*
X490567Y13250D01*
X491150Y13333D01*
X491567Y13250D01*
X492067Y13000D01*
G01X500433Y10000D02*
X503767Y11667D01*
X500433Y13333D01*
G01X507700Y10000D02*
Y15000D01*
X506700Y14000D01*
G01Y10000D02*
X508700D01*
G01X514300D02*
Y15000D01*
X511217Y11417D01*
X515383D01*
G01X522000Y10000D02*
Y13333D01*
G01Y12417D02*
X522250Y12833D01*
X522667Y13167D01*
X523250Y13333D01*
X523833Y13167D01*
X524250Y12833D01*
X524500Y12417D01*
Y10000D01*
G01Y12417D02*
X524750Y12833D01*
X525167Y13167D01*
X525750Y13333D01*
X526333Y13167D01*
X526750Y12833D01*
X527000Y12333D01*
Y10000D01*
G01X530100Y13333D02*
Y10000D01*
G01Y14667D02*
X529933Y14750D01*
Y14917D01*
X530100Y15000D01*
X530267Y14917D01*
Y14750D01*
X530100Y14667D01*
G01X535700Y10000D02*
Y15000D01*
G01X272500Y0D02*
Y-5000D01*
G01X270583Y0D02*
X274417D01*
G01X276683Y-5000D02*
Y0D01*
G01Y-2417D02*
X277100Y-2000D01*
X277517Y-1750D01*
X278183Y-1667D01*
X278683Y-1750D01*
X279267Y-2083D01*
X279517Y-2583D01*
Y-5000D01*
G01X282450Y-2750D02*
X285117D01*
X284867Y-2167D01*
X284450Y-1833D01*
X283867Y-1667D01*
X283283Y-1750D01*
X282783Y-2000D01*
X282450Y-2583D01*
X282283Y-3083D01*
Y-3583D01*
X282450Y-4083D01*
X282867Y-4583D01*
X283367Y-4917D01*
X283950Y-5000D01*
X284533Y-4833D01*
X285117Y-4333D01*
G01X294900Y-5000D02*
Y0D01*
G01X302000Y-5000D02*
Y-1667D01*
G01Y-2250D02*
X301667Y-1917D01*
X301167Y-1750D01*
X300583Y-1667D01*
X300000Y-1833D01*
X299500Y-2167D01*
X299167Y-2667D01*
X299000Y-3333D01*
X299167Y-4000D01*
X299500Y-4500D01*
X300000Y-4833D01*
X300583Y-5000D01*
X301167Y-4917D01*
X301667Y-4667D01*
X302000Y-4333D01*
G01X304933Y-5000D02*
Y-1667D01*
G01Y-2333D02*
X305350Y-2000D01*
X305767Y-1750D01*
X306350Y-1667D01*
X306767Y-1750D01*
X307267Y-2000D01*
G01X310533Y-6250D02*
X311117Y-6583D01*
X311783Y-6667D01*
X312367Y-6583D01*
X312867Y-6167D01*
X313200Y-5583D01*
Y-1667D01*
G01Y-2333D02*
X312867Y-2000D01*
X312367Y-1750D01*
X311783Y-1667D01*
X311117Y-1833D01*
X310700Y-2167D01*
X310367Y-2750D01*
X310200Y-3333D01*
X310283Y-3833D01*
X310617Y-4417D01*
X311117Y-4833D01*
X311783Y-5000D01*
X312283Y-4917D01*
X312867Y-4583D01*
X313200Y-4250D01*
G01X316050Y-2750D02*
X318717D01*
X318467Y-2167D01*
X318050Y-1833D01*
X317467Y-1667D01*
X316883Y-1750D01*
X316383Y-2000D01*
X316050Y-2583D01*
X315883Y-3083D01*
Y-3583D01*
X316050Y-4083D01*
X316467Y-4583D01*
X316967Y-4917D01*
X317550Y-5000D01*
X318133Y-4833D01*
X318717Y-4333D01*
G01X321650Y-4417D02*
X322067Y-4750D01*
X322650Y-5000D01*
X323150D01*
X323650Y-4833D01*
X323983Y-4583D01*
X324150Y-4250D01*
X324067Y-3750D01*
X323733Y-3500D01*
X322233Y-3000D01*
X321900Y-2417D01*
X322067Y-2000D01*
X322400Y-1750D01*
X322900Y-1667D01*
X323400Y-1750D01*
X323900Y-2000D01*
G01X328500Y0D02*
Y-5000D01*
G01X327333Y-1667D02*
X329667D01*
G01X341200Y0D02*
Y-5000D01*
G01Y-4250D02*
X340867Y-4667D01*
X340367Y-4917D01*
X339783Y-5000D01*
X339117Y-4833D01*
X338617Y-4417D01*
X338283Y-3917D01*
X338200Y-3333D01*
X338283Y-2750D01*
X338617Y-2250D01*
X339117Y-1833D01*
X339783Y-1667D01*
X340367Y-1750D01*
X340783Y-1917D01*
X341200Y-2250D01*
G01X345300Y-1667D02*
Y-5000D01*
G01Y-333D02*
X345133Y-250D01*
Y-83D01*
X345300Y0D01*
X345467Y-83D01*
Y-250D01*
X345300Y-333D01*
G01X348400Y-5000D02*
Y-1667D01*
G01Y-2583D02*
X348650Y-2167D01*
X349067Y-1833D01*
X349650Y-1667D01*
X350233Y-1833D01*
X350650Y-2167D01*
X350900Y-2583D01*
Y-5000D01*
G01Y-2583D02*
X351150Y-2167D01*
X351567Y-1833D01*
X352150Y-1667D01*
X352733Y-1833D01*
X353150Y-2167D01*
X353400Y-2667D01*
Y-5000D01*
G01X355250Y-2750D02*
X357917D01*
X357667Y-2167D01*
X357250Y-1833D01*
X356667Y-1667D01*
X356083Y-1750D01*
X355583Y-2000D01*
X355250Y-2583D01*
X355083Y-3083D01*
Y-3583D01*
X355250Y-4083D01*
X355667Y-4583D01*
X356167Y-4917D01*
X356750Y-5000D01*
X357333Y-4833D01*
X357917Y-4333D01*
G01X360683Y-5000D02*
Y-1667D01*
G01Y-2500D02*
X361017Y-2083D01*
X361517Y-1750D01*
X362183Y-1667D01*
X362767Y-1750D01*
X363267Y-2083D01*
X363517Y-2667D01*
Y-5000D01*
G01X366450Y-4417D02*
X366867Y-4750D01*
X367450Y-5000D01*
X367950D01*
X368450Y-4833D01*
X368783Y-4583D01*
X368950Y-4250D01*
X368867Y-3750D01*
X368533Y-3500D01*
X367033Y-3000D01*
X366700Y-2417D01*
X366867Y-2000D01*
X367200Y-1750D01*
X367700Y-1667D01*
X368200Y-1750D01*
X368700Y-2000D01*
G01X373300Y-1667D02*
Y-5000D01*
G01Y-333D02*
X373133Y-250D01*
Y-83D01*
X373300Y0D01*
X373467Y-83D01*
Y-250D01*
X373300Y-333D01*
G01X378900Y-5000D02*
X378400Y-4917D01*
X377900Y-4583D01*
X377567Y-4000D01*
X377400Y-3333D01*
X377567Y-2667D01*
X377900Y-2083D01*
X378400Y-1750D01*
X378900Y-1667D01*
X379400Y-1750D01*
X379900Y-2083D01*
X380233Y-2667D01*
X380317Y-3333D01*
X380233Y-4000D01*
X379900Y-4583D01*
X379400Y-4917D01*
X378900Y-5000D01*
G01X383083D02*
Y-1667D01*
G01Y-2500D02*
X383417Y-2083D01*
X383917Y-1750D01*
X384583Y-1667D01*
X385167Y-1750D01*
X385667Y-2083D01*
X385917Y-2667D01*
Y-5000D01*
G01X395700D02*
X395200Y-4917D01*
X394700Y-4583D01*
X394367Y-4000D01*
X394200Y-3333D01*
X394367Y-2667D01*
X394700Y-2083D01*
X395200Y-1750D01*
X395700Y-1667D01*
X396200Y-1750D01*
X396700Y-2083D01*
X397033Y-2667D01*
X397117Y-3333D01*
X397033Y-4000D01*
X396700Y-4583D01*
X396200Y-4917D01*
X395700Y-5000D01*
G01X400800D02*
Y-750D01*
X400967Y-333D01*
X401300Y-83D01*
X401800Y0D01*
X402300Y-167D01*
X402550Y-583D01*
G01X401550Y-2000D02*
X399883D01*
G01X411000Y-6667D02*
Y-1667D01*
G01Y-2417D02*
X411417Y-2000D01*
X411833Y-1750D01*
X412500Y-1667D01*
X413083Y-1750D01*
X413667Y-2167D01*
X413917Y-2750D01*
X414000Y-3333D01*
X413917Y-3917D01*
X413667Y-4500D01*
X413167Y-4833D01*
X412500Y-5000D01*
X411917Y-4917D01*
X411333Y-4667D01*
X411000Y-4333D01*
G01X419600Y-5000D02*
Y-1667D01*
G01Y-2250D02*
X419267Y-1917D01*
X418767Y-1750D01*
X418183Y-1667D01*
X417600Y-1833D01*
X417100Y-2167D01*
X416767Y-2667D01*
X416600Y-3333D01*
X416767Y-4000D01*
X417100Y-4500D01*
X417600Y-4833D01*
X418183Y-5000D01*
X418767Y-4917D01*
X419267Y-4667D01*
X419600Y-4333D01*
G01X425200Y0D02*
Y-5000D01*
G01Y-4250D02*
X424867Y-4667D01*
X424367Y-4917D01*
X423783Y-5000D01*
X423117Y-4833D01*
X422617Y-4417D01*
X422283Y-3917D01*
X422200Y-3333D01*
X422283Y-2750D01*
X422617Y-2250D01*
X423117Y-1833D01*
X423783Y-1667D01*
X424367Y-1750D01*
X424783Y-1917D01*
X425200Y-2250D01*
G01X434900Y-5000D02*
X434400Y-4917D01*
X433900Y-4583D01*
X433567Y-4000D01*
X433400Y-3333D01*
X433567Y-2667D01*
X433900Y-2083D01*
X434400Y-1750D01*
X434900Y-1667D01*
X435400Y-1750D01*
X435900Y-2083D01*
X436233Y-2667D01*
X436317Y-3333D01*
X436233Y-4000D01*
X435900Y-4583D01*
X435400Y-4917D01*
X434900Y-5000D01*
G01X439333D02*
Y-1667D01*
G01Y-2333D02*
X439750Y-2000D01*
X440167Y-1750D01*
X440750Y-1667D01*
X441167Y-1750D01*
X441667Y-2000D01*
G01X453200Y0D02*
Y-5000D01*
G01Y-4250D02*
X452867Y-4667D01*
X452367Y-4917D01*
X451783Y-5000D01*
X451117Y-4833D01*
X450617Y-4417D01*
X450283Y-3917D01*
X450200Y-3333D01*
X450283Y-2750D01*
X450617Y-2250D01*
X451117Y-1833D01*
X451783Y-1667D01*
X452367Y-1750D01*
X452783Y-1917D01*
X453200Y-2250D01*
G01X457300Y-1667D02*
Y-5000D01*
G01Y-333D02*
X457133Y-250D01*
Y-83D01*
X457300Y0D01*
X457467Y-83D01*
Y-250D01*
X457300Y-333D01*
G01X464400Y-5000D02*
Y-1667D01*
G01Y-2250D02*
X464067Y-1917D01*
X463567Y-1750D01*
X462983Y-1667D01*
X462400Y-1833D01*
X461900Y-2167D01*
X461567Y-2667D01*
X461400Y-3333D01*
X461567Y-4000D01*
X461900Y-4500D01*
X462400Y-4833D01*
X462983Y-5000D01*
X463567Y-4917D01*
X464067Y-4667D01*
X464400Y-4333D01*
G01X466000Y-5000D02*
Y-1667D01*
G01Y-2583D02*
X466250Y-2167D01*
X466667Y-1833D01*
X467250Y-1667D01*
X467833Y-1833D01*
X468250Y-2167D01*
X468500Y-2583D01*
Y-5000D01*
G01Y-2583D02*
X468750Y-2167D01*
X469167Y-1833D01*
X469750Y-1667D01*
X470333Y-1833D01*
X470750Y-2167D01*
X471000Y-2667D01*
Y-5000D01*
G01X472850Y-2750D02*
X475517D01*
X475267Y-2167D01*
X474850Y-1833D01*
X474267Y-1667D01*
X473683Y-1750D01*
X473183Y-2000D01*
X472850Y-2583D01*
X472683Y-3083D01*
Y-3583D01*
X472850Y-4083D01*
X473267Y-4583D01*
X473767Y-4917D01*
X474350Y-5000D01*
X474933Y-4833D01*
X475517Y-4333D01*
G01X479700Y0D02*
Y-5000D01*
G01X478533Y-1667D02*
X480867D01*
G01X484050Y-2750D02*
X486717D01*
X486467Y-2167D01*
X486050Y-1833D01*
X485467Y-1667D01*
X484883Y-1750D01*
X484383Y-2000D01*
X484050Y-2583D01*
X483883Y-3083D01*
Y-3583D01*
X484050Y-4083D01*
X484467Y-4583D01*
X484967Y-4917D01*
X485550Y-5000D01*
X486133Y-4833D01*
X486717Y-4333D01*
G01X489733Y-5000D02*
Y-1667D01*
G01Y-2333D02*
X490150Y-2000D01*
X490567Y-1750D01*
X491150Y-1667D01*
X491567Y-1750D01*
X492067Y-2000D01*
G01X503767Y-5000D02*
X500433Y-3333D01*
X503767Y-1667D01*
G01X506617Y-4083D02*
X508783D01*
G01Y-2583D02*
X506617D01*
G01X518900Y-5000D02*
Y0D01*
X517900Y-1000D01*
G01Y-5000D02*
X519900D01*
G01X525500D02*
Y0D01*
X522417Y-3583D01*
X526583D01*
G01X533200Y-5000D02*
Y-1667D01*
G01Y-2583D02*
X533450Y-2167D01*
X533867Y-1833D01*
X534450Y-1667D01*
X535033Y-1833D01*
X535450Y-2167D01*
X535700Y-2583D01*
Y-5000D01*
G01Y-2583D02*
X535950Y-2167D01*
X536367Y-1833D01*
X536950Y-1667D01*
X537533Y-1833D01*
X537950Y-2167D01*
X538200Y-2667D01*
Y-5000D01*
G01X541300Y-1667D02*
Y-5000D01*
G01Y-333D02*
X541133Y-250D01*
Y-83D01*
X541300Y0D01*
X541467Y-83D01*
Y-250D01*
X541300Y-333D01*
G01X546900Y-5000D02*
Y0D01*
G01X270750Y-47833D02*
X271417Y-48250D01*
X272167Y-48500D01*
X272833D01*
X273500Y-48250D01*
X274000Y-47833D01*
X274250Y-47250D01*
X274083Y-46667D01*
X273667Y-46167D01*
X272917Y-45833D01*
X271917Y-45667D01*
X271333Y-45333D01*
X271083Y-44750D01*
X271250Y-44167D01*
X271667Y-43750D01*
X272250Y-43500D01*
X272833D01*
X273417Y-43667D01*
X273917Y-44083D01*
G01X278100Y-48500D02*
X277600Y-48417D01*
X277100Y-48083D01*
X276767Y-47500D01*
X276600Y-46833D01*
X276767Y-46167D01*
X277100Y-45583D01*
X277600Y-45250D01*
X278100Y-45167D01*
X278600Y-45250D01*
X279100Y-45583D01*
X279433Y-46167D01*
X279517Y-46833D01*
X279433Y-47500D01*
X279100Y-48083D01*
X278600Y-48417D01*
X278100Y-48500D01*
G01X283700D02*
Y-43500D01*
G01X290800D02*
Y-48500D01*
G01Y-47750D02*
X290467Y-48167D01*
X289967Y-48417D01*
X289383Y-48500D01*
X288717Y-48333D01*
X288217Y-47917D01*
X287883Y-47417D01*
X287800Y-46833D01*
X287883Y-46250D01*
X288217Y-45750D01*
X288717Y-45333D01*
X289383Y-45167D01*
X289967Y-45250D01*
X290383Y-45417D01*
X290800Y-45750D01*
G01X293650Y-46250D02*
X296317D01*
X296067Y-45667D01*
X295650Y-45333D01*
X295067Y-45167D01*
X294483Y-45250D01*
X293983Y-45500D01*
X293650Y-46083D01*
X293483Y-46583D01*
Y-47083D01*
X293650Y-47583D01*
X294067Y-48083D01*
X294567Y-48417D01*
X295150Y-48500D01*
X295733Y-48333D01*
X296317Y-47833D01*
G01X299333Y-48500D02*
Y-45167D01*
G01Y-45833D02*
X299750Y-45500D01*
X300167Y-45250D01*
X300750Y-45167D01*
X301167Y-45250D01*
X301667Y-45500D01*
G01X309200Y-48500D02*
Y-45167D01*
G01Y-46083D02*
X309450Y-45667D01*
X309867Y-45333D01*
X310450Y-45167D01*
X311033Y-45333D01*
X311450Y-45667D01*
X311700Y-46083D01*
Y-48500D01*
G01Y-46083D02*
X311950Y-45667D01*
X312367Y-45333D01*
X312950Y-45167D01*
X313533Y-45333D01*
X313950Y-45667D01*
X314200Y-46167D01*
Y-48500D01*
G01X318800D02*
Y-45167D01*
G01Y-45750D02*
X318467Y-45417D01*
X317967Y-45250D01*
X317383Y-45167D01*
X316800Y-45333D01*
X316300Y-45667D01*
X315967Y-46167D01*
X315800Y-46833D01*
X315967Y-47500D01*
X316300Y-48000D01*
X316800Y-48333D01*
X317383Y-48500D01*
X317967Y-48417D01*
X318467Y-48167D01*
X318800Y-47833D01*
G01X321650Y-47917D02*
X322067Y-48250D01*
X322650Y-48500D01*
X323150D01*
X323650Y-48333D01*
X323983Y-48083D01*
X324150Y-47750D01*
X324067Y-47250D01*
X323733Y-47000D01*
X322233Y-46500D01*
X321900Y-45917D01*
X322067Y-45500D01*
X322400Y-45250D01*
X322900Y-45167D01*
X323400Y-45250D01*
X323900Y-45500D01*
G01X327083Y-48500D02*
Y-43500D01*
G01X329750Y-45167D02*
X327083Y-47083D01*
G01X328167Y-46333D02*
X329917Y-48500D01*
G01X339700Y-43500D02*
Y-48500D01*
G01X338533Y-45167D02*
X340867D01*
G01X343883Y-48500D02*
Y-43500D01*
G01Y-45917D02*
X344300Y-45500D01*
X344717Y-45250D01*
X345383Y-45167D01*
X345883Y-45250D01*
X346467Y-45583D01*
X346717Y-46083D01*
Y-48500D01*
G01X350900Y-45167D02*
Y-48500D01*
G01Y-43833D02*
X350733Y-43750D01*
Y-43583D01*
X350900Y-43500D01*
X351067Y-43583D01*
Y-43750D01*
X350900Y-43833D01*
G01X357833Y-45583D02*
X357250Y-45250D01*
X356750Y-45167D01*
X356083Y-45333D01*
X355583Y-45667D01*
X355250Y-46250D01*
X355167Y-46833D01*
X355250Y-47417D01*
X355583Y-47917D01*
X356083Y-48333D01*
X356750Y-48500D01*
X357333Y-48333D01*
X357833Y-48000D01*
G01X360683Y-48500D02*
Y-43500D01*
G01X363350Y-45167D02*
X360683Y-47083D01*
G01X361767Y-46333D02*
X363517Y-48500D01*
G01X366283D02*
Y-45167D01*
G01Y-46000D02*
X366617Y-45583D01*
X367117Y-45250D01*
X367783Y-45167D01*
X368367Y-45250D01*
X368867Y-45583D01*
X369117Y-46167D01*
Y-48500D01*
G01X372050Y-46250D02*
X374717D01*
X374467Y-45667D01*
X374050Y-45333D01*
X373467Y-45167D01*
X372883Y-45250D01*
X372383Y-45500D01*
X372050Y-46083D01*
X371883Y-46583D01*
Y-47083D01*
X372050Y-47583D01*
X372467Y-48083D01*
X372967Y-48417D01*
X373550Y-48500D01*
X374133Y-48333D01*
X374717Y-47833D01*
G01X377650Y-47917D02*
X378067Y-48250D01*
X378650Y-48500D01*
X379150D01*
X379650Y-48333D01*
X379983Y-48083D01*
X380150Y-47750D01*
X380067Y-47250D01*
X379733Y-47000D01*
X378233Y-46500D01*
X377900Y-45917D01*
X378067Y-45500D01*
X378400Y-45250D01*
X378900Y-45167D01*
X379400Y-45250D01*
X379900Y-45500D01*
G01X383250Y-47917D02*
X383667Y-48250D01*
X384250Y-48500D01*
X384750D01*
X385250Y-48333D01*
X385583Y-48083D01*
X385750Y-47750D01*
X385667Y-47250D01*
X385333Y-47000D01*
X383833Y-46500D01*
X383500Y-45917D01*
X383667Y-45500D01*
X384000Y-45250D01*
X384500Y-45167D01*
X385000Y-45250D01*
X385500Y-45500D01*
G01X394200Y-50167D02*
Y-45167D01*
G01Y-45917D02*
X394617Y-45500D01*
X395033Y-45250D01*
X395700Y-45167D01*
X396283Y-45250D01*
X396867Y-45667D01*
X397117Y-46250D01*
X397200Y-46833D01*
X397117Y-47417D01*
X396867Y-48000D01*
X396367Y-48333D01*
X395700Y-48500D01*
X395117Y-48417D01*
X394533Y-48167D01*
X394200Y-47833D01*
G01X401300Y-48500D02*
Y-43500D01*
G01X405483Y-45167D02*
Y-47500D01*
X405817Y-48083D01*
X406317Y-48417D01*
X406900Y-48500D01*
X407483Y-48417D01*
X407983Y-48083D01*
X408317Y-47500D01*
G01Y-48500D02*
Y-45167D01*
G01X411250Y-47917D02*
X411667Y-48250D01*
X412250Y-48500D01*
X412750D01*
X413250Y-48333D01*
X413583Y-48083D01*
X413750Y-47750D01*
X413667Y-47250D01*
X413333Y-47000D01*
X411833Y-46500D01*
X411500Y-45917D01*
X411667Y-45500D01*
X412000Y-45250D01*
X412500Y-45167D01*
X413000Y-45250D01*
X413500Y-45500D01*
G01X423700Y-48500D02*
Y-43500D01*
G01X428050Y-46250D02*
X430717D01*
X430467Y-45667D01*
X430050Y-45333D01*
X429467Y-45167D01*
X428883Y-45250D01*
X428383Y-45500D01*
X428050Y-46083D01*
X427883Y-46583D01*
Y-47083D01*
X428050Y-47583D01*
X428467Y-48083D01*
X428967Y-48417D01*
X429550Y-48500D01*
X430133Y-48333D01*
X430717Y-47833D01*
G01X433733Y-49750D02*
X434317Y-50083D01*
X434983Y-50167D01*
X435567Y-50083D01*
X436067Y-49667D01*
X436400Y-49083D01*
Y-45167D01*
G01Y-45833D02*
X436067Y-45500D01*
X435567Y-45250D01*
X434983Y-45167D01*
X434317Y-45333D01*
X433900Y-45667D01*
X433567Y-46250D01*
X433400Y-46833D01*
X433483Y-47333D01*
X433817Y-47917D01*
X434317Y-48333D01*
X434983Y-48500D01*
X435483Y-48417D01*
X436067Y-48083D01*
X436400Y-47750D01*
G01X439250Y-46250D02*
X441917D01*
X441667Y-45667D01*
X441250Y-45333D01*
X440667Y-45167D01*
X440083Y-45250D01*
X439583Y-45500D01*
X439250Y-46083D01*
X439083Y-46583D01*
Y-47083D01*
X439250Y-47583D01*
X439667Y-48083D01*
X440167Y-48417D01*
X440750Y-48500D01*
X441333Y-48333D01*
X441917Y-47833D01*
G01X444683Y-48500D02*
Y-45167D01*
G01Y-46000D02*
X445017Y-45583D01*
X445517Y-45250D01*
X446183Y-45167D01*
X446767Y-45250D01*
X447267Y-45583D01*
X447517Y-46167D01*
Y-48500D01*
G01X453200Y-43500D02*
Y-48500D01*
G01Y-47750D02*
X452867Y-48167D01*
X452367Y-48417D01*
X451783Y-48500D01*
X451117Y-48333D01*
X450617Y-47917D01*
X450283Y-47417D01*
X450200Y-46833D01*
X450283Y-46250D01*
X450617Y-45750D01*
X451117Y-45333D01*
X451783Y-45167D01*
X452367Y-45250D01*
X452783Y-45417D01*
X453200Y-45750D01*
G01X462900Y-43500D02*
Y-48500D01*
G01X461733Y-45167D02*
X464067D01*
G01X467083Y-48500D02*
Y-43500D01*
G01Y-45917D02*
X467500Y-45500D01*
X467917Y-45250D01*
X468583Y-45167D01*
X469083Y-45250D01*
X469667Y-45583D01*
X469917Y-46083D01*
Y-48500D01*
G01X474100Y-45167D02*
Y-48500D01*
G01Y-43833D02*
X473933Y-43750D01*
Y-43583D01*
X474100Y-43500D01*
X474267Y-43583D01*
Y-43750D01*
X474100Y-43833D01*
G01X481033Y-45583D02*
X480450Y-45250D01*
X479950Y-45167D01*
X479283Y-45333D01*
X478783Y-45667D01*
X478450Y-46250D01*
X478367Y-46833D01*
X478450Y-47417D01*
X478783Y-47917D01*
X479283Y-48333D01*
X479950Y-48500D01*
X480533Y-48333D01*
X481033Y-48000D01*
G01X483883Y-48500D02*
Y-43500D01*
G01X486550Y-45167D02*
X483883Y-47083D01*
G01X484967Y-46333D02*
X486717Y-48500D01*
G01X489483D02*
Y-45167D01*
G01Y-46000D02*
X489817Y-45583D01*
X490317Y-45250D01*
X490983Y-45167D01*
X491567Y-45250D01*
X492067Y-45583D01*
X492317Y-46167D01*
Y-48500D01*
G01X495250Y-46250D02*
X497917D01*
X497667Y-45667D01*
X497250Y-45333D01*
X496667Y-45167D01*
X496083Y-45250D01*
X495583Y-45500D01*
X495250Y-46083D01*
X495083Y-46583D01*
Y-47083D01*
X495250Y-47583D01*
X495667Y-48083D01*
X496167Y-48417D01*
X496750Y-48500D01*
X497333Y-48333D01*
X497917Y-47833D01*
G01X500850Y-47917D02*
X501267Y-48250D01*
X501850Y-48500D01*
X502350D01*
X502850Y-48333D01*
X503183Y-48083D01*
X503350Y-47750D01*
X503267Y-47250D01*
X502933Y-47000D01*
X501433Y-46500D01*
X501100Y-45917D01*
X501267Y-45500D01*
X501600Y-45250D01*
X502100Y-45167D01*
X502600Y-45250D01*
X503100Y-45500D01*
G01X506450Y-47917D02*
X506867Y-48250D01*
X507450Y-48500D01*
X507950D01*
X508450Y-48333D01*
X508783Y-48083D01*
X508950Y-47750D01*
X508867Y-47250D01*
X508533Y-47000D01*
X507033Y-46500D01*
X506700Y-45917D01*
X506867Y-45500D01*
X507200Y-45250D01*
X507700Y-45167D01*
X508200Y-45250D01*
X508700Y-45500D01*
G01X518900Y-48500D02*
X518400Y-48417D01*
X517900Y-48083D01*
X517567Y-47500D01*
X517400Y-46833D01*
X517567Y-46167D01*
X517900Y-45583D01*
X518400Y-45250D01*
X518900Y-45167D01*
X519400Y-45250D01*
X519900Y-45583D01*
X520233Y-46167D01*
X520317Y-46833D01*
X520233Y-47500D01*
X519900Y-48083D01*
X519400Y-48417D01*
X518900Y-48500D01*
G01X523083D02*
Y-45167D01*
G01Y-46000D02*
X523417Y-45583D01*
X523917Y-45250D01*
X524583Y-45167D01*
X525167Y-45250D01*
X525667Y-45583D01*
X525917Y-46167D01*
Y-48500D01*
G01X535700Y-43500D02*
Y-48500D01*
G01X534533Y-45167D02*
X536867D01*
G01X540133Y-48500D02*
Y-45167D01*
G01Y-45833D02*
X540550Y-45500D01*
X540967Y-45250D01*
X541550Y-45167D01*
X541967Y-45250D01*
X542467Y-45500D01*
G01X548400Y-48500D02*
Y-45167D01*
G01Y-45750D02*
X548067Y-45417D01*
X547567Y-45250D01*
X546983Y-45167D01*
X546400Y-45333D01*
X545900Y-45667D01*
X545567Y-46167D01*
X545400Y-46833D01*
X545567Y-47500D01*
X545900Y-48000D01*
X546400Y-48333D01*
X546983Y-48500D01*
X547567Y-48417D01*
X548067Y-48167D01*
X548400Y-47833D01*
G01X553833Y-45583D02*
X553250Y-45250D01*
X552750Y-45167D01*
X552083Y-45333D01*
X551583Y-45667D01*
X551250Y-46250D01*
X551167Y-46833D01*
X551250Y-47417D01*
X551583Y-47917D01*
X552083Y-48333D01*
X552750Y-48500D01*
X553333Y-48333D01*
X553833Y-48000D01*
G01X556850Y-46250D02*
X559517D01*
X559267Y-45667D01*
X558850Y-45333D01*
X558267Y-45167D01*
X557683Y-45250D01*
X557183Y-45500D01*
X556850Y-46083D01*
X556683Y-46583D01*
Y-47083D01*
X556850Y-47583D01*
X557267Y-48083D01*
X557767Y-48417D01*
X558350Y-48500D01*
X558933Y-48333D01*
X559517Y-47833D01*
G01X563700Y-48667D02*
X563533Y-48583D01*
Y-48417D01*
X563700Y-48333D01*
X563867Y-48417D01*
Y-48583D01*
X563700Y-48667D01*
G01X272500Y-33500D02*
Y-28500D01*
G01X276850Y-31250D02*
X279517D01*
X279267Y-30667D01*
X278850Y-30333D01*
X278267Y-30167D01*
X277683Y-30250D01*
X277183Y-30500D01*
X276850Y-31083D01*
X276683Y-31583D01*
Y-32083D01*
X276850Y-32583D01*
X277267Y-33083D01*
X277767Y-33417D01*
X278350Y-33500D01*
X278933Y-33333D01*
X279517Y-32833D01*
G01X282533Y-34750D02*
X283117Y-35083D01*
X283783Y-35167D01*
X284367Y-35083D01*
X284867Y-34667D01*
X285200Y-34083D01*
Y-30167D01*
G01Y-30833D02*
X284867Y-30500D01*
X284367Y-30250D01*
X283783Y-30167D01*
X283117Y-30333D01*
X282700Y-30667D01*
X282367Y-31250D01*
X282200Y-31833D01*
X282283Y-32333D01*
X282617Y-32917D01*
X283117Y-33333D01*
X283783Y-33500D01*
X284283Y-33417D01*
X284867Y-33083D01*
X285200Y-32750D01*
G01X288050Y-31250D02*
X290717D01*
X290467Y-30667D01*
X290050Y-30333D01*
X289467Y-30167D01*
X288883Y-30250D01*
X288383Y-30500D01*
X288050Y-31083D01*
X287883Y-31583D01*
Y-32083D01*
X288050Y-32583D01*
X288467Y-33083D01*
X288967Y-33417D01*
X289550Y-33500D01*
X290133Y-33333D01*
X290717Y-32833D01*
G01X293483Y-33500D02*
Y-30167D01*
G01Y-31000D02*
X293817Y-30583D01*
X294317Y-30250D01*
X294983Y-30167D01*
X295567Y-30250D01*
X296067Y-30583D01*
X296317Y-31167D01*
Y-33500D01*
G01X302000Y-28500D02*
Y-33500D01*
G01Y-32750D02*
X301667Y-33167D01*
X301167Y-33417D01*
X300583Y-33500D01*
X299917Y-33333D01*
X299417Y-32917D01*
X299083Y-32417D01*
X299000Y-31833D01*
X299083Y-31250D01*
X299417Y-30750D01*
X299917Y-30333D01*
X300583Y-30167D01*
X301167Y-30250D01*
X301583Y-30417D01*
X302000Y-30750D01*
G01X311700Y-28500D02*
Y-33500D01*
G01X310533Y-30167D02*
X312867D01*
G01X315883Y-33500D02*
Y-28500D01*
G01Y-30917D02*
X316300Y-30500D01*
X316717Y-30250D01*
X317383Y-30167D01*
X317883Y-30250D01*
X318467Y-30583D01*
X318717Y-31083D01*
Y-33500D01*
G01X322900Y-30167D02*
Y-33500D01*
G01Y-28833D02*
X322733Y-28750D01*
Y-28583D01*
X322900Y-28500D01*
X323067Y-28583D01*
Y-28750D01*
X322900Y-28833D01*
G01X329833Y-30583D02*
X329250Y-30250D01*
X328750Y-30167D01*
X328083Y-30333D01*
X327583Y-30667D01*
X327250Y-31250D01*
X327167Y-31833D01*
X327250Y-32417D01*
X327583Y-32917D01*
X328083Y-33333D01*
X328750Y-33500D01*
X329333Y-33333D01*
X329833Y-33000D01*
G01X332683Y-33500D02*
Y-28500D01*
G01X335350Y-30167D02*
X332683Y-32083D01*
G01X333767Y-31333D02*
X335517Y-33500D01*
G01X338283D02*
Y-30167D01*
G01Y-31000D02*
X338617Y-30583D01*
X339117Y-30250D01*
X339783Y-30167D01*
X340367Y-30250D01*
X340867Y-30583D01*
X341117Y-31167D01*
Y-33500D01*
G01X344050Y-31250D02*
X346717D01*
X346467Y-30667D01*
X346050Y-30333D01*
X345467Y-30167D01*
X344883Y-30250D01*
X344383Y-30500D01*
X344050Y-31083D01*
X343883Y-31583D01*
Y-32083D01*
X344050Y-32583D01*
X344467Y-33083D01*
X344967Y-33417D01*
X345550Y-33500D01*
X346133Y-33333D01*
X346717Y-32833D01*
G01X349650Y-32917D02*
X350067Y-33250D01*
X350650Y-33500D01*
X351150D01*
X351650Y-33333D01*
X351983Y-33083D01*
X352150Y-32750D01*
X352067Y-32250D01*
X351733Y-32000D01*
X350233Y-31500D01*
X349900Y-30917D01*
X350067Y-30500D01*
X350400Y-30250D01*
X350900Y-30167D01*
X351400Y-30250D01*
X351900Y-30500D01*
G01X355250Y-32917D02*
X355667Y-33250D01*
X356250Y-33500D01*
X356750D01*
X357250Y-33333D01*
X357583Y-33083D01*
X357750Y-32750D01*
X357667Y-32250D01*
X357333Y-32000D01*
X355833Y-31500D01*
X355500Y-30917D01*
X355667Y-30500D01*
X356000Y-30250D01*
X356500Y-30167D01*
X357000Y-30250D01*
X357500Y-30500D01*
G01X367700Y-33500D02*
X367200Y-33417D01*
X366700Y-33083D01*
X366367Y-32500D01*
X366200Y-31833D01*
X366367Y-31167D01*
X366700Y-30583D01*
X367200Y-30250D01*
X367700Y-30167D01*
X368200Y-30250D01*
X368700Y-30583D01*
X369033Y-31167D01*
X369117Y-31833D01*
X369033Y-32500D01*
X368700Y-33083D01*
X368200Y-33417D01*
X367700Y-33500D01*
G01X371883D02*
Y-30167D01*
G01Y-31000D02*
X372217Y-30583D01*
X372717Y-30250D01*
X373383Y-30167D01*
X373967Y-30250D01*
X374467Y-30583D01*
X374717Y-31167D01*
Y-33500D01*
G01X385833Y-30583D02*
X385250Y-30250D01*
X384750Y-30167D01*
X384083Y-30333D01*
X383583Y-30667D01*
X383250Y-31250D01*
X383167Y-31833D01*
X383250Y-32417D01*
X383583Y-32917D01*
X384083Y-33333D01*
X384750Y-33500D01*
X385333Y-33333D01*
X385833Y-33000D01*
G01X390100Y-33500D02*
X389600Y-33417D01*
X389100Y-33083D01*
X388767Y-32500D01*
X388600Y-31833D01*
X388767Y-31167D01*
X389100Y-30583D01*
X389600Y-30250D01*
X390100Y-30167D01*
X390600Y-30250D01*
X391100Y-30583D01*
X391433Y-31167D01*
X391517Y-31833D01*
X391433Y-32500D01*
X391100Y-33083D01*
X390600Y-33417D01*
X390100Y-33500D01*
G01X394200Y-35167D02*
Y-30167D01*
G01Y-30917D02*
X394617Y-30500D01*
X395033Y-30250D01*
X395700Y-30167D01*
X396283Y-30250D01*
X396867Y-30667D01*
X397117Y-31250D01*
X397200Y-31833D01*
X397117Y-32417D01*
X396867Y-33000D01*
X396367Y-33333D01*
X395700Y-33500D01*
X395117Y-33417D01*
X394533Y-33167D01*
X394200Y-32833D01*
G01X399800Y-35167D02*
Y-30167D01*
G01Y-30917D02*
X400217Y-30500D01*
X400633Y-30250D01*
X401300Y-30167D01*
X401883Y-30250D01*
X402467Y-30667D01*
X402717Y-31250D01*
X402800Y-31833D01*
X402717Y-32417D01*
X402467Y-33000D01*
X401967Y-33333D01*
X401300Y-33500D01*
X400717Y-33417D01*
X400133Y-33167D01*
X399800Y-32833D01*
G01X405650Y-31250D02*
X408317D01*
X408067Y-30667D01*
X407650Y-30333D01*
X407067Y-30167D01*
X406483Y-30250D01*
X405983Y-30500D01*
X405650Y-31083D01*
X405483Y-31583D01*
Y-32083D01*
X405650Y-32583D01*
X406067Y-33083D01*
X406567Y-33417D01*
X407150Y-33500D01*
X407733Y-33333D01*
X408317Y-32833D01*
G01X411333Y-33500D02*
Y-30167D01*
G01Y-30833D02*
X411750Y-30500D01*
X412167Y-30250D01*
X412750Y-30167D01*
X413167Y-30250D01*
X413667Y-30500D01*
G01X423283Y-35167D02*
X422450Y-34333D01*
X422033Y-33500D01*
Y-30167D01*
X422450Y-29333D01*
X423283Y-28500D01*
G01X427217Y-30167D02*
X428217Y-33500D01*
X429300Y-30167D01*
X430383Y-33500D01*
X431383Y-30167D01*
G01X433483Y-33500D02*
Y-28500D01*
G01Y-30917D02*
X433900Y-30500D01*
X434317Y-30250D01*
X434983Y-30167D01*
X435483Y-30250D01*
X436067Y-30583D01*
X436317Y-31083D01*
Y-33500D01*
G01X440500Y-30167D02*
Y-33500D01*
G01Y-28833D02*
X440333Y-28750D01*
Y-28583D01*
X440500Y-28500D01*
X440667Y-28583D01*
Y-28750D01*
X440500Y-28833D01*
G01X447433Y-30583D02*
X446850Y-30250D01*
X446350Y-30167D01*
X445683Y-30333D01*
X445183Y-30667D01*
X444850Y-31250D01*
X444767Y-31833D01*
X444850Y-32417D01*
X445183Y-32917D01*
X445683Y-33333D01*
X446350Y-33500D01*
X446933Y-33333D01*
X447433Y-33000D01*
G01X450283Y-33500D02*
Y-28500D01*
G01Y-30917D02*
X450700Y-30500D01*
X451117Y-30250D01*
X451783Y-30167D01*
X452283Y-30250D01*
X452867Y-30583D01*
X453117Y-31083D01*
Y-33500D01*
G01X462900Y-30167D02*
Y-33500D01*
G01Y-28833D02*
X462733Y-28750D01*
Y-28583D01*
X462900Y-28500D01*
X463067Y-28583D01*
Y-28750D01*
X462900Y-28833D01*
G01X467250Y-32917D02*
X467667Y-33250D01*
X468250Y-33500D01*
X468750D01*
X469250Y-33333D01*
X469583Y-33083D01*
X469750Y-32750D01*
X469667Y-32250D01*
X469333Y-32000D01*
X467833Y-31500D01*
X467500Y-30917D01*
X467667Y-30500D01*
X468000Y-30250D01*
X468500Y-30167D01*
X469000Y-30250D01*
X469500Y-30500D01*
G01X478200Y-33500D02*
Y-28500D01*
G01Y-31000D02*
X478617Y-30500D01*
X479117Y-30250D01*
X479617Y-30167D01*
X480367Y-30333D01*
X480867Y-30667D01*
X481200Y-31250D01*
Y-31917D01*
X481033Y-32583D01*
X480700Y-33083D01*
X480117Y-33417D01*
X479617Y-33500D01*
X479117Y-33417D01*
X478617Y-33167D01*
X478200Y-32750D01*
G01X484050Y-31250D02*
X486717D01*
X486467Y-30667D01*
X486050Y-30333D01*
X485467Y-30167D01*
X484883Y-30250D01*
X484383Y-30500D01*
X484050Y-31083D01*
X483883Y-31583D01*
Y-32083D01*
X484050Y-32583D01*
X484467Y-33083D01*
X484967Y-33417D01*
X485550Y-33500D01*
X486133Y-33333D01*
X486717Y-32833D01*
G01X490900Y-28500D02*
Y-33500D01*
G01X489733Y-30167D02*
X492067D01*
G01X496500Y-28500D02*
Y-33500D01*
G01X495333Y-30167D02*
X497667D01*
G01X500850Y-31250D02*
X503517D01*
X503267Y-30667D01*
X502850Y-30333D01*
X502267Y-30167D01*
X501683Y-30250D01*
X501183Y-30500D01*
X500850Y-31083D01*
X500683Y-31583D01*
Y-32083D01*
X500850Y-32583D01*
X501267Y-33083D01*
X501767Y-33417D01*
X502350Y-33500D01*
X502933Y-33333D01*
X503517Y-32833D01*
G01X506533Y-33500D02*
Y-30167D01*
G01Y-30833D02*
X506950Y-30500D01*
X507367Y-30250D01*
X507950Y-30167D01*
X508367Y-30250D01*
X508867Y-30500D01*
G01X513717Y-35167D02*
X514550Y-34333D01*
X514967Y-33500D01*
Y-30167D01*
X514550Y-29333D01*
X513717Y-28500D01*
G01X271250Y-19417D02*
X271667Y-19750D01*
X272250Y-20000D01*
X272750D01*
X273250Y-19833D01*
X273583Y-19583D01*
X273750Y-19250D01*
X273667Y-18750D01*
X273333Y-18500D01*
X271833Y-18000D01*
X271500Y-17417D01*
X271667Y-17000D01*
X272000Y-16750D01*
X272500Y-16667D01*
X273000Y-16750D01*
X273500Y-17000D01*
G01X278100Y-20000D02*
X277600Y-19917D01*
X277100Y-19583D01*
X276767Y-19000D01*
X276600Y-18333D01*
X276767Y-17667D01*
X277100Y-17083D01*
X277600Y-16750D01*
X278100Y-16667D01*
X278600Y-16750D01*
X279100Y-17083D01*
X279433Y-17667D01*
X279517Y-18333D01*
X279433Y-19000D01*
X279100Y-19583D01*
X278600Y-19917D01*
X278100Y-20000D01*
G01X283700D02*
Y-15000D01*
G01X290800D02*
Y-20000D01*
G01Y-19250D02*
X290467Y-19667D01*
X289967Y-19917D01*
X289383Y-20000D01*
X288717Y-19833D01*
X288217Y-19417D01*
X287883Y-18917D01*
X287800Y-18333D01*
X287883Y-17750D01*
X288217Y-17250D01*
X288717Y-16833D01*
X289383Y-16667D01*
X289967Y-16750D01*
X290383Y-16917D01*
X290800Y-17250D01*
G01X293650Y-17750D02*
X296317D01*
X296067Y-17167D01*
X295650Y-16833D01*
X295067Y-16667D01*
X294483Y-16750D01*
X293983Y-17000D01*
X293650Y-17583D01*
X293483Y-18083D01*
Y-18583D01*
X293650Y-19083D01*
X294067Y-19583D01*
X294567Y-19917D01*
X295150Y-20000D01*
X295733Y-19833D01*
X296317Y-19333D01*
G01X299333Y-20000D02*
Y-16667D01*
G01Y-17333D02*
X299750Y-17000D01*
X300167Y-16750D01*
X300750Y-16667D01*
X301167Y-16750D01*
X301667Y-17000D01*
G01X309200Y-20000D02*
Y-16667D01*
G01Y-17583D02*
X309450Y-17167D01*
X309867Y-16833D01*
X310450Y-16667D01*
X311033Y-16833D01*
X311450Y-17167D01*
X311700Y-17583D01*
Y-20000D01*
G01Y-17583D02*
X311950Y-17167D01*
X312367Y-16833D01*
X312950Y-16667D01*
X313533Y-16833D01*
X313950Y-17167D01*
X314200Y-17667D01*
Y-20000D01*
G01X318800D02*
Y-16667D01*
G01Y-17250D02*
X318467Y-16917D01*
X317967Y-16750D01*
X317383Y-16667D01*
X316800Y-16833D01*
X316300Y-17167D01*
X315967Y-17667D01*
X315800Y-18333D01*
X315967Y-19000D01*
X316300Y-19500D01*
X316800Y-19833D01*
X317383Y-20000D01*
X317967Y-19917D01*
X318467Y-19667D01*
X318800Y-19333D01*
G01X321650Y-19417D02*
X322067Y-19750D01*
X322650Y-20000D01*
X323150D01*
X323650Y-19833D01*
X323983Y-19583D01*
X324150Y-19250D01*
X324067Y-18750D01*
X323733Y-18500D01*
X322233Y-18000D01*
X321900Y-17417D01*
X322067Y-17000D01*
X322400Y-16750D01*
X322900Y-16667D01*
X323400Y-16750D01*
X323900Y-17000D01*
G01X327083Y-20000D02*
Y-15000D01*
G01X329750Y-16667D02*
X327083Y-18583D01*
G01X328167Y-17833D02*
X329917Y-20000D01*
G01X339700Y-15000D02*
Y-20000D01*
G01X338533Y-16667D02*
X340867D01*
G01X343883Y-20000D02*
Y-15000D01*
G01Y-17417D02*
X344300Y-17000D01*
X344717Y-16750D01*
X345383Y-16667D01*
X345883Y-16750D01*
X346467Y-17083D01*
X346717Y-17583D01*
Y-20000D01*
G01X350900Y-16667D02*
Y-20000D01*
G01Y-15333D02*
X350733Y-15250D01*
Y-15083D01*
X350900Y-15000D01*
X351067Y-15083D01*
Y-15250D01*
X350900Y-15333D01*
G01X357833Y-17083D02*
X357250Y-16750D01*
X356750Y-16667D01*
X356083Y-16833D01*
X355583Y-17167D01*
X355250Y-17750D01*
X355167Y-18333D01*
X355250Y-18917D01*
X355583Y-19417D01*
X356083Y-19833D01*
X356750Y-20000D01*
X357333Y-19833D01*
X357833Y-19500D01*
G01X360683Y-20000D02*
Y-15000D01*
G01X363350Y-16667D02*
X360683Y-18583D01*
G01X361767Y-17833D02*
X363517Y-20000D01*
G01X366283D02*
Y-16667D01*
G01Y-17500D02*
X366617Y-17083D01*
X367117Y-16750D01*
X367783Y-16667D01*
X368367Y-16750D01*
X368867Y-17083D01*
X369117Y-17667D01*
Y-20000D01*
G01X372050Y-17750D02*
X374717D01*
X374467Y-17167D01*
X374050Y-16833D01*
X373467Y-16667D01*
X372883Y-16750D01*
X372383Y-17000D01*
X372050Y-17583D01*
X371883Y-18083D01*
Y-18583D01*
X372050Y-19083D01*
X372467Y-19583D01*
X372967Y-19917D01*
X373550Y-20000D01*
X374133Y-19833D01*
X374717Y-19333D01*
G01X377650Y-19417D02*
X378067Y-19750D01*
X378650Y-20000D01*
X379150D01*
X379650Y-19833D01*
X379983Y-19583D01*
X380150Y-19250D01*
X380067Y-18750D01*
X379733Y-18500D01*
X378233Y-18000D01*
X377900Y-17417D01*
X378067Y-17000D01*
X378400Y-16750D01*
X378900Y-16667D01*
X379400Y-16750D01*
X379900Y-17000D01*
G01X383250Y-19417D02*
X383667Y-19750D01*
X384250Y-20000D01*
X384750D01*
X385250Y-19833D01*
X385583Y-19583D01*
X385750Y-19250D01*
X385667Y-18750D01*
X385333Y-18500D01*
X383833Y-18000D01*
X383500Y-17417D01*
X383667Y-17000D01*
X384000Y-16750D01*
X384500Y-16667D01*
X385000Y-16750D01*
X385500Y-17000D01*
G01X272500Y15000D02*
Y10000D01*
G01X270583Y15000D02*
X274417D01*
G01X276683Y10000D02*
Y15000D01*
G01Y12583D02*
X277100Y13000D01*
X277517Y13250D01*
X278183Y13333D01*
X278683Y13250D01*
X279267Y12917D01*
X279517Y12417D01*
Y10000D01*
G01X282450Y12250D02*
X285117D01*
X284867Y12833D01*
X284450Y13167D01*
X283867Y13333D01*
X283283Y13250D01*
X282783Y13000D01*
X282450Y12417D01*
X282283Y11917D01*
Y11417D01*
X282450Y10917D01*
X282867Y10417D01*
X283367Y10083D01*
X283950Y10000D01*
X284533Y10167D01*
X285117Y10667D01*
G01X294900Y10000D02*
Y15000D01*
G01X302000Y10000D02*
Y13333D01*
G01Y12750D02*
X301667Y13083D01*
X301167Y13250D01*
X300583Y13333D01*
X300000Y13167D01*
X299500Y12833D01*
X299167Y12333D01*
X299000Y11667D01*
X299167Y11000D01*
X299500Y10500D01*
X300000Y10167D01*
X300583Y10000D01*
X301167Y10083D01*
X301667Y10333D01*
X302000Y10667D01*
G01X304933Y10000D02*
Y13333D01*
G01Y12667D02*
X305350Y13000D01*
X305767Y13250D01*
X306350Y13333D01*
X306767Y13250D01*
X307267Y13000D01*
G01X310533Y8750D02*
X311117Y8417D01*
X311783Y8333D01*
X312367Y8417D01*
X312867Y8833D01*
X313200Y9417D01*
Y13333D01*
G01Y12667D02*
X312867Y13000D01*
X312367Y13250D01*
X311783Y13333D01*
X311117Y13167D01*
X310700Y12833D01*
X310367Y12250D01*
X310200Y11667D01*
X310283Y11167D01*
X310617Y10583D01*
X311117Y10167D01*
X311783Y10000D01*
X312283Y10083D01*
X312867Y10417D01*
X313200Y10750D01*
G01X316050Y12250D02*
X318717D01*
X318467Y12833D01*
X318050Y13167D01*
X317467Y13333D01*
X316883Y13250D01*
X316383Y13000D01*
X316050Y12417D01*
X315883Y11917D01*
Y11417D01*
X316050Y10917D01*
X316467Y10417D01*
X316967Y10083D01*
X317550Y10000D01*
X318133Y10167D01*
X318717Y10667D01*
G01X321650Y10583D02*
X322067Y10250D01*
X322650Y10000D01*
X323150D01*
X323650Y10167D01*
X323983Y10417D01*
X324150Y10750D01*
X324067Y11250D01*
X323733Y11500D01*
X322233Y12000D01*
X321900Y12583D01*
X322067Y13000D01*
X322400Y13250D01*
X322900Y13333D01*
X323400Y13250D01*
X323900Y13000D01*
G01X328500Y15000D02*
Y10000D01*
G01X327333Y13333D02*
X329667D01*
G01X341200Y15000D02*
Y10000D01*
G01Y10750D02*
X340867Y10333D01*
X340367Y10083D01*
X339783Y10000D01*
X339117Y10167D01*
X338617Y10583D01*
X338283Y11083D01*
X338200Y11667D01*
X338283Y12250D01*
X338617Y12750D01*
X339117Y13167D01*
X339783Y13333D01*
X340367Y13250D01*
X340783Y13083D01*
X341200Y12750D01*
G01X345300Y13333D02*
Y10000D01*
G01Y14667D02*
X345133Y14750D01*
Y14917D01*
X345300Y15000D01*
X345467Y14917D01*
Y14750D01*
X345300Y14667D01*
G01X348400Y10000D02*
Y13333D01*
G01Y12417D02*
X348650Y12833D01*
X349067Y13167D01*
X349650Y13333D01*
X350233Y13167D01*
X350650Y12833D01*
X350900Y12417D01*
Y10000D01*
G01Y12417D02*
X351150Y12833D01*
X351567Y13167D01*
X352150Y13333D01*
X352733Y13167D01*
X353150Y12833D01*
X353400Y12333D01*
Y10000D01*
G01X355250Y12250D02*
X357917D01*
X357667Y12833D01*
X357250Y13167D01*
X356667Y13333D01*
X356083Y13250D01*
X355583Y13000D01*
X355250Y12417D01*
X355083Y11917D01*
Y11417D01*
X355250Y10917D01*
X355667Y10417D01*
X356167Y10083D01*
X356750Y10000D01*
X357333Y10167D01*
X357917Y10667D01*
G01X360683Y10000D02*
Y13333D01*
G01Y12500D02*
X361017Y12917D01*
X361517Y13250D01*
X362183Y13333D01*
X362767Y13250D01*
X363267Y12917D01*
X363517Y12333D01*
Y10000D01*
G01X366450Y10583D02*
X366867Y10250D01*
X367450Y10000D01*
X367950D01*
X368450Y10167D01*
X368783Y10417D01*
X368950Y10750D01*
X368867Y11250D01*
X368533Y11500D01*
X367033Y12000D01*
X366700Y12583D01*
X366867Y13000D01*
X367200Y13250D01*
X367700Y13333D01*
X368200Y13250D01*
X368700Y13000D01*
G01X373300Y13333D02*
Y10000D01*
G01Y14667D02*
X373133Y14750D01*
Y14917D01*
X373300Y15000D01*
X373467Y14917D01*
Y14750D01*
X373300Y14667D01*
G01X378900Y10000D02*
X378400Y10083D01*
X377900Y10417D01*
X377567Y11000D01*
X377400Y11667D01*
X377567Y12333D01*
X377900Y12917D01*
X378400Y13250D01*
X378900Y13333D01*
X379400Y13250D01*
X379900Y12917D01*
X380233Y12333D01*
X380317Y11667D01*
X380233Y11000D01*
X379900Y10417D01*
X379400Y10083D01*
X378900Y10000D01*
G01X383083D02*
Y13333D01*
G01Y12500D02*
X383417Y12917D01*
X383917Y13250D01*
X384583Y13333D01*
X385167Y13250D01*
X385667Y12917D01*
X385917Y12333D01*
Y10000D01*
G01X395700D02*
X395200Y10083D01*
X394700Y10417D01*
X394367Y11000D01*
X394200Y11667D01*
X394367Y12333D01*
X394700Y12917D01*
X395200Y13250D01*
X395700Y13333D01*
X396200Y13250D01*
X396700Y12917D01*
X397033Y12333D01*
X397117Y11667D01*
X397033Y11000D01*
X396700Y10417D01*
X396200Y10083D01*
X395700Y10000D01*
G01X400800D02*
Y14250D01*
X400967Y14667D01*
X401300Y14917D01*
X401800Y15000D01*
X402300Y14833D01*
X402550Y14417D01*
G01X401550Y13000D02*
X399883D01*
G01X411000Y8333D02*
Y13333D01*
G01Y12583D02*
X411417Y13000D01*
X411833Y13250D01*
X412500Y13333D01*
X413083Y13250D01*
X413667Y12833D01*
X413917Y12250D01*
X414000Y11667D01*
X413917Y11083D01*
X413667Y10500D01*
X413167Y10167D01*
X412500Y10000D01*
X411917Y10083D01*
X411333Y10333D01*
X411000Y10667D01*
G01X419600Y10000D02*
Y13333D01*
G01Y12750D02*
X419267Y13083D01*
X418767Y13250D01*
X418183Y13333D01*
X417600Y13167D01*
X417100Y12833D01*
X416767Y12333D01*
X416600Y11667D01*
X416767Y11000D01*
X417100Y10500D01*
X417600Y10167D01*
X418183Y10000D01*
X418767Y10083D01*
X419267Y10333D01*
X419600Y10667D01*
G01X425200Y15000D02*
Y10000D01*
G01Y10750D02*
X424867Y10333D01*
X424367Y10083D01*
X423783Y10000D01*
X423117Y10167D01*
X422617Y10583D01*
X422283Y11083D01*
X422200Y11667D01*
X422283Y12250D01*
X422617Y12750D01*
X423117Y13167D01*
X423783Y13333D01*
X424367Y13250D01*
X424783Y13083D01*
X425200Y12750D01*
G01X434900Y10000D02*
X434400Y10083D01*
X433900Y10417D01*
X433567Y11000D01*
X433400Y11667D01*
X433567Y12333D01*
X433900Y12917D01*
X434400Y13250D01*
X434900Y13333D01*
X435400Y13250D01*
X435900Y12917D01*
X436233Y12333D01*
X436317Y11667D01*
X436233Y11000D01*
X435900Y10417D01*
X435400Y10083D01*
X434900Y10000D01*
G01X439333D02*
Y13333D01*
G01Y12667D02*
X439750Y13000D01*
X440167Y13250D01*
X440750Y13333D01*
X441167Y13250D01*
X441667Y13000D01*
G01X453200Y15000D02*
Y10000D01*
G01Y10750D02*
X452867Y10333D01*
X452367Y10083D01*
X451783Y10000D01*
X451117Y10167D01*
X450617Y10583D01*
X450283Y11083D01*
X450200Y11667D01*
X450283Y12250D01*
X450617Y12750D01*
X451117Y13167D01*
X451783Y13333D01*
X452367Y13250D01*
X452783Y13083D01*
X453200Y12750D01*
G01X457300Y13333D02*
Y10000D01*
G01Y14667D02*
X457133Y14750D01*
Y14917D01*
X457300Y15000D01*
X457467Y14917D01*
Y14750D01*
X457300Y14667D01*
G01X464400Y10000D02*
Y13333D01*
G01Y12750D02*
X464067Y13083D01*
X463567Y13250D01*
X462983Y13333D01*
X462400Y13167D01*
X461900Y12833D01*
X461567Y12333D01*
X461400Y11667D01*
X461567Y11000D01*
X461900Y10500D01*
X462400Y10167D01*
X462983Y10000D01*
X463567Y10083D01*
X464067Y10333D01*
X464400Y10667D01*
G01X466000Y10000D02*
Y13333D01*
G01Y12417D02*
X466250Y12833D01*
X466667Y13167D01*
X467250Y13333D01*
X467833Y13167D01*
X468250Y12833D01*
X468500Y12417D01*
Y10000D01*
G01Y12417D02*
X468750Y12833D01*
X469167Y13167D01*
X469750Y13333D01*
X470333Y13167D01*
X470750Y12833D01*
X471000Y12333D01*
Y10000D01*
G01X472850Y12250D02*
X475517D01*
X475267Y12833D01*
X474850Y13167D01*
X474267Y13333D01*
X473683Y13250D01*
X473183Y13000D01*
X472850Y12417D01*
X472683Y11917D01*
Y11417D01*
X472850Y10917D01*
X473267Y10417D01*
X473767Y10083D01*
X474350Y10000D01*
X474933Y10167D01*
X475517Y10667D01*
G01X479700Y15000D02*
Y10000D01*
G01X478533Y13333D02*
X480867D01*
G01X484050Y12250D02*
X486717D01*
X486467Y12833D01*
X486050Y13167D01*
X485467Y13333D01*
X484883Y13250D01*
X484383Y13000D01*
X484050Y12417D01*
X483883Y11917D01*
Y11417D01*
X484050Y10917D01*
X484467Y10417D01*
X484967Y10083D01*
X485550Y10000D01*
X486133Y10167D01*
X486717Y10667D01*
G01X489733Y10000D02*
Y13333D01*
G01Y12667D02*
X490150Y13000D01*
X490567Y13250D01*
X491150Y13333D01*
X491567Y13250D01*
X492067Y13000D01*
G01X500433Y10000D02*
X503767Y11667D01*
X500433Y13333D01*
G01X507700Y10000D02*
Y15000D01*
X506700Y14000D01*
G01Y10000D02*
X508700D01*
G01X514300D02*
Y15000D01*
X511217Y11417D01*
X515383D01*
G01X522000Y10000D02*
Y13333D01*
G01Y12417D02*
X522250Y12833D01*
X522667Y13167D01*
X523250Y13333D01*
X523833Y13167D01*
X524250Y12833D01*
X524500Y12417D01*
Y10000D01*
G01Y12417D02*
X524750Y12833D01*
X525167Y13167D01*
X525750Y13333D01*
X526333Y13167D01*
X526750Y12833D01*
X527000Y12333D01*
Y10000D01*
G01X530100Y13333D02*
Y10000D01*
G01Y14667D02*
X529933Y14750D01*
Y14917D01*
X530100Y15000D01*
X530267Y14917D01*
Y14750D01*
X530100Y14667D01*
G01X535700Y10000D02*
Y15000D01*
G01X272500Y101500D02*
Y96500D01*
G01X271333Y99833D02*
X273667D01*
G01X276933Y96500D02*
Y99833D01*
G01Y99167D02*
X277350Y99500D01*
X277767Y99750D01*
X278350Y99833D01*
X278767Y99750D01*
X279267Y99500D01*
G01X285200Y96500D02*
Y99833D01*
G01Y99250D02*
X284867Y99583D01*
X284367Y99750D01*
X283783Y99833D01*
X283200Y99667D01*
X282700Y99333D01*
X282367Y98833D01*
X282200Y98167D01*
X282367Y97500D01*
X282700Y97000D01*
X283200Y96667D01*
X283783Y96500D01*
X284367Y96583D01*
X284867Y96833D01*
X285200Y97167D01*
G01X290633Y99417D02*
X290050Y99750D01*
X289550Y99833D01*
X288883Y99667D01*
X288383Y99333D01*
X288050Y98750D01*
X287967Y98167D01*
X288050Y97583D01*
X288383Y97083D01*
X288883Y96667D01*
X289550Y96500D01*
X290133Y96667D01*
X290633Y97000D01*
G01X293650Y98750D02*
X296317D01*
X296067Y99333D01*
X295650Y99667D01*
X295067Y99833D01*
X294483Y99750D01*
X293983Y99500D01*
X293650Y98917D01*
X293483Y98417D01*
Y97917D01*
X293650Y97417D01*
X294067Y96917D01*
X294567Y96583D01*
X295150Y96500D01*
X295733Y96667D01*
X296317Y97167D01*
G01X304017Y99833D02*
X305017Y96500D01*
X306100Y99833D01*
X307183Y96500D01*
X308183Y99833D01*
G01X311700D02*
Y96500D01*
G01Y101167D02*
X311533Y101250D01*
Y101417D01*
X311700Y101500D01*
X311867Y101417D01*
Y101250D01*
X311700Y101167D01*
G01X318800Y101500D02*
Y96500D01*
G01Y97250D02*
X318467Y96833D01*
X317967Y96583D01*
X317383Y96500D01*
X316717Y96667D01*
X316217Y97083D01*
X315883Y97583D01*
X315800Y98167D01*
X315883Y98750D01*
X316217Y99250D01*
X316717Y99667D01*
X317383Y99833D01*
X317967Y99750D01*
X318383Y99583D01*
X318800Y99250D01*
G01X322900Y101500D02*
Y96500D01*
G01X321733Y99833D02*
X324067D01*
G01X327083Y96500D02*
Y101500D01*
G01Y99083D02*
X327500Y99500D01*
X327917Y99750D01*
X328583Y99833D01*
X329083Y99750D01*
X329667Y99417D01*
X329917Y98917D01*
Y96500D01*
G01X341367D02*
X338033Y98167D01*
X341367Y99833D01*
G01X344217Y97417D02*
X346383D01*
G01Y98917D02*
X344217D01*
G01X354667Y97250D02*
X355167Y96833D01*
X355750Y96583D01*
X356500Y96500D01*
X357250Y96667D01*
X357833Y97000D01*
X358250Y97583D01*
X358333Y98250D01*
X358167Y98917D01*
X357750Y99333D01*
X357167Y99667D01*
X356583Y99750D01*
X356000Y99667D01*
X355250Y99333D01*
X355500Y101500D01*
X357750D01*
G01X365200Y96500D02*
Y99833D01*
G01Y98917D02*
X365450Y99333D01*
X365867Y99667D01*
X366450Y99833D01*
X367033Y99667D01*
X367450Y99333D01*
X367700Y98917D01*
Y96500D01*
G01Y98917D02*
X367950Y99333D01*
X368367Y99667D01*
X368950Y99833D01*
X369533Y99667D01*
X369950Y99333D01*
X370200Y98833D01*
Y96500D01*
G01X373300Y99833D02*
Y96500D01*
G01Y101167D02*
X373133Y101250D01*
Y101417D01*
X373300Y101500D01*
X373467Y101417D01*
Y101250D01*
X373300Y101167D01*
G01X378900Y96500D02*
Y101500D01*
G01X270667Y82250D02*
X271167Y81833D01*
X271750Y81583D01*
X272500Y81500D01*
X273250Y81667D01*
X273833Y82000D01*
X274250Y82583D01*
X274333Y83250D01*
X274167Y83917D01*
X273750Y84333D01*
X273167Y84667D01*
X272583Y84750D01*
X272000Y84667D01*
X271250Y84333D01*
X271500Y86500D01*
X273750D01*
G01X281200Y81500D02*
Y84833D01*
G01Y83917D02*
X281450Y84333D01*
X281867Y84667D01*
X282450Y84833D01*
X283033Y84667D01*
X283450Y84333D01*
X283700Y83917D01*
Y81500D01*
G01Y83917D02*
X283950Y84333D01*
X284367Y84667D01*
X284950Y84833D01*
X285533Y84667D01*
X285950Y84333D01*
X286200Y83833D01*
Y81500D01*
G01X289300Y84833D02*
Y81500D01*
G01Y86167D02*
X289133Y86250D01*
Y86417D01*
X289300Y86500D01*
X289467Y86417D01*
Y86250D01*
X289300Y86167D01*
G01X294900Y81500D02*
Y86500D01*
G01X307767Y81500D02*
X304433Y83167D01*
X307767Y84833D01*
G01X317300Y86500D02*
Y81500D01*
G01X316133Y84833D02*
X318467D01*
G01X321733Y81500D02*
Y84833D01*
G01Y84167D02*
X322150Y84500D01*
X322567Y84750D01*
X323150Y84833D01*
X323567Y84750D01*
X324067Y84500D01*
G01X330000Y81500D02*
Y84833D01*
G01Y84250D02*
X329667Y84583D01*
X329167Y84750D01*
X328583Y84833D01*
X328000Y84667D01*
X327500Y84333D01*
X327167Y83833D01*
X327000Y83167D01*
X327167Y82500D01*
X327500Y82000D01*
X328000Y81667D01*
X328583Y81500D01*
X329167Y81583D01*
X329667Y81833D01*
X330000Y82167D01*
G01X335433Y84417D02*
X334850Y84750D01*
X334350Y84833D01*
X333683Y84667D01*
X333183Y84333D01*
X332850Y83750D01*
X332767Y83167D01*
X332850Y82583D01*
X333183Y82083D01*
X333683Y81667D01*
X334350Y81500D01*
X334933Y81667D01*
X335433Y82000D01*
G01X338450Y83750D02*
X341117D01*
X340867Y84333D01*
X340450Y84667D01*
X339867Y84833D01*
X339283Y84750D01*
X338783Y84500D01*
X338450Y83917D01*
X338283Y83417D01*
Y82917D01*
X338450Y82417D01*
X338867Y81917D01*
X339367Y81583D01*
X339950Y81500D01*
X340533Y81667D01*
X341117Y82167D01*
G01X348817Y84833D02*
X349817Y81500D01*
X350900Y84833D01*
X351983Y81500D01*
X352983Y84833D01*
G01X356500D02*
Y81500D01*
G01Y86167D02*
X356333Y86250D01*
Y86417D01*
X356500Y86500D01*
X356667Y86417D01*
Y86250D01*
X356500Y86167D01*
G01X363600Y86500D02*
Y81500D01*
G01Y82250D02*
X363267Y81833D01*
X362767Y81583D01*
X362183Y81500D01*
X361517Y81667D01*
X361017Y82083D01*
X360683Y82583D01*
X360600Y83167D01*
X360683Y83750D01*
X361017Y84250D01*
X361517Y84667D01*
X362183Y84833D01*
X362767Y84750D01*
X363183Y84583D01*
X363600Y84250D01*
G01X367700Y86500D02*
Y81500D01*
G01X366533Y84833D02*
X368867D01*
G01X371883Y81500D02*
Y86500D01*
G01Y84083D02*
X372300Y84500D01*
X372717Y84750D01*
X373383Y84833D01*
X373883Y84750D01*
X374467Y84417D01*
X374717Y83917D01*
Y81500D01*
G01X386167D02*
X382833Y83167D01*
X386167Y84833D01*
G01X389017Y82417D02*
X391183D01*
G01Y83917D02*
X389017D01*
G01X401133Y81500D02*
X401300Y82583D01*
X401550Y83500D01*
X401883Y84333D01*
X402300Y85250D01*
X402967Y86500D01*
X399633D01*
G01X410000Y81500D02*
Y84833D01*
G01Y83917D02*
X410250Y84333D01*
X410667Y84667D01*
X411250Y84833D01*
X411833Y84667D01*
X412250Y84333D01*
X412500Y83917D01*
Y81500D01*
G01Y83917D02*
X412750Y84333D01*
X413167Y84667D01*
X413750Y84833D01*
X414333Y84667D01*
X414750Y84333D01*
X415000Y83833D01*
Y81500D01*
G01X418100Y84833D02*
Y81500D01*
G01Y86167D02*
X417933Y86250D01*
Y86417D01*
X418100Y86500D01*
X418267Y86417D01*
Y86250D01*
X418100Y86167D01*
G01X423700Y81500D02*
Y86500D01*
G01X272500Y71500D02*
Y66500D01*
G01X271333Y69833D02*
X273667D01*
G01X276933Y66500D02*
Y69833D01*
G01Y69167D02*
X277350Y69500D01*
X277767Y69750D01*
X278350Y69833D01*
X278767Y69750D01*
X279267Y69500D01*
G01X285200Y66500D02*
Y69833D01*
G01Y69250D02*
X284867Y69583D01*
X284367Y69750D01*
X283783Y69833D01*
X283200Y69667D01*
X282700Y69333D01*
X282367Y68833D01*
X282200Y68167D01*
X282367Y67500D01*
X282700Y67000D01*
X283200Y66667D01*
X283783Y66500D01*
X284367Y66583D01*
X284867Y66833D01*
X285200Y67167D01*
G01X290633Y69417D02*
X290050Y69750D01*
X289550Y69833D01*
X288883Y69667D01*
X288383Y69333D01*
X288050Y68750D01*
X287967Y68167D01*
X288050Y67583D01*
X288383Y67083D01*
X288883Y66667D01*
X289550Y66500D01*
X290133Y66667D01*
X290633Y67000D01*
G01X293650Y68750D02*
X296317D01*
X296067Y69333D01*
X295650Y69667D01*
X295067Y69833D01*
X294483Y69750D01*
X293983Y69500D01*
X293650Y68917D01*
X293483Y68417D01*
Y67917D01*
X293650Y67417D01*
X294067Y66917D01*
X294567Y66583D01*
X295150Y66500D01*
X295733Y66667D01*
X296317Y67167D01*
G01X304017Y69833D02*
X305017Y66500D01*
X306100Y69833D01*
X307183Y66500D01*
X308183Y69833D01*
G01X311700D02*
Y66500D01*
G01Y71167D02*
X311533Y71250D01*
Y71417D01*
X311700Y71500D01*
X311867Y71417D01*
Y71250D01*
X311700Y71167D01*
G01X318800Y71500D02*
Y66500D01*
G01Y67250D02*
X318467Y66833D01*
X317967Y66583D01*
X317383Y66500D01*
X316717Y66667D01*
X316217Y67083D01*
X315883Y67583D01*
X315800Y68167D01*
X315883Y68750D01*
X316217Y69250D01*
X316717Y69667D01*
X317383Y69833D01*
X317967Y69750D01*
X318383Y69583D01*
X318800Y69250D01*
G01X322900Y71500D02*
Y66500D01*
G01X321733Y69833D02*
X324067D01*
G01X327083Y66500D02*
Y71500D01*
G01Y69083D02*
X327500Y69500D01*
X327917Y69750D01*
X328583Y69833D01*
X329083Y69750D01*
X329667Y69417D01*
X329917Y68917D01*
Y66500D01*
G01X338033D02*
X341367Y68167D01*
X338033Y69833D01*
G01X350733Y66500D02*
X350900Y67583D01*
X351150Y68500D01*
X351483Y69333D01*
X351900Y70250D01*
X352567Y71500D01*
X349233D01*
G01X359600Y66500D02*
Y69833D01*
G01Y68917D02*
X359850Y69333D01*
X360267Y69667D01*
X360850Y69833D01*
X361433Y69667D01*
X361850Y69333D01*
X362100Y68917D01*
Y66500D01*
G01Y68917D02*
X362350Y69333D01*
X362767Y69667D01*
X363350Y69833D01*
X363933Y69667D01*
X364350Y69333D01*
X364600Y68833D01*
Y66500D01*
G01X367700Y69833D02*
Y66500D01*
G01Y71167D02*
X367533Y71250D01*
Y71417D01*
X367700Y71500D01*
X367867Y71417D01*
Y71250D01*
X367700Y71167D01*
G01X373300Y66500D02*
Y71500D01*
G01X272500Y52000D02*
Y47000D01*
G01X270583Y52000D02*
X274417D01*
G01X276683Y47000D02*
Y52000D01*
G01Y49583D02*
X277100Y50000D01*
X277517Y50250D01*
X278183Y50333D01*
X278683Y50250D01*
X279267Y49917D01*
X279517Y49417D01*
Y47000D01*
G01X282450Y49250D02*
X285117D01*
X284867Y49833D01*
X284450Y50167D01*
X283867Y50333D01*
X283283Y50250D01*
X282783Y50000D01*
X282450Y49417D01*
X282283Y48917D01*
Y48417D01*
X282450Y47917D01*
X282867Y47417D01*
X283367Y47083D01*
X283950Y47000D01*
X284533Y47167D01*
X285117Y47667D01*
G01X294900Y47000D02*
Y52000D01*
G01X302000Y47000D02*
Y50333D01*
G01Y49750D02*
X301667Y50083D01*
X301167Y50250D01*
X300583Y50333D01*
X300000Y50167D01*
X299500Y49833D01*
X299167Y49333D01*
X299000Y48667D01*
X299167Y48000D01*
X299500Y47500D01*
X300000Y47167D01*
X300583Y47000D01*
X301167Y47083D01*
X301667Y47333D01*
X302000Y47667D01*
G01X304933Y47000D02*
Y50333D01*
G01Y49667D02*
X305350Y50000D01*
X305767Y50250D01*
X306350Y50333D01*
X306767Y50250D01*
X307267Y50000D01*
G01X310533Y45750D02*
X311117Y45417D01*
X311783Y45333D01*
X312367Y45417D01*
X312867Y45833D01*
X313200Y46417D01*
Y50333D01*
G01Y49667D02*
X312867Y50000D01*
X312367Y50250D01*
X311783Y50333D01*
X311117Y50167D01*
X310700Y49833D01*
X310367Y49250D01*
X310200Y48667D01*
X310283Y48167D01*
X310617Y47583D01*
X311117Y47167D01*
X311783Y47000D01*
X312283Y47083D01*
X312867Y47417D01*
X313200Y47750D01*
G01X316050Y49250D02*
X318717D01*
X318467Y49833D01*
X318050Y50167D01*
X317467Y50333D01*
X316883Y50250D01*
X316383Y50000D01*
X316050Y49417D01*
X315883Y48917D01*
Y48417D01*
X316050Y47917D01*
X316467Y47417D01*
X316967Y47083D01*
X317550Y47000D01*
X318133Y47167D01*
X318717Y47667D01*
G01X321650Y47583D02*
X322067Y47250D01*
X322650Y47000D01*
X323150D01*
X323650Y47167D01*
X323983Y47417D01*
X324150Y47750D01*
X324067Y48250D01*
X323733Y48500D01*
X322233Y49000D01*
X321900Y49583D01*
X322067Y50000D01*
X322400Y50250D01*
X322900Y50333D01*
X323400Y50250D01*
X323900Y50000D01*
G01X328500Y52000D02*
Y47000D01*
G01X327333Y50333D02*
X329667D01*
G01X341200Y52000D02*
Y47000D01*
G01Y47750D02*
X340867Y47333D01*
X340367Y47083D01*
X339783Y47000D01*
X339117Y47167D01*
X338617Y47583D01*
X338283Y48083D01*
X338200Y48667D01*
X338283Y49250D01*
X338617Y49750D01*
X339117Y50167D01*
X339783Y50333D01*
X340367Y50250D01*
X340783Y50083D01*
X341200Y49750D01*
G01X345300Y50333D02*
Y47000D01*
G01Y51667D02*
X345133Y51750D01*
Y51917D01*
X345300Y52000D01*
X345467Y51917D01*
Y51750D01*
X345300Y51667D01*
G01X348400Y47000D02*
Y50333D01*
G01Y49417D02*
X348650Y49833D01*
X349067Y50167D01*
X349650Y50333D01*
X350233Y50167D01*
X350650Y49833D01*
X350900Y49417D01*
Y47000D01*
G01Y49417D02*
X351150Y49833D01*
X351567Y50167D01*
X352150Y50333D01*
X352733Y50167D01*
X353150Y49833D01*
X353400Y49333D01*
Y47000D01*
G01X355250Y49250D02*
X357917D01*
X357667Y49833D01*
X357250Y50167D01*
X356667Y50333D01*
X356083Y50250D01*
X355583Y50000D01*
X355250Y49417D01*
X355083Y48917D01*
Y48417D01*
X355250Y47917D01*
X355667Y47417D01*
X356167Y47083D01*
X356750Y47000D01*
X357333Y47167D01*
X357917Y47667D01*
G01X360683Y47000D02*
Y50333D01*
G01Y49500D02*
X361017Y49917D01*
X361517Y50250D01*
X362183Y50333D01*
X362767Y50250D01*
X363267Y49917D01*
X363517Y49333D01*
Y47000D01*
G01X366450Y47583D02*
X366867Y47250D01*
X367450Y47000D01*
X367950D01*
X368450Y47167D01*
X368783Y47417D01*
X368950Y47750D01*
X368867Y48250D01*
X368533Y48500D01*
X367033Y49000D01*
X366700Y49583D01*
X366867Y50000D01*
X367200Y50250D01*
X367700Y50333D01*
X368200Y50250D01*
X368700Y50000D01*
G01X373300Y50333D02*
Y47000D01*
G01Y51667D02*
X373133Y51750D01*
Y51917D01*
X373300Y52000D01*
X373467Y51917D01*
Y51750D01*
X373300Y51667D01*
G01X378900Y47000D02*
X378400Y47083D01*
X377900Y47417D01*
X377567Y48000D01*
X377400Y48667D01*
X377567Y49333D01*
X377900Y49917D01*
X378400Y50250D01*
X378900Y50333D01*
X379400Y50250D01*
X379900Y49917D01*
X380233Y49333D01*
X380317Y48667D01*
X380233Y48000D01*
X379900Y47417D01*
X379400Y47083D01*
X378900Y47000D01*
G01X383083D02*
Y50333D01*
G01Y49500D02*
X383417Y49917D01*
X383917Y50250D01*
X384583Y50333D01*
X385167Y50250D01*
X385667Y49917D01*
X385917Y49333D01*
Y47000D01*
G01X395700D02*
X395200Y47083D01*
X394700Y47417D01*
X394367Y48000D01*
X394200Y48667D01*
X394367Y49333D01*
X394700Y49917D01*
X395200Y50250D01*
X395700Y50333D01*
X396200Y50250D01*
X396700Y49917D01*
X397033Y49333D01*
X397117Y48667D01*
X397033Y48000D01*
X396700Y47417D01*
X396200Y47083D01*
X395700Y47000D01*
G01X400800D02*
Y51250D01*
X400967Y51667D01*
X401300Y51917D01*
X401800Y52000D01*
X402300Y51833D01*
X402550Y51417D01*
G01X401550Y50000D02*
X399883D01*
G01X411000Y45333D02*
Y50333D01*
G01Y49583D02*
X411417Y50000D01*
X411833Y50250D01*
X412500Y50333D01*
X413083Y50250D01*
X413667Y49833D01*
X413917Y49250D01*
X414000Y48667D01*
X413917Y48083D01*
X413667Y47500D01*
X413167Y47167D01*
X412500Y47000D01*
X411917Y47083D01*
X411333Y47333D01*
X411000Y47667D01*
G01X419600Y47000D02*
Y50333D01*
G01Y49750D02*
X419267Y50083D01*
X418767Y50250D01*
X418183Y50333D01*
X417600Y50167D01*
X417100Y49833D01*
X416767Y49333D01*
X416600Y48667D01*
X416767Y48000D01*
X417100Y47500D01*
X417600Y47167D01*
X418183Y47000D01*
X418767Y47083D01*
X419267Y47333D01*
X419600Y47667D01*
G01X425200Y52000D02*
Y47000D01*
G01Y47750D02*
X424867Y47333D01*
X424367Y47083D01*
X423783Y47000D01*
X423117Y47167D01*
X422617Y47583D01*
X422283Y48083D01*
X422200Y48667D01*
X422283Y49250D01*
X422617Y49750D01*
X423117Y50167D01*
X423783Y50333D01*
X424367Y50250D01*
X424783Y50083D01*
X425200Y49750D01*
G01X434900Y47000D02*
X434400Y47083D01*
X433900Y47417D01*
X433567Y48000D01*
X433400Y48667D01*
X433567Y49333D01*
X433900Y49917D01*
X434400Y50250D01*
X434900Y50333D01*
X435400Y50250D01*
X435900Y49917D01*
X436233Y49333D01*
X436317Y48667D01*
X436233Y48000D01*
X435900Y47417D01*
X435400Y47083D01*
X434900Y47000D01*
G01X439333D02*
Y50333D01*
G01Y49667D02*
X439750Y50000D01*
X440167Y50250D01*
X440750Y50333D01*
X441167Y50250D01*
X441667Y50000D01*
G01X453200Y52000D02*
Y47000D01*
G01Y47750D02*
X452867Y47333D01*
X452367Y47083D01*
X451783Y47000D01*
X451117Y47167D01*
X450617Y47583D01*
X450283Y48083D01*
X450200Y48667D01*
X450283Y49250D01*
X450617Y49750D01*
X451117Y50167D01*
X451783Y50333D01*
X452367Y50250D01*
X452783Y50083D01*
X453200Y49750D01*
G01X457300Y50333D02*
Y47000D01*
G01Y51667D02*
X457133Y51750D01*
Y51917D01*
X457300Y52000D01*
X457467Y51917D01*
Y51750D01*
X457300Y51667D01*
G01X464400Y47000D02*
Y50333D01*
G01Y49750D02*
X464067Y50083D01*
X463567Y50250D01*
X462983Y50333D01*
X462400Y50167D01*
X461900Y49833D01*
X461567Y49333D01*
X461400Y48667D01*
X461567Y48000D01*
X461900Y47500D01*
X462400Y47167D01*
X462983Y47000D01*
X463567Y47083D01*
X464067Y47333D01*
X464400Y47667D01*
G01X466000Y47000D02*
Y50333D01*
G01Y49417D02*
X466250Y49833D01*
X466667Y50167D01*
X467250Y50333D01*
X467833Y50167D01*
X468250Y49833D01*
X468500Y49417D01*
Y47000D01*
G01Y49417D02*
X468750Y49833D01*
X469167Y50167D01*
X469750Y50333D01*
X470333Y50167D01*
X470750Y49833D01*
X471000Y49333D01*
Y47000D01*
G01X472850Y49250D02*
X475517D01*
X475267Y49833D01*
X474850Y50167D01*
X474267Y50333D01*
X473683Y50250D01*
X473183Y50000D01*
X472850Y49417D01*
X472683Y48917D01*
Y48417D01*
X472850Y47917D01*
X473267Y47417D01*
X473767Y47083D01*
X474350Y47000D01*
X474933Y47167D01*
X475517Y47667D01*
G01X479700Y52000D02*
Y47000D01*
G01X478533Y50333D02*
X480867D01*
G01X484050Y49250D02*
X486717D01*
X486467Y49833D01*
X486050Y50167D01*
X485467Y50333D01*
X484883Y50250D01*
X484383Y50000D01*
X484050Y49417D01*
X483883Y48917D01*
Y48417D01*
X484050Y47917D01*
X484467Y47417D01*
X484967Y47083D01*
X485550Y47000D01*
X486133Y47167D01*
X486717Y47667D01*
G01X489733Y47000D02*
Y50333D01*
G01Y49667D02*
X490150Y50000D01*
X490567Y50250D01*
X491150Y50333D01*
X491567Y50250D01*
X492067Y50000D01*
G01X500433Y47000D02*
X503767Y48667D01*
X500433Y50333D01*
G01X513300Y47000D02*
Y52000D01*
X512300Y51000D01*
G01Y47000D02*
X514300D01*
G01X519900D02*
Y52000D01*
X516817Y48417D01*
X520983D01*
G01X527600Y47000D02*
Y50333D01*
G01Y49417D02*
X527850Y49833D01*
X528267Y50167D01*
X528850Y50333D01*
X529433Y50167D01*
X529850Y49833D01*
X530100Y49417D01*
Y47000D01*
G01Y49417D02*
X530350Y49833D01*
X530767Y50167D01*
X531350Y50333D01*
X531933Y50167D01*
X532350Y49833D01*
X532600Y49333D01*
Y47000D01*
G01X535700Y50333D02*
Y47000D01*
G01Y51667D02*
X535533Y51750D01*
Y51917D01*
X535700Y52000D01*
X535867Y51917D01*
Y51750D01*
X535700Y51667D01*
G01X541300Y47000D02*
Y52000D01*
G01X273580Y32670D02*
Y27670D01*
G01X271663Y32670D02*
X275497D01*
G01X277763Y27670D02*
Y32670D01*
G01Y30253D02*
X278180Y30670D01*
X278597Y30920D01*
X279263Y31003D01*
X279763Y30920D01*
X280347Y30587D01*
X280597Y30087D01*
Y27670D01*
G01X283530Y29920D02*
X286197D01*
X285947Y30503D01*
X285530Y30837D01*
X284947Y31003D01*
X284363Y30920D01*
X283863Y30670D01*
X283530Y30087D01*
X283363Y29587D01*
Y29087D01*
X283530Y28587D01*
X283947Y28087D01*
X284447Y27753D01*
X285030Y27670D01*
X285613Y27837D01*
X286197Y28337D01*
G01X295980Y27670D02*
Y32670D01*
G01X303080Y27670D02*
Y31003D01*
G01Y30420D02*
X302747Y30753D01*
X302247Y30920D01*
X301663Y31003D01*
X301080Y30837D01*
X300580Y30503D01*
X300247Y30003D01*
X300080Y29337D01*
X300247Y28670D01*
X300580Y28170D01*
X301080Y27837D01*
X301663Y27670D01*
X302247Y27753D01*
X302747Y28003D01*
X303080Y28337D01*
G01X306013Y27670D02*
Y31003D01*
G01Y30337D02*
X306430Y30670D01*
X306847Y30920D01*
X307430Y31003D01*
X307847Y30920D01*
X308347Y30670D01*
G01X311613Y26420D02*
X312197Y26087D01*
X312863Y26003D01*
X313447Y26087D01*
X313947Y26503D01*
X314280Y27087D01*
Y31003D01*
G01Y30337D02*
X313947Y30670D01*
X313447Y30920D01*
X312863Y31003D01*
X312197Y30837D01*
X311780Y30503D01*
X311447Y29920D01*
X311280Y29337D01*
X311363Y28837D01*
X311697Y28253D01*
X312197Y27837D01*
X312863Y27670D01*
X313363Y27753D01*
X313947Y28087D01*
X314280Y28420D01*
G01X317130Y29920D02*
X319797D01*
X319547Y30503D01*
X319130Y30837D01*
X318547Y31003D01*
X317963Y30920D01*
X317463Y30670D01*
X317130Y30087D01*
X316963Y29587D01*
Y29087D01*
X317130Y28587D01*
X317547Y28087D01*
X318047Y27753D01*
X318630Y27670D01*
X319213Y27837D01*
X319797Y28337D01*
G01X322730Y28253D02*
X323147Y27920D01*
X323730Y27670D01*
X324230D01*
X324730Y27837D01*
X325063Y28087D01*
X325230Y28420D01*
X325147Y28920D01*
X324813Y29170D01*
X323313Y29670D01*
X322980Y30253D01*
X323147Y30670D01*
X323480Y30920D01*
X323980Y31003D01*
X324480Y30920D01*
X324980Y30670D01*
G01X329580Y32670D02*
Y27670D01*
G01X328413Y31003D02*
X330747D01*
G01X342280Y32670D02*
Y27670D01*
G01Y28420D02*
X341947Y28003D01*
X341447Y27753D01*
X340863Y27670D01*
X340197Y27837D01*
X339697Y28253D01*
X339363Y28753D01*
X339280Y29337D01*
X339363Y29920D01*
X339697Y30420D01*
X340197Y30837D01*
X340863Y31003D01*
X341447Y30920D01*
X341863Y30753D01*
X342280Y30420D01*
G01X346380Y31003D02*
Y27670D01*
G01Y32337D02*
X346213Y32420D01*
Y32587D01*
X346380Y32670D01*
X346547Y32587D01*
Y32420D01*
X346380Y32337D01*
G01X349480Y27670D02*
Y31003D01*
G01Y30087D02*
X349730Y30503D01*
X350147Y30837D01*
X350730Y31003D01*
X351313Y30837D01*
X351730Y30503D01*
X351980Y30087D01*
Y27670D01*
G01Y30087D02*
X352230Y30503D01*
X352647Y30837D01*
X353230Y31003D01*
X353813Y30837D01*
X354230Y30503D01*
X354480Y30003D01*
Y27670D01*
G01X356330Y29920D02*
X358997D01*
X358747Y30503D01*
X358330Y30837D01*
X357747Y31003D01*
X357163Y30920D01*
X356663Y30670D01*
X356330Y30087D01*
X356163Y29587D01*
Y29087D01*
X356330Y28587D01*
X356747Y28087D01*
X357247Y27753D01*
X357830Y27670D01*
X358413Y27837D01*
X358997Y28337D01*
G01X361763Y27670D02*
Y31003D01*
G01Y30170D02*
X362097Y30587D01*
X362597Y30920D01*
X363263Y31003D01*
X363847Y30920D01*
X364347Y30587D01*
X364597Y30003D01*
Y27670D01*
G01X367530Y28253D02*
X367947Y27920D01*
X368530Y27670D01*
X369030D01*
X369530Y27837D01*
X369863Y28087D01*
X370030Y28420D01*
X369947Y28920D01*
X369613Y29170D01*
X368113Y29670D01*
X367780Y30253D01*
X367947Y30670D01*
X368280Y30920D01*
X368780Y31003D01*
X369280Y30920D01*
X369780Y30670D01*
G01X374380Y31003D02*
Y27670D01*
G01Y32337D02*
X374213Y32420D01*
Y32587D01*
X374380Y32670D01*
X374547Y32587D01*
Y32420D01*
X374380Y32337D01*
G01X379980Y27670D02*
X379480Y27753D01*
X378980Y28087D01*
X378647Y28670D01*
X378480Y29337D01*
X378647Y30003D01*
X378980Y30587D01*
X379480Y30920D01*
X379980Y31003D01*
X380480Y30920D01*
X380980Y30587D01*
X381313Y30003D01*
X381397Y29337D01*
X381313Y28670D01*
X380980Y28087D01*
X380480Y27753D01*
X379980Y27670D01*
G01X384163D02*
Y31003D01*
G01Y30170D02*
X384497Y30587D01*
X384997Y30920D01*
X385663Y31003D01*
X386247Y30920D01*
X386747Y30587D01*
X386997Y30003D01*
Y27670D01*
G01X396780D02*
X396280Y27753D01*
X395780Y28087D01*
X395447Y28670D01*
X395280Y29337D01*
X395447Y30003D01*
X395780Y30587D01*
X396280Y30920D01*
X396780Y31003D01*
X397280Y30920D01*
X397780Y30587D01*
X398113Y30003D01*
X398197Y29337D01*
X398113Y28670D01*
X397780Y28087D01*
X397280Y27753D01*
X396780Y27670D01*
G01X401880D02*
Y31920D01*
X402047Y32337D01*
X402380Y32587D01*
X402880Y32670D01*
X403380Y32503D01*
X403630Y32087D01*
G01X402630Y30670D02*
X400963D01*
G01X412080Y26003D02*
Y31003D01*
G01Y30253D02*
X412497Y30670D01*
X412913Y30920D01*
X413580Y31003D01*
X414163Y30920D01*
X414747Y30503D01*
X414997Y29920D01*
X415080Y29337D01*
X414997Y28753D01*
X414747Y28170D01*
X414247Y27837D01*
X413580Y27670D01*
X412997Y27753D01*
X412413Y28003D01*
X412080Y28337D01*
G01X420680Y27670D02*
Y31003D01*
G01Y30420D02*
X420347Y30753D01*
X419847Y30920D01*
X419263Y31003D01*
X418680Y30837D01*
X418180Y30503D01*
X417847Y30003D01*
X417680Y29337D01*
X417847Y28670D01*
X418180Y28170D01*
X418680Y27837D01*
X419263Y27670D01*
X419847Y27753D01*
X420347Y28003D01*
X420680Y28337D01*
G01X426280Y32670D02*
Y27670D01*
G01Y28420D02*
X425947Y28003D01*
X425447Y27753D01*
X424863Y27670D01*
X424197Y27837D01*
X423697Y28253D01*
X423363Y28753D01*
X423280Y29337D01*
X423363Y29920D01*
X423697Y30420D01*
X424197Y30837D01*
X424863Y31003D01*
X425447Y30920D01*
X425863Y30753D01*
X426280Y30420D01*
G01X435980Y27670D02*
X435480Y27753D01*
X434980Y28087D01*
X434647Y28670D01*
X434480Y29337D01*
X434647Y30003D01*
X434980Y30587D01*
X435480Y30920D01*
X435980Y31003D01*
X436480Y30920D01*
X436980Y30587D01*
X437313Y30003D01*
X437397Y29337D01*
X437313Y28670D01*
X436980Y28087D01*
X436480Y27753D01*
X435980Y27670D01*
G01X440413D02*
Y31003D01*
G01Y30337D02*
X440830Y30670D01*
X441247Y30920D01*
X441830Y31003D01*
X442247Y30920D01*
X442747Y30670D01*
G01X454280Y32670D02*
Y27670D01*
G01Y28420D02*
X453947Y28003D01*
X453447Y27753D01*
X452863Y27670D01*
X452197Y27837D01*
X451697Y28253D01*
X451363Y28753D01*
X451280Y29337D01*
X451363Y29920D01*
X451697Y30420D01*
X452197Y30837D01*
X452863Y31003D01*
X453447Y30920D01*
X453863Y30753D01*
X454280Y30420D01*
G01X458380Y31003D02*
Y27670D01*
G01Y32337D02*
X458213Y32420D01*
Y32587D01*
X458380Y32670D01*
X458547Y32587D01*
Y32420D01*
X458380Y32337D01*
G01X465480Y27670D02*
Y31003D01*
G01Y30420D02*
X465147Y30753D01*
X464647Y30920D01*
X464063Y31003D01*
X463480Y30837D01*
X462980Y30503D01*
X462647Y30003D01*
X462480Y29337D01*
X462647Y28670D01*
X462980Y28170D01*
X463480Y27837D01*
X464063Y27670D01*
X464647Y27753D01*
X465147Y28003D01*
X465480Y28337D01*
G01X467080Y27670D02*
Y31003D01*
G01Y30087D02*
X467330Y30503D01*
X467747Y30837D01*
X468330Y31003D01*
X468913Y30837D01*
X469330Y30503D01*
X469580Y30087D01*
Y27670D01*
G01Y30087D02*
X469830Y30503D01*
X470247Y30837D01*
X470830Y31003D01*
X471413Y30837D01*
X471830Y30503D01*
X472080Y30003D01*
Y27670D01*
G01X473930Y29920D02*
X476597D01*
X476347Y30503D01*
X475930Y30837D01*
X475347Y31003D01*
X474763Y30920D01*
X474263Y30670D01*
X473930Y30087D01*
X473763Y29587D01*
Y29087D01*
X473930Y28587D01*
X474347Y28087D01*
X474847Y27753D01*
X475430Y27670D01*
X476013Y27837D01*
X476597Y28337D01*
G01X480780Y32670D02*
Y27670D01*
G01X479613Y31003D02*
X481947D01*
G01X485130Y29920D02*
X487797D01*
X487547Y30503D01*
X487130Y30837D01*
X486547Y31003D01*
X485963Y30920D01*
X485463Y30670D01*
X485130Y30087D01*
X484963Y29587D01*
Y29087D01*
X485130Y28587D01*
X485547Y28087D01*
X486047Y27753D01*
X486630Y27670D01*
X487213Y27837D01*
X487797Y28337D01*
G01X490813Y27670D02*
Y31003D01*
G01Y30337D02*
X491230Y30670D01*
X491647Y30920D01*
X492230Y31003D01*
X492647Y30920D01*
X493147Y30670D01*
G01X504847Y27670D02*
X501513Y29337D01*
X504847Y31003D01*
G01X507697Y28587D02*
X509863D01*
G01Y30087D02*
X507697D01*
G01X519980Y27670D02*
Y32670D01*
X518980Y31670D01*
G01Y27670D02*
X520980D01*
G01X526580D02*
Y32670D01*
X523497Y29087D01*
X527663D01*
G01X534280Y27670D02*
Y31003D01*
G01Y30087D02*
X534530Y30503D01*
X534947Y30837D01*
X535530Y31003D01*
X536113Y30837D01*
X536530Y30503D01*
X536780Y30087D01*
Y27670D01*
G01Y30087D02*
X537030Y30503D01*
X537447Y30837D01*
X538030Y31003D01*
X538613Y30837D01*
X539030Y30503D01*
X539280Y30003D01*
Y27670D01*
G01X542380Y31003D02*
Y27670D01*
G01Y32337D02*
X542213Y32420D01*
Y32587D01*
X542380Y32670D01*
X542547Y32587D01*
Y32420D01*
X542380Y32337D01*
G01X547980Y27670D02*
Y32670D01*
G01X272500Y101500D02*
Y96500D01*
G01X271333Y99833D02*
X273667D01*
G01X276933Y96500D02*
Y99833D01*
G01Y99167D02*
X277350Y99500D01*
X277767Y99750D01*
X278350Y99833D01*
X278767Y99750D01*
X279267Y99500D01*
G01X285200Y96500D02*
Y99833D01*
G01Y99250D02*
X284867Y99583D01*
X284367Y99750D01*
X283783Y99833D01*
X283200Y99667D01*
X282700Y99333D01*
X282367Y98833D01*
X282200Y98167D01*
X282367Y97500D01*
X282700Y97000D01*
X283200Y96667D01*
X283783Y96500D01*
X284367Y96583D01*
X284867Y96833D01*
X285200Y97167D01*
G01X290633Y99417D02*
X290050Y99750D01*
X289550Y99833D01*
X288883Y99667D01*
X288383Y99333D01*
X288050Y98750D01*
X287967Y98167D01*
X288050Y97583D01*
X288383Y97083D01*
X288883Y96667D01*
X289550Y96500D01*
X290133Y96667D01*
X290633Y97000D01*
G01X293650Y98750D02*
X296317D01*
X296067Y99333D01*
X295650Y99667D01*
X295067Y99833D01*
X294483Y99750D01*
X293983Y99500D01*
X293650Y98917D01*
X293483Y98417D01*
Y97917D01*
X293650Y97417D01*
X294067Y96917D01*
X294567Y96583D01*
X295150Y96500D01*
X295733Y96667D01*
X296317Y97167D01*
G01X304017Y99833D02*
X305017Y96500D01*
X306100Y99833D01*
X307183Y96500D01*
X308183Y99833D01*
G01X311700D02*
Y96500D01*
G01Y101167D02*
X311533Y101250D01*
Y101417D01*
X311700Y101500D01*
X311867Y101417D01*
Y101250D01*
X311700Y101167D01*
G01X318800Y101500D02*
Y96500D01*
G01Y97250D02*
X318467Y96833D01*
X317967Y96583D01*
X317383Y96500D01*
X316717Y96667D01*
X316217Y97083D01*
X315883Y97583D01*
X315800Y98167D01*
X315883Y98750D01*
X316217Y99250D01*
X316717Y99667D01*
X317383Y99833D01*
X317967Y99750D01*
X318383Y99583D01*
X318800Y99250D01*
G01X322900Y101500D02*
Y96500D01*
G01X321733Y99833D02*
X324067D01*
G01X327083Y96500D02*
Y101500D01*
G01Y99083D02*
X327500Y99500D01*
X327917Y99750D01*
X328583Y99833D01*
X329083Y99750D01*
X329667Y99417D01*
X329917Y98917D01*
Y96500D01*
G01X341367D02*
X338033Y98167D01*
X341367Y99833D01*
G01X344217Y97417D02*
X346383D01*
G01Y98917D02*
X344217D01*
G01X354667Y97250D02*
X355167Y96833D01*
X355750Y96583D01*
X356500Y96500D01*
X357250Y96667D01*
X357833Y97000D01*
X358250Y97583D01*
X358333Y98250D01*
X358167Y98917D01*
X357750Y99333D01*
X357167Y99667D01*
X356583Y99750D01*
X356000Y99667D01*
X355250Y99333D01*
X355500Y101500D01*
X357750D01*
G01X365200Y96500D02*
Y99833D01*
G01Y98917D02*
X365450Y99333D01*
X365867Y99667D01*
X366450Y99833D01*
X367033Y99667D01*
X367450Y99333D01*
X367700Y98917D01*
Y96500D01*
G01Y98917D02*
X367950Y99333D01*
X368367Y99667D01*
X368950Y99833D01*
X369533Y99667D01*
X369950Y99333D01*
X370200Y98833D01*
Y96500D01*
G01X373300Y99833D02*
Y96500D01*
G01Y101167D02*
X373133Y101250D01*
Y101417D01*
X373300Y101500D01*
X373467Y101417D01*
Y101250D01*
X373300Y101167D01*
G01X378900Y96500D02*
Y101500D01*
G01X270667Y82250D02*
X271167Y81833D01*
X271750Y81583D01*
X272500Y81500D01*
X273250Y81667D01*
X273833Y82000D01*
X274250Y82583D01*
X274333Y83250D01*
X274167Y83917D01*
X273750Y84333D01*
X273167Y84667D01*
X272583Y84750D01*
X272000Y84667D01*
X271250Y84333D01*
X271500Y86500D01*
X273750D01*
G01X281200Y81500D02*
Y84833D01*
G01Y83917D02*
X281450Y84333D01*
X281867Y84667D01*
X282450Y84833D01*
X283033Y84667D01*
X283450Y84333D01*
X283700Y83917D01*
Y81500D01*
G01Y83917D02*
X283950Y84333D01*
X284367Y84667D01*
X284950Y84833D01*
X285533Y84667D01*
X285950Y84333D01*
X286200Y83833D01*
Y81500D01*
G01X289300Y84833D02*
Y81500D01*
G01Y86167D02*
X289133Y86250D01*
Y86417D01*
X289300Y86500D01*
X289467Y86417D01*
Y86250D01*
X289300Y86167D01*
G01X294900Y81500D02*
Y86500D01*
G01X307767Y81500D02*
X304433Y83167D01*
X307767Y84833D01*
G01X317300Y86500D02*
Y81500D01*
G01X316133Y84833D02*
X318467D01*
G01X321733Y81500D02*
Y84833D01*
G01Y84167D02*
X322150Y84500D01*
X322567Y84750D01*
X323150Y84833D01*
X323567Y84750D01*
X324067Y84500D01*
G01X330000Y81500D02*
Y84833D01*
G01Y84250D02*
X329667Y84583D01*
X329167Y84750D01*
X328583Y84833D01*
X328000Y84667D01*
X327500Y84333D01*
X327167Y83833D01*
X327000Y83167D01*
X327167Y82500D01*
X327500Y82000D01*
X328000Y81667D01*
X328583Y81500D01*
X329167Y81583D01*
X329667Y81833D01*
X330000Y82167D01*
G01X335433Y84417D02*
X334850Y84750D01*
X334350Y84833D01*
X333683Y84667D01*
X333183Y84333D01*
X332850Y83750D01*
X332767Y83167D01*
X332850Y82583D01*
X333183Y82083D01*
X333683Y81667D01*
X334350Y81500D01*
X334933Y81667D01*
X335433Y82000D01*
G01X338450Y83750D02*
X341117D01*
X340867Y84333D01*
X340450Y84667D01*
X339867Y84833D01*
X339283Y84750D01*
X338783Y84500D01*
X338450Y83917D01*
X338283Y83417D01*
Y82917D01*
X338450Y82417D01*
X338867Y81917D01*
X339367Y81583D01*
X339950Y81500D01*
X340533Y81667D01*
X341117Y82167D01*
G01X348817Y84833D02*
X349817Y81500D01*
X350900Y84833D01*
X351983Y81500D01*
X352983Y84833D01*
G01X356500D02*
Y81500D01*
G01Y86167D02*
X356333Y86250D01*
Y86417D01*
X356500Y86500D01*
X356667Y86417D01*
Y86250D01*
X356500Y86167D01*
G01X363600Y86500D02*
Y81500D01*
G01Y82250D02*
X363267Y81833D01*
X362767Y81583D01*
X362183Y81500D01*
X361517Y81667D01*
X361017Y82083D01*
X360683Y82583D01*
X360600Y83167D01*
X360683Y83750D01*
X361017Y84250D01*
X361517Y84667D01*
X362183Y84833D01*
X362767Y84750D01*
X363183Y84583D01*
X363600Y84250D01*
G01X367700Y86500D02*
Y81500D01*
G01X366533Y84833D02*
X368867D01*
G01X371883Y81500D02*
Y86500D01*
G01Y84083D02*
X372300Y84500D01*
X372717Y84750D01*
X373383Y84833D01*
X373883Y84750D01*
X374467Y84417D01*
X374717Y83917D01*
Y81500D01*
G01X386167D02*
X382833Y83167D01*
X386167Y84833D01*
G01X389017Y82417D02*
X391183D01*
G01Y83917D02*
X389017D01*
G01X401133Y81500D02*
X401300Y82583D01*
X401550Y83500D01*
X401883Y84333D01*
X402300Y85250D01*
X402967Y86500D01*
X399633D01*
G01X410000Y81500D02*
Y84833D01*
G01Y83917D02*
X410250Y84333D01*
X410667Y84667D01*
X411250Y84833D01*
X411833Y84667D01*
X412250Y84333D01*
X412500Y83917D01*
Y81500D01*
G01Y83917D02*
X412750Y84333D01*
X413167Y84667D01*
X413750Y84833D01*
X414333Y84667D01*
X414750Y84333D01*
X415000Y83833D01*
Y81500D01*
G01X418100Y84833D02*
Y81500D01*
G01Y86167D02*
X417933Y86250D01*
Y86417D01*
X418100Y86500D01*
X418267Y86417D01*
Y86250D01*
X418100Y86167D01*
G01X423700Y81500D02*
Y86500D01*
G01X272500Y71500D02*
Y66500D01*
G01X271333Y69833D02*
X273667D01*
G01X276933Y66500D02*
Y69833D01*
G01Y69167D02*
X277350Y69500D01*
X277767Y69750D01*
X278350Y69833D01*
X278767Y69750D01*
X279267Y69500D01*
G01X285200Y66500D02*
Y69833D01*
G01Y69250D02*
X284867Y69583D01*
X284367Y69750D01*
X283783Y69833D01*
X283200Y69667D01*
X282700Y69333D01*
X282367Y68833D01*
X282200Y68167D01*
X282367Y67500D01*
X282700Y67000D01*
X283200Y66667D01*
X283783Y66500D01*
X284367Y66583D01*
X284867Y66833D01*
X285200Y67167D01*
G01X290633Y69417D02*
X290050Y69750D01*
X289550Y69833D01*
X288883Y69667D01*
X288383Y69333D01*
X288050Y68750D01*
X287967Y68167D01*
X288050Y67583D01*
X288383Y67083D01*
X288883Y66667D01*
X289550Y66500D01*
X290133Y66667D01*
X290633Y67000D01*
G01X293650Y68750D02*
X296317D01*
X296067Y69333D01*
X295650Y69667D01*
X295067Y69833D01*
X294483Y69750D01*
X293983Y69500D01*
X293650Y68917D01*
X293483Y68417D01*
Y67917D01*
X293650Y67417D01*
X294067Y66917D01*
X294567Y66583D01*
X295150Y66500D01*
X295733Y66667D01*
X296317Y67167D01*
G01X304017Y69833D02*
X305017Y66500D01*
X306100Y69833D01*
X307183Y66500D01*
X308183Y69833D01*
G01X311700D02*
Y66500D01*
G01Y71167D02*
X311533Y71250D01*
Y71417D01*
X311700Y71500D01*
X311867Y71417D01*
Y71250D01*
X311700Y71167D01*
G01X318800Y71500D02*
Y66500D01*
G01Y67250D02*
X318467Y66833D01*
X317967Y66583D01*
X317383Y66500D01*
X316717Y66667D01*
X316217Y67083D01*
X315883Y67583D01*
X315800Y68167D01*
X315883Y68750D01*
X316217Y69250D01*
X316717Y69667D01*
X317383Y69833D01*
X317967Y69750D01*
X318383Y69583D01*
X318800Y69250D01*
G01X322900Y71500D02*
Y66500D01*
G01X321733Y69833D02*
X324067D01*
G01X327083Y66500D02*
Y71500D01*
G01Y69083D02*
X327500Y69500D01*
X327917Y69750D01*
X328583Y69833D01*
X329083Y69750D01*
X329667Y69417D01*
X329917Y68917D01*
Y66500D01*
G01X338033D02*
X341367Y68167D01*
X338033Y69833D01*
G01X350733Y66500D02*
X350900Y67583D01*
X351150Y68500D01*
X351483Y69333D01*
X351900Y70250D01*
X352567Y71500D01*
X349233D01*
G01X359600Y66500D02*
Y69833D01*
G01Y68917D02*
X359850Y69333D01*
X360267Y69667D01*
X360850Y69833D01*
X361433Y69667D01*
X361850Y69333D01*
X362100Y68917D01*
Y66500D01*
G01Y68917D02*
X362350Y69333D01*
X362767Y69667D01*
X363350Y69833D01*
X363933Y69667D01*
X364350Y69333D01*
X364600Y68833D01*
Y66500D01*
G01X367700Y69833D02*
Y66500D01*
G01Y71167D02*
X367533Y71250D01*
Y71417D01*
X367700Y71500D01*
X367867Y71417D01*
Y71250D01*
X367700Y71167D01*
G01X373300Y66500D02*
Y71500D01*
G01X272500Y52000D02*
Y47000D01*
G01X270583Y52000D02*
X274417D01*
G01X276683Y47000D02*
Y52000D01*
G01Y49583D02*
X277100Y50000D01*
X277517Y50250D01*
X278183Y50333D01*
X278683Y50250D01*
X279267Y49917D01*
X279517Y49417D01*
Y47000D01*
G01X282450Y49250D02*
X285117D01*
X284867Y49833D01*
X284450Y50167D01*
X283867Y50333D01*
X283283Y50250D01*
X282783Y50000D01*
X282450Y49417D01*
X282283Y48917D01*
Y48417D01*
X282450Y47917D01*
X282867Y47417D01*
X283367Y47083D01*
X283950Y47000D01*
X284533Y47167D01*
X285117Y47667D01*
G01X294900Y47000D02*
Y52000D01*
G01X302000Y47000D02*
Y50333D01*
G01Y49750D02*
X301667Y50083D01*
X301167Y50250D01*
X300583Y50333D01*
X300000Y50167D01*
X299500Y49833D01*
X299167Y49333D01*
X299000Y48667D01*
X299167Y48000D01*
X299500Y47500D01*
X300000Y47167D01*
X300583Y47000D01*
X301167Y47083D01*
X301667Y47333D01*
X302000Y47667D01*
G01X304933Y47000D02*
Y50333D01*
G01Y49667D02*
X305350Y50000D01*
X305767Y50250D01*
X306350Y50333D01*
X306767Y50250D01*
X307267Y50000D01*
G01X310533Y45750D02*
X311117Y45417D01*
X311783Y45333D01*
X312367Y45417D01*
X312867Y45833D01*
X313200Y46417D01*
Y50333D01*
G01Y49667D02*
X312867Y50000D01*
X312367Y50250D01*
X311783Y50333D01*
X311117Y50167D01*
X310700Y49833D01*
X310367Y49250D01*
X310200Y48667D01*
X310283Y48167D01*
X310617Y47583D01*
X311117Y47167D01*
X311783Y47000D01*
X312283Y47083D01*
X312867Y47417D01*
X313200Y47750D01*
G01X316050Y49250D02*
X318717D01*
X318467Y49833D01*
X318050Y50167D01*
X317467Y50333D01*
X316883Y50250D01*
X316383Y50000D01*
X316050Y49417D01*
X315883Y48917D01*
Y48417D01*
X316050Y47917D01*
X316467Y47417D01*
X316967Y47083D01*
X317550Y47000D01*
X318133Y47167D01*
X318717Y47667D01*
G01X321650Y47583D02*
X322067Y47250D01*
X322650Y47000D01*
X323150D01*
X323650Y47167D01*
X323983Y47417D01*
X324150Y47750D01*
X324067Y48250D01*
X323733Y48500D01*
X322233Y49000D01*
X321900Y49583D01*
X322067Y50000D01*
X322400Y50250D01*
X322900Y50333D01*
X323400Y50250D01*
X323900Y50000D01*
G01X328500Y52000D02*
Y47000D01*
G01X327333Y50333D02*
X329667D01*
G01X341200Y52000D02*
Y47000D01*
G01Y47750D02*
X340867Y47333D01*
X340367Y47083D01*
X339783Y47000D01*
X339117Y47167D01*
X338617Y47583D01*
X338283Y48083D01*
X338200Y48667D01*
X338283Y49250D01*
X338617Y49750D01*
X339117Y50167D01*
X339783Y50333D01*
X340367Y50250D01*
X340783Y50083D01*
X341200Y49750D01*
G01X345300Y50333D02*
Y47000D01*
G01Y51667D02*
X345133Y51750D01*
Y51917D01*
X345300Y52000D01*
X345467Y51917D01*
Y51750D01*
X345300Y51667D01*
G01X348400Y47000D02*
Y50333D01*
G01Y49417D02*
X348650Y49833D01*
X349067Y50167D01*
X349650Y50333D01*
X350233Y50167D01*
X350650Y49833D01*
X350900Y49417D01*
Y47000D01*
G01Y49417D02*
X351150Y49833D01*
X351567Y50167D01*
X352150Y50333D01*
X352733Y50167D01*
X353150Y49833D01*
X353400Y49333D01*
Y47000D01*
G01X355250Y49250D02*
X357917D01*
X357667Y49833D01*
X357250Y50167D01*
X356667Y50333D01*
X356083Y50250D01*
X355583Y50000D01*
X355250Y49417D01*
X355083Y48917D01*
Y48417D01*
X355250Y47917D01*
X355667Y47417D01*
X356167Y47083D01*
X356750Y47000D01*
X357333Y47167D01*
X357917Y47667D01*
G01X360683Y47000D02*
Y50333D01*
G01Y49500D02*
X361017Y49917D01*
X361517Y50250D01*
X362183Y50333D01*
X362767Y50250D01*
X363267Y49917D01*
X363517Y49333D01*
Y47000D01*
G01X366450Y47583D02*
X366867Y47250D01*
X367450Y47000D01*
X367950D01*
X368450Y47167D01*
X368783Y47417D01*
X368950Y47750D01*
X368867Y48250D01*
X368533Y48500D01*
X367033Y49000D01*
X366700Y49583D01*
X366867Y50000D01*
X367200Y50250D01*
X367700Y50333D01*
X368200Y50250D01*
X368700Y50000D01*
G01X373300Y50333D02*
Y47000D01*
G01Y51667D02*
X373133Y51750D01*
Y51917D01*
X373300Y52000D01*
X373467Y51917D01*
Y51750D01*
X373300Y51667D01*
G01X378900Y47000D02*
X378400Y47083D01*
X377900Y47417D01*
X377567Y48000D01*
X377400Y48667D01*
X377567Y49333D01*
X377900Y49917D01*
X378400Y50250D01*
X378900Y50333D01*
X379400Y50250D01*
X379900Y49917D01*
X380233Y49333D01*
X380317Y48667D01*
X380233Y48000D01*
X379900Y47417D01*
X379400Y47083D01*
X378900Y47000D01*
G01X383083D02*
Y50333D01*
G01Y49500D02*
X383417Y49917D01*
X383917Y50250D01*
X384583Y50333D01*
X385167Y50250D01*
X385667Y49917D01*
X385917Y49333D01*
Y47000D01*
G01X395700D02*
X395200Y47083D01*
X394700Y47417D01*
X394367Y48000D01*
X394200Y48667D01*
X394367Y49333D01*
X394700Y49917D01*
X395200Y50250D01*
X395700Y50333D01*
X396200Y50250D01*
X396700Y49917D01*
X397033Y49333D01*
X397117Y48667D01*
X397033Y48000D01*
X396700Y47417D01*
X396200Y47083D01*
X395700Y47000D01*
G01X400800D02*
Y51250D01*
X400967Y51667D01*
X401300Y51917D01*
X401800Y52000D01*
X402300Y51833D01*
X402550Y51417D01*
G01X401550Y50000D02*
X399883D01*
G01X411000Y45333D02*
Y50333D01*
G01Y49583D02*
X411417Y50000D01*
X411833Y50250D01*
X412500Y50333D01*
X413083Y50250D01*
X413667Y49833D01*
X413917Y49250D01*
X414000Y48667D01*
X413917Y48083D01*
X413667Y47500D01*
X413167Y47167D01*
X412500Y47000D01*
X411917Y47083D01*
X411333Y47333D01*
X411000Y47667D01*
G01X419600Y47000D02*
Y50333D01*
G01Y49750D02*
X419267Y50083D01*
X418767Y50250D01*
X418183Y50333D01*
X417600Y50167D01*
X417100Y49833D01*
X416767Y49333D01*
X416600Y48667D01*
X416767Y48000D01*
X417100Y47500D01*
X417600Y47167D01*
X418183Y47000D01*
X418767Y47083D01*
X419267Y47333D01*
X419600Y47667D01*
G01X425200Y52000D02*
Y47000D01*
G01Y47750D02*
X424867Y47333D01*
X424367Y47083D01*
X423783Y47000D01*
X423117Y47167D01*
X422617Y47583D01*
X422283Y48083D01*
X422200Y48667D01*
X422283Y49250D01*
X422617Y49750D01*
X423117Y50167D01*
X423783Y50333D01*
X424367Y50250D01*
X424783Y50083D01*
X425200Y49750D01*
G01X434900Y47000D02*
X434400Y47083D01*
X433900Y47417D01*
X433567Y48000D01*
X433400Y48667D01*
X433567Y49333D01*
X433900Y49917D01*
X434400Y50250D01*
X434900Y50333D01*
X435400Y50250D01*
X435900Y49917D01*
X436233Y49333D01*
X436317Y48667D01*
X436233Y48000D01*
X435900Y47417D01*
X435400Y47083D01*
X434900Y47000D01*
G01X439333D02*
Y50333D01*
G01Y49667D02*
X439750Y50000D01*
X440167Y50250D01*
X440750Y50333D01*
X441167Y50250D01*
X441667Y50000D01*
G01X453200Y52000D02*
Y47000D01*
G01Y47750D02*
X452867Y47333D01*
X452367Y47083D01*
X451783Y47000D01*
X451117Y47167D01*
X450617Y47583D01*
X450283Y48083D01*
X450200Y48667D01*
X450283Y49250D01*
X450617Y49750D01*
X451117Y50167D01*
X451783Y50333D01*
X452367Y50250D01*
X452783Y50083D01*
X453200Y49750D01*
G01X457300Y50333D02*
Y47000D01*
G01Y51667D02*
X457133Y51750D01*
Y51917D01*
X457300Y52000D01*
X457467Y51917D01*
Y51750D01*
X457300Y51667D01*
G01X464400Y47000D02*
Y50333D01*
G01Y49750D02*
X464067Y50083D01*
X463567Y50250D01*
X462983Y50333D01*
X462400Y50167D01*
X461900Y49833D01*
X461567Y49333D01*
X461400Y48667D01*
X461567Y48000D01*
X461900Y47500D01*
X462400Y47167D01*
X462983Y47000D01*
X463567Y47083D01*
X464067Y47333D01*
X464400Y47667D01*
G01X466000Y47000D02*
Y50333D01*
G01Y49417D02*
X466250Y49833D01*
X466667Y50167D01*
X467250Y50333D01*
X467833Y50167D01*
X468250Y49833D01*
X468500Y49417D01*
Y47000D01*
G01Y49417D02*
X468750Y49833D01*
X469167Y50167D01*
X469750Y50333D01*
X470333Y50167D01*
X470750Y49833D01*
X471000Y49333D01*
Y47000D01*
G01X472850Y49250D02*
X475517D01*
X475267Y49833D01*
X474850Y50167D01*
X474267Y50333D01*
X473683Y50250D01*
X473183Y50000D01*
X472850Y49417D01*
X472683Y48917D01*
Y48417D01*
X472850Y47917D01*
X473267Y47417D01*
X473767Y47083D01*
X474350Y47000D01*
X474933Y47167D01*
X475517Y47667D01*
G01X479700Y52000D02*
Y47000D01*
G01X478533Y50333D02*
X480867D01*
G01X484050Y49250D02*
X486717D01*
X486467Y49833D01*
X486050Y50167D01*
X485467Y50333D01*
X484883Y50250D01*
X484383Y50000D01*
X484050Y49417D01*
X483883Y48917D01*
Y48417D01*
X484050Y47917D01*
X484467Y47417D01*
X484967Y47083D01*
X485550Y47000D01*
X486133Y47167D01*
X486717Y47667D01*
G01X489733Y47000D02*
Y50333D01*
G01Y49667D02*
X490150Y50000D01*
X490567Y50250D01*
X491150Y50333D01*
X491567Y50250D01*
X492067Y50000D01*
G01X500433Y47000D02*
X503767Y48667D01*
X500433Y50333D01*
G01X513300Y47000D02*
Y52000D01*
X512300Y51000D01*
G01Y47000D02*
X514300D01*
G01X519900D02*
Y52000D01*
X516817Y48417D01*
X520983D01*
G01X527600Y47000D02*
Y50333D01*
G01Y49417D02*
X527850Y49833D01*
X528267Y50167D01*
X528850Y50333D01*
X529433Y50167D01*
X529850Y49833D01*
X530100Y49417D01*
Y47000D01*
G01Y49417D02*
X530350Y49833D01*
X530767Y50167D01*
X531350Y50333D01*
X531933Y50167D01*
X532350Y49833D01*
X532600Y49333D01*
Y47000D01*
G01X535700Y50333D02*
Y47000D01*
G01Y51667D02*
X535533Y51750D01*
Y51917D01*
X535700Y52000D01*
X535867Y51917D01*
Y51750D01*
X535700Y51667D01*
G01X541300Y47000D02*
Y52000D01*
G01X273580Y32670D02*
Y27670D01*
G01X271663Y32670D02*
X275497D01*
G01X277763Y27670D02*
Y32670D01*
G01Y30253D02*
X278180Y30670D01*
X278597Y30920D01*
X279263Y31003D01*
X279763Y30920D01*
X280347Y30587D01*
X280597Y30087D01*
Y27670D01*
G01X283530Y29920D02*
X286197D01*
X285947Y30503D01*
X285530Y30837D01*
X284947Y31003D01*
X284363Y30920D01*
X283863Y30670D01*
X283530Y30087D01*
X283363Y29587D01*
Y29087D01*
X283530Y28587D01*
X283947Y28087D01*
X284447Y27753D01*
X285030Y27670D01*
X285613Y27837D01*
X286197Y28337D01*
G01X295980Y27670D02*
Y32670D01*
G01X303080Y27670D02*
Y31003D01*
G01Y30420D02*
X302747Y30753D01*
X302247Y30920D01*
X301663Y31003D01*
X301080Y30837D01*
X300580Y30503D01*
X300247Y30003D01*
X300080Y29337D01*
X300247Y28670D01*
X300580Y28170D01*
X301080Y27837D01*
X301663Y27670D01*
X302247Y27753D01*
X302747Y28003D01*
X303080Y28337D01*
G01X306013Y27670D02*
Y31003D01*
G01Y30337D02*
X306430Y30670D01*
X306847Y30920D01*
X307430Y31003D01*
X307847Y30920D01*
X308347Y30670D01*
G01X311613Y26420D02*
X312197Y26087D01*
X312863Y26003D01*
X313447Y26087D01*
X313947Y26503D01*
X314280Y27087D01*
Y31003D01*
G01Y30337D02*
X313947Y30670D01*
X313447Y30920D01*
X312863Y31003D01*
X312197Y30837D01*
X311780Y30503D01*
X311447Y29920D01*
X311280Y29337D01*
X311363Y28837D01*
X311697Y28253D01*
X312197Y27837D01*
X312863Y27670D01*
X313363Y27753D01*
X313947Y28087D01*
X314280Y28420D01*
G01X317130Y29920D02*
X319797D01*
X319547Y30503D01*
X319130Y30837D01*
X318547Y31003D01*
X317963Y30920D01*
X317463Y30670D01*
X317130Y30087D01*
X316963Y29587D01*
Y29087D01*
X317130Y28587D01*
X317547Y28087D01*
X318047Y27753D01*
X318630Y27670D01*
X319213Y27837D01*
X319797Y28337D01*
G01X322730Y28253D02*
X323147Y27920D01*
X323730Y27670D01*
X324230D01*
X324730Y27837D01*
X325063Y28087D01*
X325230Y28420D01*
X325147Y28920D01*
X324813Y29170D01*
X323313Y29670D01*
X322980Y30253D01*
X323147Y30670D01*
X323480Y30920D01*
X323980Y31003D01*
X324480Y30920D01*
X324980Y30670D01*
G01X329580Y32670D02*
Y27670D01*
G01X328413Y31003D02*
X330747D01*
G01X342280Y32670D02*
Y27670D01*
G01Y28420D02*
X341947Y28003D01*
X341447Y27753D01*
X340863Y27670D01*
X340197Y27837D01*
X339697Y28253D01*
X339363Y28753D01*
X339280Y29337D01*
X339363Y29920D01*
X339697Y30420D01*
X340197Y30837D01*
X340863Y31003D01*
X341447Y30920D01*
X341863Y30753D01*
X342280Y30420D01*
G01X346380Y31003D02*
Y27670D01*
G01Y32337D02*
X346213Y32420D01*
Y32587D01*
X346380Y32670D01*
X346547Y32587D01*
Y32420D01*
X346380Y32337D01*
G01X349480Y27670D02*
Y31003D01*
G01Y30087D02*
X349730Y30503D01*
X350147Y30837D01*
X350730Y31003D01*
X351313Y30837D01*
X351730Y30503D01*
X351980Y30087D01*
Y27670D01*
G01Y30087D02*
X352230Y30503D01*
X352647Y30837D01*
X353230Y31003D01*
X353813Y30837D01*
X354230Y30503D01*
X354480Y30003D01*
Y27670D01*
G01X356330Y29920D02*
X358997D01*
X358747Y30503D01*
X358330Y30837D01*
X357747Y31003D01*
X357163Y30920D01*
X356663Y30670D01*
X356330Y30087D01*
X356163Y29587D01*
Y29087D01*
X356330Y28587D01*
X356747Y28087D01*
X357247Y27753D01*
X357830Y27670D01*
X358413Y27837D01*
X358997Y28337D01*
G01X361763Y27670D02*
Y31003D01*
G01Y30170D02*
X362097Y30587D01*
X362597Y30920D01*
X363263Y31003D01*
X363847Y30920D01*
X364347Y30587D01*
X364597Y30003D01*
Y27670D01*
G01X367530Y28253D02*
X367947Y27920D01*
X368530Y27670D01*
X369030D01*
X369530Y27837D01*
X369863Y28087D01*
X370030Y28420D01*
X369947Y28920D01*
X369613Y29170D01*
X368113Y29670D01*
X367780Y30253D01*
X367947Y30670D01*
X368280Y30920D01*
X368780Y31003D01*
X369280Y30920D01*
X369780Y30670D01*
G01X374380Y31003D02*
Y27670D01*
G01Y32337D02*
X374213Y32420D01*
Y32587D01*
X374380Y32670D01*
X374547Y32587D01*
Y32420D01*
X374380Y32337D01*
G01X379980Y27670D02*
X379480Y27753D01*
X378980Y28087D01*
X378647Y28670D01*
X378480Y29337D01*
X378647Y30003D01*
X378980Y30587D01*
X379480Y30920D01*
X379980Y31003D01*
X380480Y30920D01*
X380980Y30587D01*
X381313Y30003D01*
X381397Y29337D01*
X381313Y28670D01*
X380980Y28087D01*
X380480Y27753D01*
X379980Y27670D01*
G01X384163D02*
Y31003D01*
G01Y30170D02*
X384497Y30587D01*
X384997Y30920D01*
X385663Y31003D01*
X386247Y30920D01*
X386747Y30587D01*
X386997Y30003D01*
Y27670D01*
G01X396780D02*
X396280Y27753D01*
X395780Y28087D01*
X395447Y28670D01*
X395280Y29337D01*
X395447Y30003D01*
X395780Y30587D01*
X396280Y30920D01*
X396780Y31003D01*
X397280Y30920D01*
X397780Y30587D01*
X398113Y30003D01*
X398197Y29337D01*
X398113Y28670D01*
X397780Y28087D01*
X397280Y27753D01*
X396780Y27670D01*
G01X401880D02*
Y31920D01*
X402047Y32337D01*
X402380Y32587D01*
X402880Y32670D01*
X403380Y32503D01*
X403630Y32087D01*
G01X402630Y30670D02*
X400963D01*
G01X412080Y26003D02*
Y31003D01*
G01Y30253D02*
X412497Y30670D01*
X412913Y30920D01*
X413580Y31003D01*
X414163Y30920D01*
X414747Y30503D01*
X414997Y29920D01*
X415080Y29337D01*
X414997Y28753D01*
X414747Y28170D01*
X414247Y27837D01*
X413580Y27670D01*
X412997Y27753D01*
X412413Y28003D01*
X412080Y28337D01*
G01X420680Y27670D02*
Y31003D01*
G01Y30420D02*
X420347Y30753D01*
X419847Y30920D01*
X419263Y31003D01*
X418680Y30837D01*
X418180Y30503D01*
X417847Y30003D01*
X417680Y29337D01*
X417847Y28670D01*
X418180Y28170D01*
X418680Y27837D01*
X419263Y27670D01*
X419847Y27753D01*
X420347Y28003D01*
X420680Y28337D01*
G01X426280Y32670D02*
Y27670D01*
G01Y28420D02*
X425947Y28003D01*
X425447Y27753D01*
X424863Y27670D01*
X424197Y27837D01*
X423697Y28253D01*
X423363Y28753D01*
X423280Y29337D01*
X423363Y29920D01*
X423697Y30420D01*
X424197Y30837D01*
X424863Y31003D01*
X425447Y30920D01*
X425863Y30753D01*
X426280Y30420D01*
G01X435980Y27670D02*
X435480Y27753D01*
X434980Y28087D01*
X434647Y28670D01*
X434480Y29337D01*
X434647Y30003D01*
X434980Y30587D01*
X435480Y30920D01*
X435980Y31003D01*
X436480Y30920D01*
X436980Y30587D01*
X437313Y30003D01*
X437397Y29337D01*
X437313Y28670D01*
X436980Y28087D01*
X436480Y27753D01*
X435980Y27670D01*
G01X440413D02*
Y31003D01*
G01Y30337D02*
X440830Y30670D01*
X441247Y30920D01*
X441830Y31003D01*
X442247Y30920D01*
X442747Y30670D01*
G01X454280Y32670D02*
Y27670D01*
G01Y28420D02*
X453947Y28003D01*
X453447Y27753D01*
X452863Y27670D01*
X452197Y27837D01*
X451697Y28253D01*
X451363Y28753D01*
X451280Y29337D01*
X451363Y29920D01*
X451697Y30420D01*
X452197Y30837D01*
X452863Y31003D01*
X453447Y30920D01*
X453863Y30753D01*
X454280Y30420D01*
G01X458380Y31003D02*
Y27670D01*
G01Y32337D02*
X458213Y32420D01*
Y32587D01*
X458380Y32670D01*
X458547Y32587D01*
Y32420D01*
X458380Y32337D01*
G01X465480Y27670D02*
Y31003D01*
G01Y30420D02*
X465147Y30753D01*
X464647Y30920D01*
X464063Y31003D01*
X463480Y30837D01*
X462980Y30503D01*
X462647Y30003D01*
X462480Y29337D01*
X462647Y28670D01*
X462980Y28170D01*
X463480Y27837D01*
X464063Y27670D01*
X464647Y27753D01*
X465147Y28003D01*
X465480Y28337D01*
G01X467080Y27670D02*
Y31003D01*
G01Y30087D02*
X467330Y30503D01*
X467747Y30837D01*
X468330Y31003D01*
X468913Y30837D01*
X469330Y30503D01*
X469580Y30087D01*
Y27670D01*
G01Y30087D02*
X469830Y30503D01*
X470247Y30837D01*
X470830Y31003D01*
X471413Y30837D01*
X471830Y30503D01*
X472080Y30003D01*
Y27670D01*
G01X473930Y29920D02*
X476597D01*
X476347Y30503D01*
X475930Y30837D01*
X475347Y31003D01*
X474763Y30920D01*
X474263Y30670D01*
X473930Y30087D01*
X473763Y29587D01*
Y29087D01*
X473930Y28587D01*
X474347Y28087D01*
X474847Y27753D01*
X475430Y27670D01*
X476013Y27837D01*
X476597Y28337D01*
G01X480780Y32670D02*
Y27670D01*
G01X479613Y31003D02*
X481947D01*
G01X485130Y29920D02*
X487797D01*
X487547Y30503D01*
X487130Y30837D01*
X486547Y31003D01*
X485963Y30920D01*
X485463Y30670D01*
X485130Y30087D01*
X484963Y29587D01*
Y29087D01*
X485130Y28587D01*
X485547Y28087D01*
X486047Y27753D01*
X486630Y27670D01*
X487213Y27837D01*
X487797Y28337D01*
G01X490813Y27670D02*
Y31003D01*
G01Y30337D02*
X491230Y30670D01*
X491647Y30920D01*
X492230Y31003D01*
X492647Y30920D01*
X493147Y30670D01*
G01X504847Y27670D02*
X501513Y29337D01*
X504847Y31003D01*
G01X507697Y28587D02*
X509863D01*
G01Y30087D02*
X507697D01*
G01X519980Y27670D02*
Y32670D01*
X518980Y31670D01*
G01Y27670D02*
X520980D01*
G01X526580D02*
Y32670D01*
X523497Y29087D01*
X527663D01*
G01X534280Y27670D02*
Y31003D01*
G01Y30087D02*
X534530Y30503D01*
X534947Y30837D01*
X535530Y31003D01*
X536113Y30837D01*
X536530Y30503D01*
X536780Y30087D01*
Y27670D01*
G01Y30087D02*
X537030Y30503D01*
X537447Y30837D01*
X538030Y31003D01*
X538613Y30837D01*
X539030Y30503D01*
X539280Y30003D01*
Y27670D01*
G01X542380Y31003D02*
Y27670D01*
G01Y32337D02*
X542213Y32420D01*
Y32587D01*
X542380Y32670D01*
X542547Y32587D01*
Y32420D01*
X542380Y32337D01*
G01X547980Y27670D02*
Y32670D01*
G01X271250Y141583D02*
X271667Y141250D01*
X272250Y141000D01*
X272750D01*
X273250Y141167D01*
X273583Y141417D01*
X273750Y141750D01*
X273667Y142250D01*
X273333Y142500D01*
X271833Y143000D01*
X271500Y143583D01*
X271667Y144000D01*
X272000Y144250D01*
X272500Y144333D01*
X273000Y144250D01*
X273500Y144000D01*
G01X276600Y139333D02*
Y144333D01*
G01Y143583D02*
X277017Y144000D01*
X277433Y144250D01*
X278100Y144333D01*
X278683Y144250D01*
X279267Y143833D01*
X279517Y143250D01*
X279600Y142667D01*
X279517Y142083D01*
X279267Y141500D01*
X278767Y141167D01*
X278100Y141000D01*
X277517Y141083D01*
X276933Y141333D01*
X276600Y141667D01*
G01X282450Y143250D02*
X285117D01*
X284867Y143833D01*
X284450Y144167D01*
X283867Y144333D01*
X283283Y144250D01*
X282783Y144000D01*
X282450Y143417D01*
X282283Y142917D01*
Y142417D01*
X282450Y141917D01*
X282867Y141417D01*
X283367Y141083D01*
X283950Y141000D01*
X284533Y141167D01*
X285117Y141667D01*
G01X290633Y143917D02*
X290050Y144250D01*
X289550Y144333D01*
X288883Y144167D01*
X288383Y143833D01*
X288050Y143250D01*
X287967Y142667D01*
X288050Y142083D01*
X288383Y141583D01*
X288883Y141167D01*
X289550Y141000D01*
X290133Y141167D01*
X290633Y141500D01*
G01X294900Y144333D02*
Y141000D01*
G01Y145667D02*
X294733Y145750D01*
Y145917D01*
X294900Y146000D01*
X295067Y145917D01*
Y145750D01*
X294900Y145667D01*
G01X300000Y141000D02*
Y145250D01*
X300167Y145667D01*
X300500Y145917D01*
X301000Y146000D01*
X301500Y145833D01*
X301750Y145417D01*
G01X300750Y144000D02*
X299083D01*
G01X306100Y144333D02*
Y141000D01*
G01Y145667D02*
X305933Y145750D01*
Y145917D01*
X306100Y146000D01*
X306267Y145917D01*
Y145750D01*
X306100Y145667D01*
G01X313033Y143917D02*
X312450Y144250D01*
X311950Y144333D01*
X311283Y144167D01*
X310783Y143833D01*
X310450Y143250D01*
X310367Y142667D01*
X310450Y142083D01*
X310783Y141583D01*
X311283Y141167D01*
X311950Y141000D01*
X312533Y141167D01*
X313033Y141500D01*
G01X318800Y141000D02*
Y144333D01*
G01Y143750D02*
X318467Y144083D01*
X317967Y144250D01*
X317383Y144333D01*
X316800Y144167D01*
X316300Y143833D01*
X315967Y143333D01*
X315800Y142667D01*
X315967Y142000D01*
X316300Y141500D01*
X316800Y141167D01*
X317383Y141000D01*
X317967Y141083D01*
X318467Y141333D01*
X318800Y141667D01*
G01X322900Y146000D02*
Y141000D01*
G01X321733Y144333D02*
X324067D01*
G01X328500D02*
Y141000D01*
G01Y145667D02*
X328333Y145750D01*
Y145917D01*
X328500Y146000D01*
X328667Y145917D01*
Y145750D01*
X328500Y145667D01*
G01X334100Y141000D02*
X333600Y141083D01*
X333100Y141417D01*
X332767Y142000D01*
X332600Y142667D01*
X332767Y143333D01*
X333100Y143917D01*
X333600Y144250D01*
X334100Y144333D01*
X334600Y144250D01*
X335100Y143917D01*
X335433Y143333D01*
X335517Y142667D01*
X335433Y142000D01*
X335100Y141417D01*
X334600Y141083D01*
X334100Y141000D01*
G01X338283D02*
Y144333D01*
G01Y143500D02*
X338617Y143917D01*
X339117Y144250D01*
X339783Y144333D01*
X340367Y144250D01*
X340867Y143917D01*
X341117Y143333D01*
Y141000D01*
G01X345300Y140833D02*
X345133Y140917D01*
Y141083D01*
X345300Y141167D01*
X345467Y141083D01*
Y140917D01*
X345300Y140833D01*
G01X270833Y110000D02*
Y115000D01*
X272917D01*
X273583Y114750D01*
X274000Y114417D01*
X274167Y113750D01*
X274000Y113083D01*
X273500Y112667D01*
X272917Y112417D01*
X270833D01*
G01X272917D02*
X274167Y110000D01*
G01X276850Y112250D02*
X279517D01*
X279267Y112833D01*
X278850Y113167D01*
X278267Y113333D01*
X277683Y113250D01*
X277183Y113000D01*
X276850Y112417D01*
X276683Y111917D01*
Y111417D01*
X276850Y110917D01*
X277267Y110417D01*
X277767Y110083D01*
X278350Y110000D01*
X278933Y110167D01*
X279517Y110667D01*
G01X283700Y110000D02*
Y115000D01*
G01X290800Y110000D02*
Y113333D01*
G01Y112750D02*
X290467Y113083D01*
X289967Y113250D01*
X289383Y113333D01*
X288800Y113167D01*
X288300Y112833D01*
X287967Y112333D01*
X287800Y111667D01*
X287967Y111000D01*
X288300Y110500D01*
X288800Y110167D01*
X289383Y110000D01*
X289967Y110083D01*
X290467Y110333D01*
X290800Y110667D01*
G01X294900Y115000D02*
Y110000D01*
G01X293733Y113333D02*
X296067D01*
G01X300500D02*
Y110000D01*
G01Y114667D02*
X300333Y114750D01*
Y114917D01*
X300500Y115000D01*
X300667Y114917D01*
Y114750D01*
X300500Y114667D01*
G01X304600Y113333D02*
X306100Y110000D01*
X307600Y113333D01*
G01X310450Y112250D02*
X313117D01*
X312867Y112833D01*
X312450Y113167D01*
X311867Y113333D01*
X311283Y113250D01*
X310783Y113000D01*
X310450Y112417D01*
X310283Y111917D01*
Y111417D01*
X310450Y110917D01*
X310867Y110417D01*
X311367Y110083D01*
X311950Y110000D01*
X312533Y110167D01*
X313117Y110667D01*
G01X321400Y108333D02*
Y113333D01*
G01Y112583D02*
X321817Y113000D01*
X322233Y113250D01*
X322900Y113333D01*
X323483Y113250D01*
X324067Y112833D01*
X324317Y112250D01*
X324400Y111667D01*
X324317Y111083D01*
X324067Y110500D01*
X323567Y110167D01*
X322900Y110000D01*
X322317Y110083D01*
X321733Y110333D01*
X321400Y110667D01*
G01X328500Y110000D02*
X328000Y110083D01*
X327500Y110417D01*
X327167Y111000D01*
X327000Y111667D01*
X327167Y112333D01*
X327500Y112917D01*
X328000Y113250D01*
X328500Y113333D01*
X329000Y113250D01*
X329500Y112917D01*
X329833Y112333D01*
X329917Y111667D01*
X329833Y111000D01*
X329500Y110417D01*
X329000Y110083D01*
X328500Y110000D01*
G01X332850Y110583D02*
X333267Y110250D01*
X333850Y110000D01*
X334350D01*
X334850Y110167D01*
X335183Y110417D01*
X335350Y110750D01*
X335267Y111250D01*
X334933Y111500D01*
X333433Y112000D01*
X333100Y112583D01*
X333267Y113000D01*
X333600Y113250D01*
X334100Y113333D01*
X334600Y113250D01*
X335100Y113000D01*
G01X339700Y113333D02*
Y110000D01*
G01Y114667D02*
X339533Y114750D01*
Y114917D01*
X339700Y115000D01*
X339867Y114917D01*
Y114750D01*
X339700Y114667D01*
G01X345300Y115000D02*
Y110000D01*
G01X344133Y113333D02*
X346467D01*
G01X350900D02*
Y110000D01*
G01Y114667D02*
X350733Y114750D01*
Y114917D01*
X350900Y115000D01*
X351067Y114917D01*
Y114750D01*
X350900Y114667D01*
G01X356500Y110000D02*
X356000Y110083D01*
X355500Y110417D01*
X355167Y111000D01*
X355000Y111667D01*
X355167Y112333D01*
X355500Y112917D01*
X356000Y113250D01*
X356500Y113333D01*
X357000Y113250D01*
X357500Y112917D01*
X357833Y112333D01*
X357917Y111667D01*
X357833Y111000D01*
X357500Y110417D01*
X357000Y110083D01*
X356500Y110000D01*
G01X360683D02*
Y113333D01*
G01Y112500D02*
X361017Y112917D01*
X361517Y113250D01*
X362183Y113333D01*
X362767Y113250D01*
X363267Y112917D01*
X363517Y112333D01*
Y110000D01*
G01X371800D02*
Y115000D01*
G01Y112500D02*
X372217Y113000D01*
X372717Y113250D01*
X373217Y113333D01*
X373967Y113167D01*
X374467Y112833D01*
X374800Y112250D01*
Y111583D01*
X374633Y110917D01*
X374300Y110417D01*
X373717Y110083D01*
X373217Y110000D01*
X372717Y110083D01*
X372217Y110333D01*
X371800Y110750D01*
G01X377650Y112250D02*
X380317D01*
X380067Y112833D01*
X379650Y113167D01*
X379067Y113333D01*
X378483Y113250D01*
X377983Y113000D01*
X377650Y112417D01*
X377483Y111917D01*
Y111417D01*
X377650Y110917D01*
X378067Y110417D01*
X378567Y110083D01*
X379150Y110000D01*
X379733Y110167D01*
X380317Y110667D01*
G01X384500Y115000D02*
Y110000D01*
G01X383333Y113333D02*
X385667D01*
G01X388017D02*
X389017Y110000D01*
X390100Y113333D01*
X391183Y110000D01*
X392183Y113333D01*
G01X394450Y112250D02*
X397117D01*
X396867Y112833D01*
X396450Y113167D01*
X395867Y113333D01*
X395283Y113250D01*
X394783Y113000D01*
X394450Y112417D01*
X394283Y111917D01*
Y111417D01*
X394450Y110917D01*
X394867Y110417D01*
X395367Y110083D01*
X395950Y110000D01*
X396533Y110167D01*
X397117Y110667D01*
G01X400050Y112250D02*
X402717D01*
X402467Y112833D01*
X402050Y113167D01*
X401467Y113333D01*
X400883Y113250D01*
X400383Y113000D01*
X400050Y112417D01*
X399883Y111917D01*
Y111417D01*
X400050Y110917D01*
X400467Y110417D01*
X400967Y110083D01*
X401550Y110000D01*
X402133Y110167D01*
X402717Y110667D01*
G01X405483Y110000D02*
Y113333D01*
G01Y112500D02*
X405817Y112917D01*
X406317Y113250D01*
X406983Y113333D01*
X407567Y113250D01*
X408067Y112917D01*
X408317Y112333D01*
Y110000D01*
G01X419600D02*
Y113333D01*
G01Y112750D02*
X419267Y113083D01*
X418767Y113250D01*
X418183Y113333D01*
X417600Y113167D01*
X417100Y112833D01*
X416767Y112333D01*
X416600Y111667D01*
X416767Y111000D01*
X417100Y110500D01*
X417600Y110167D01*
X418183Y110000D01*
X418767Y110083D01*
X419267Y110333D01*
X419600Y110667D01*
G01X422283Y110000D02*
Y113333D01*
G01Y112500D02*
X422617Y112917D01*
X423117Y113250D01*
X423783Y113333D01*
X424367Y113250D01*
X424867Y112917D01*
X425117Y112333D01*
Y110000D01*
G01X427550Y108500D02*
X428050Y108333D01*
X428717Y108500D01*
X429133Y108833D01*
X429467Y109250D01*
X429967Y110583D01*
X431050Y113333D01*
G01X428383D02*
X429967Y110583D01*
G01X439000Y108333D02*
Y113333D01*
G01Y112583D02*
X439417Y113000D01*
X439833Y113250D01*
X440500Y113333D01*
X441083Y113250D01*
X441667Y112833D01*
X441917Y112250D01*
X442000Y111667D01*
X441917Y111083D01*
X441667Y110500D01*
X441167Y110167D01*
X440500Y110000D01*
X439917Y110083D01*
X439333Y110333D01*
X439000Y110667D01*
G01X447600Y110000D02*
Y113333D01*
G01Y112750D02*
X447267Y113083D01*
X446767Y113250D01*
X446183Y113333D01*
X445600Y113167D01*
X445100Y112833D01*
X444767Y112333D01*
X444600Y111667D01*
X444767Y111000D01*
X445100Y110500D01*
X445600Y110167D01*
X446183Y110000D01*
X446767Y110083D01*
X447267Y110333D01*
X447600Y110667D01*
G01X453200Y115000D02*
Y110000D01*
G01Y110750D02*
X452867Y110333D01*
X452367Y110083D01*
X451783Y110000D01*
X451117Y110167D01*
X450617Y110583D01*
X450283Y111083D01*
X450200Y111667D01*
X450283Y112250D01*
X450617Y112750D01*
X451117Y113167D01*
X451783Y113333D01*
X452367Y113250D01*
X452783Y113083D01*
X453200Y112750D01*
G01X462900Y115000D02*
Y110000D01*
G01X461733Y113333D02*
X464067D01*
G01X468500Y110000D02*
X468000Y110083D01*
X467500Y110417D01*
X467167Y111000D01*
X467000Y111667D01*
X467167Y112333D01*
X467500Y112917D01*
X468000Y113250D01*
X468500Y113333D01*
X469000Y113250D01*
X469500Y112917D01*
X469833Y112333D01*
X469917Y111667D01*
X469833Y111000D01*
X469500Y110417D01*
X469000Y110083D01*
X468500Y110000D01*
G01X478200Y108333D02*
Y113333D01*
G01Y112583D02*
X478617Y113000D01*
X479033Y113250D01*
X479700Y113333D01*
X480283Y113250D01*
X480867Y112833D01*
X481117Y112250D01*
X481200Y111667D01*
X481117Y111083D01*
X480867Y110500D01*
X480367Y110167D01*
X479700Y110000D01*
X479117Y110083D01*
X478533Y110333D01*
X478200Y110667D01*
G01X486800Y110000D02*
Y113333D01*
G01Y112750D02*
X486467Y113083D01*
X485967Y113250D01*
X485383Y113333D01*
X484800Y113167D01*
X484300Y112833D01*
X483967Y112333D01*
X483800Y111667D01*
X483967Y111000D01*
X484300Y110500D01*
X484800Y110167D01*
X485383Y110000D01*
X485967Y110083D01*
X486467Y110333D01*
X486800Y110667D01*
G01X492400Y115000D02*
Y110000D01*
G01Y110750D02*
X492067Y110333D01*
X491567Y110083D01*
X490983Y110000D01*
X490317Y110167D01*
X489817Y110583D01*
X489483Y111083D01*
X489400Y111667D01*
X489483Y112250D01*
X489817Y112750D01*
X490317Y113167D01*
X490983Y113333D01*
X491567Y113250D01*
X491983Y113083D01*
X492400Y112750D01*
G01X270750Y125000D02*
Y130000D01*
G01X274250D02*
Y125000D01*
G01Y127500D02*
X270750D01*
G01X276267Y125000D02*
Y130000D01*
X277933D01*
X278600Y129750D01*
X279100Y129417D01*
X279517Y128917D01*
X279850Y128333D01*
X279933Y127500D01*
X279850Y126667D01*
X279517Y126083D01*
X279100Y125583D01*
X278600Y125250D01*
X277933Y125000D01*
X276267D01*
G01X282700Y130000D02*
X284700D01*
G01X283700D02*
Y125000D01*
G01X282700D02*
X284700D01*
G01X293233D02*
Y130000D01*
X295233D01*
X295900Y129750D01*
X296400Y129167D01*
X296567Y128500D01*
X296400Y127833D01*
X295983Y127333D01*
X295233Y127083D01*
X293233D01*
G01X302333Y129583D02*
X301833Y129833D01*
X301250Y130000D01*
X300583D01*
X299833Y129750D01*
X299250Y129333D01*
X298833Y128833D01*
X298500Y128000D01*
X298417Y127250D01*
X298583Y126500D01*
X298833Y126000D01*
X299333Y125500D01*
X299917Y125167D01*
X300500Y125000D01*
X301083D01*
X301667Y125167D01*
X302167Y125417D01*
X302583Y125750D01*
G01X306767Y127667D02*
X307100Y127917D01*
X307350Y128333D01*
X307517Y128917D01*
X307350Y129417D01*
X307017Y129750D01*
X306433Y130000D01*
X304183D01*
Y125000D01*
X306933D01*
X307517Y125333D01*
X307850Y125833D01*
X308017Y126417D01*
X307850Y127000D01*
X307350Y127500D01*
X306767Y127667D01*
X304183D01*
G01X311700Y124833D02*
X311533Y124917D01*
Y125083D01*
X311700Y125167D01*
X311867Y125083D01*
Y124917D01*
X311700Y124833D01*
G01X270750Y150667D02*
X271417Y150250D01*
X272167Y150000D01*
X272833D01*
X273500Y150250D01*
X274000Y150667D01*
X274250Y151250D01*
X274083Y151833D01*
X273667Y152333D01*
X272917Y152667D01*
X271917Y152833D01*
X271333Y153167D01*
X271083Y153750D01*
X271250Y154333D01*
X271667Y154750D01*
X272250Y155000D01*
X272833D01*
X273417Y154833D01*
X273917Y154417D01*
G01X276850Y152250D02*
X279517D01*
X279267Y152833D01*
X278850Y153167D01*
X278267Y153333D01*
X277683Y153250D01*
X277183Y153000D01*
X276850Y152417D01*
X276683Y151917D01*
Y151417D01*
X276850Y150917D01*
X277267Y150417D01*
X277767Y150083D01*
X278350Y150000D01*
X278933Y150167D01*
X279517Y150667D01*
G01X282533Y150000D02*
Y153333D01*
G01Y152667D02*
X282950Y153000D01*
X283367Y153250D01*
X283950Y153333D01*
X284367Y153250D01*
X284867Y153000D01*
G01X287800Y153333D02*
X289300Y150000D01*
X290800Y153333D01*
G01X293650Y152250D02*
X296317D01*
X296067Y152833D01*
X295650Y153167D01*
X295067Y153333D01*
X294483Y153250D01*
X293983Y153000D01*
X293650Y152417D01*
X293483Y151917D01*
Y151417D01*
X293650Y150917D01*
X294067Y150417D01*
X294567Y150083D01*
X295150Y150000D01*
X295733Y150167D01*
X296317Y150667D01*
G01X299333Y150000D02*
Y153333D01*
G01Y152667D02*
X299750Y153000D01*
X300167Y153250D01*
X300750Y153333D01*
X301167Y153250D01*
X301667Y153000D01*
G01X310033Y150000D02*
Y155000D01*
X312033D01*
X312700Y154750D01*
X313200Y154167D01*
X313367Y153500D01*
X313200Y152833D01*
X312783Y152333D01*
X312033Y152083D01*
X310033D01*
G01X319133Y154583D02*
X318633Y154833D01*
X318050Y155000D01*
X317383D01*
X316633Y154750D01*
X316050Y154333D01*
X315633Y153833D01*
X315300Y153000D01*
X315217Y152250D01*
X315383Y151500D01*
X315633Y151000D01*
X316133Y150500D01*
X316717Y150167D01*
X317300Y150000D01*
X317883D01*
X318467Y150167D01*
X318967Y150417D01*
X319383Y150750D01*
G01X323567Y152667D02*
X323900Y152917D01*
X324150Y153333D01*
X324317Y153917D01*
X324150Y154417D01*
X323817Y154750D01*
X323233Y155000D01*
X320983D01*
Y150000D01*
X323733D01*
X324317Y150333D01*
X324650Y150833D01*
X324817Y151417D01*
X324650Y152000D01*
X324150Y152500D01*
X323567Y152667D01*
X320983D01*
G01X328500Y149833D02*
X328333Y149917D01*
Y150083D01*
X328500Y150167D01*
X328667Y150083D01*
Y149917D01*
X328500Y149833D01*
G01Y152083D02*
X328333Y152167D01*
Y152333D01*
X328500Y152417D01*
X328667Y152333D01*
Y152167D01*
X328500Y152083D01*
G01X332517Y150000D02*
Y155000D01*
X335683D01*
G01X334517Y152583D02*
X332517D01*
G01X339700Y150000D02*
X339200Y150083D01*
X338700Y150417D01*
X338367Y151000D01*
X338200Y151667D01*
X338367Y152333D01*
X338700Y152917D01*
X339200Y153250D01*
X339700Y153333D01*
X340200Y153250D01*
X340700Y152917D01*
X341033Y152333D01*
X341117Y151667D01*
X341033Y151000D01*
X340700Y150417D01*
X340200Y150083D01*
X339700Y150000D01*
G01X345300D02*
Y155000D01*
G01X350900Y150000D02*
Y155000D01*
G01X356500Y150000D02*
X356000Y150083D01*
X355500Y150417D01*
X355167Y151000D01*
X355000Y151667D01*
X355167Y152333D01*
X355500Y152917D01*
X356000Y153250D01*
X356500Y153333D01*
X357000Y153250D01*
X357500Y152917D01*
X357833Y152333D01*
X357917Y151667D01*
X357833Y151000D01*
X357500Y150417D01*
X357000Y150083D01*
X356500Y150000D01*
G01X360017Y153333D02*
X361017Y150000D01*
X362100Y153333D01*
X363183Y150000D01*
X364183Y153333D01*
G01X372133Y150000D02*
Y153333D01*
G01Y152667D02*
X372550Y153000D01*
X372967Y153250D01*
X373550Y153333D01*
X373967Y153250D01*
X374467Y153000D01*
G01X378900Y153333D02*
Y150000D01*
G01Y154667D02*
X378733Y154750D01*
Y154917D01*
X378900Y155000D01*
X379067Y154917D01*
Y154750D01*
X378900Y154667D01*
G01X383333Y148750D02*
X383917Y148417D01*
X384583Y148333D01*
X385167Y148417D01*
X385667Y148833D01*
X386000Y149417D01*
Y153333D01*
G01Y152667D02*
X385667Y153000D01*
X385167Y153250D01*
X384583Y153333D01*
X383917Y153167D01*
X383500Y152833D01*
X383167Y152250D01*
X383000Y151667D01*
X383083Y151167D01*
X383417Y150583D01*
X383917Y150167D01*
X384583Y150000D01*
X385083Y150083D01*
X385667Y150417D01*
X386000Y150750D01*
G01X388683Y150000D02*
Y155000D01*
G01Y152583D02*
X389100Y153000D01*
X389517Y153250D01*
X390183Y153333D01*
X390683Y153250D01*
X391267Y152917D01*
X391517Y152417D01*
Y150000D01*
G01X395700Y155000D02*
Y150000D01*
G01X394533Y153333D02*
X396867D01*
G01X405650Y150583D02*
X406067Y150250D01*
X406650Y150000D01*
X407150D01*
X407650Y150167D01*
X407983Y150417D01*
X408150Y150750D01*
X408067Y151250D01*
X407733Y151500D01*
X406233Y152000D01*
X405900Y152583D01*
X406067Y153000D01*
X406400Y153250D01*
X406900Y153333D01*
X407400Y153250D01*
X407900Y153000D01*
G01X412500Y153333D02*
Y150000D01*
G01Y154667D02*
X412333Y154750D01*
Y154917D01*
X412500Y155000D01*
X412667Y154917D01*
Y154750D01*
X412500Y154667D01*
G01X419600Y155000D02*
Y150000D01*
G01Y150750D02*
X419267Y150333D01*
X418767Y150083D01*
X418183Y150000D01*
X417517Y150167D01*
X417017Y150583D01*
X416683Y151083D01*
X416600Y151667D01*
X416683Y152250D01*
X417017Y152750D01*
X417517Y153167D01*
X418183Y153333D01*
X418767Y153250D01*
X419183Y153083D01*
X419600Y152750D01*
G01X422450Y152250D02*
X425117D01*
X424867Y152833D01*
X424450Y153167D01*
X423867Y153333D01*
X423283Y153250D01*
X422783Y153000D01*
X422450Y152417D01*
X422283Y151917D01*
Y151417D01*
X422450Y150917D01*
X422867Y150417D01*
X423367Y150083D01*
X423950Y150000D01*
X424533Y150167D01*
X425117Y150667D01*
G01X433650Y150583D02*
X434067Y150250D01*
X434650Y150000D01*
X435150D01*
X435650Y150167D01*
X435983Y150417D01*
X436150Y150750D01*
X436067Y151250D01*
X435733Y151500D01*
X434233Y152000D01*
X433900Y152583D01*
X434067Y153000D01*
X434400Y153250D01*
X434900Y153333D01*
X435400Y153250D01*
X435900Y153000D01*
G01X439000Y148333D02*
Y153333D01*
G01Y152583D02*
X439417Y153000D01*
X439833Y153250D01*
X440500Y153333D01*
X441083Y153250D01*
X441667Y152833D01*
X441917Y152250D01*
X442000Y151667D01*
X441917Y151083D01*
X441667Y150500D01*
X441167Y150167D01*
X440500Y150000D01*
X439917Y150083D01*
X439333Y150333D01*
X439000Y150667D01*
G01X444850Y152250D02*
X447517D01*
X447267Y152833D01*
X446850Y153167D01*
X446267Y153333D01*
X445683Y153250D01*
X445183Y153000D01*
X444850Y152417D01*
X444683Y151917D01*
Y151417D01*
X444850Y150917D01*
X445267Y150417D01*
X445767Y150083D01*
X446350Y150000D01*
X446933Y150167D01*
X447517Y150667D01*
G01X453033Y152917D02*
X452450Y153250D01*
X451950Y153333D01*
X451283Y153167D01*
X450783Y152833D01*
X450450Y152250D01*
X450367Y151667D01*
X450450Y151083D01*
X450783Y150583D01*
X451283Y150167D01*
X451950Y150000D01*
X452533Y150167D01*
X453033Y150500D01*
G01X462733Y149083D02*
X463067Y150167D01*
G01X468500Y153333D02*
Y150000D01*
G01Y154667D02*
X468333Y154750D01*
Y154917D01*
X468500Y155000D01*
X468667Y154917D01*
Y154750D01*
X468500Y154667D01*
G01X473600Y150000D02*
Y154250D01*
X473767Y154667D01*
X474100Y154917D01*
X474600Y155000D01*
X475100Y154833D01*
X475350Y154417D01*
G01X474350Y153000D02*
X472683D01*
G01X484050Y150583D02*
X484467Y150250D01*
X485050Y150000D01*
X485550D01*
X486050Y150167D01*
X486383Y150417D01*
X486550Y150750D01*
X486467Y151250D01*
X486133Y151500D01*
X484633Y152000D01*
X484300Y152583D01*
X484467Y153000D01*
X484800Y153250D01*
X485300Y153333D01*
X485800Y153250D01*
X486300Y153000D01*
G01X490900Y155000D02*
Y150000D01*
G01X489733Y153333D02*
X492067D01*
G01X498000Y150000D02*
Y153333D01*
G01Y152750D02*
X497667Y153083D01*
X497167Y153250D01*
X496583Y153333D01*
X496000Y153167D01*
X495500Y152833D01*
X495167Y152333D01*
X495000Y151667D01*
X495167Y151000D01*
X495500Y150500D01*
X496000Y150167D01*
X496583Y150000D01*
X497167Y150083D01*
X497667Y150333D01*
X498000Y150667D01*
G01X503433Y152917D02*
X502850Y153250D01*
X502350Y153333D01*
X501683Y153167D01*
X501183Y152833D01*
X500850Y152250D01*
X500767Y151667D01*
X500850Y151083D01*
X501183Y150583D01*
X501683Y150167D01*
X502350Y150000D01*
X502933Y150167D01*
X503433Y150500D01*
G01X506283Y150000D02*
Y155000D01*
G01X508950Y153333D02*
X506283Y151417D01*
G01X507367Y152167D02*
X509117Y150000D01*
G01X517483Y153333D02*
Y151000D01*
X517817Y150417D01*
X518317Y150083D01*
X518900Y150000D01*
X519483Y150083D01*
X519983Y150417D01*
X520317Y151000D01*
G01Y150000D02*
Y153333D01*
G01X523000Y148333D02*
Y153333D01*
G01Y152583D02*
X523417Y153000D01*
X523833Y153250D01*
X524500Y153333D01*
X525083Y153250D01*
X525667Y152833D01*
X525917Y152250D01*
X526000Y151667D01*
X525917Y151083D01*
X525667Y150500D01*
X525167Y150167D01*
X524500Y150000D01*
X523917Y150083D01*
X523333Y150333D01*
X523000Y150667D01*
G01X533617Y153333D02*
X534617Y150000D01*
X535700Y153333D01*
X536783Y150000D01*
X537783Y153333D01*
G01X541300D02*
Y150000D01*
G01Y154667D02*
X541133Y154750D01*
Y154917D01*
X541300Y155000D01*
X541467Y154917D01*
Y154750D01*
X541300Y154667D01*
G01X546900Y155000D02*
Y150000D01*
G01X545733Y153333D02*
X548067D01*
G01X551083Y150000D02*
Y155000D01*
G01Y152583D02*
X551500Y153000D01*
X551917Y153250D01*
X552583Y153333D01*
X553083Y153250D01*
X553667Y152917D01*
X553917Y152417D01*
Y150000D01*
G01X558100D02*
X557600Y150083D01*
X557100Y150417D01*
X556767Y151000D01*
X556600Y151667D01*
X556767Y152333D01*
X557100Y152917D01*
X557600Y153250D01*
X558100Y153333D01*
X558600Y153250D01*
X559100Y152917D01*
X559433Y152333D01*
X559517Y151667D01*
X559433Y151000D01*
X559100Y150417D01*
X558600Y150083D01*
X558100Y150000D01*
G01X562283Y153333D02*
Y151000D01*
X562617Y150417D01*
X563117Y150083D01*
X563700Y150000D01*
X564283Y150083D01*
X564783Y150417D01*
X565117Y151000D01*
G01Y150000D02*
Y153333D01*
G01X569300Y155000D02*
Y150000D01*
G01X568133Y153333D02*
X570467D01*
G01X272500Y170000D02*
Y165000D01*
G01X270583Y170000D02*
X274417D01*
G01X276933Y165000D02*
Y168333D01*
G01Y167667D02*
X277350Y168000D01*
X277767Y168250D01*
X278350Y168333D01*
X278767Y168250D01*
X279267Y168000D01*
G01X285200Y165000D02*
Y168333D01*
G01Y167750D02*
X284867Y168083D01*
X284367Y168250D01*
X283783Y168333D01*
X283200Y168167D01*
X282700Y167833D01*
X282367Y167333D01*
X282200Y166667D01*
X282367Y166000D01*
X282700Y165500D01*
X283200Y165167D01*
X283783Y165000D01*
X284367Y165083D01*
X284867Y165333D01*
X285200Y165667D01*
G01X290800Y170000D02*
Y165000D01*
G01Y165750D02*
X290467Y165333D01*
X289967Y165083D01*
X289383Y165000D01*
X288717Y165167D01*
X288217Y165583D01*
X287883Y166083D01*
X287800Y166667D01*
X287883Y167250D01*
X288217Y167750D01*
X288717Y168167D01*
X289383Y168333D01*
X289967Y168250D01*
X290383Y168083D01*
X290800Y167750D01*
G01X294900Y168333D02*
Y165000D01*
G01Y169667D02*
X294733Y169750D01*
Y169917D01*
X294900Y170000D01*
X295067Y169917D01*
Y169750D01*
X294900Y169667D01*
G01X300500Y170000D02*
Y165000D01*
G01X299333Y168333D02*
X301667D01*
G01X306100D02*
Y165000D01*
G01Y169667D02*
X305933Y169750D01*
Y169917D01*
X306100Y170000D01*
X306267Y169917D01*
Y169750D01*
X306100Y169667D01*
G01X311700Y165000D02*
X311200Y165083D01*
X310700Y165417D01*
X310367Y166000D01*
X310200Y166667D01*
X310367Y167333D01*
X310700Y167917D01*
X311200Y168250D01*
X311700Y168333D01*
X312200Y168250D01*
X312700Y167917D01*
X313033Y167333D01*
X313117Y166667D01*
X313033Y166000D01*
X312700Y165417D01*
X312200Y165083D01*
X311700Y165000D01*
G01X315883D02*
Y168333D01*
G01Y167500D02*
X316217Y167917D01*
X316717Y168250D01*
X317383Y168333D01*
X317967Y168250D01*
X318467Y167917D01*
X318717Y167333D01*
Y165000D01*
G01X324400D02*
Y168333D01*
G01Y167750D02*
X324067Y168083D01*
X323567Y168250D01*
X322983Y168333D01*
X322400Y168167D01*
X321900Y167833D01*
X321567Y167333D01*
X321400Y166667D01*
X321567Y166000D01*
X321900Y165500D01*
X322400Y165167D01*
X322983Y165000D01*
X323567Y165083D01*
X324067Y165333D01*
X324400Y165667D01*
G01X328500Y165000D02*
Y170000D01*
G01X338033Y165000D02*
Y170000D01*
X340033D01*
X340700Y169750D01*
X341200Y169167D01*
X341367Y168500D01*
X341200Y167833D01*
X340783Y167333D01*
X340033Y167083D01*
X338033D01*
G01X347133Y169583D02*
X346633Y169833D01*
X346050Y170000D01*
X345383D01*
X344633Y169750D01*
X344050Y169333D01*
X343633Y168833D01*
X343300Y168000D01*
X343217Y167250D01*
X343383Y166500D01*
X343633Y166000D01*
X344133Y165500D01*
X344717Y165167D01*
X345300Y165000D01*
X345883D01*
X346467Y165167D01*
X346967Y165417D01*
X347383Y165750D01*
G01X351567Y167667D02*
X351900Y167917D01*
X352150Y168333D01*
X352317Y168917D01*
X352150Y169417D01*
X351817Y169750D01*
X351233Y170000D01*
X348983D01*
Y165000D01*
X351733D01*
X352317Y165333D01*
X352650Y165833D01*
X352817Y166417D01*
X352650Y167000D01*
X352150Y167500D01*
X351567Y167667D01*
X348983D01*
G01X356500Y164833D02*
X356333Y164917D01*
Y165083D01*
X356500Y165167D01*
X356667Y165083D01*
Y164917D01*
X356500Y164833D01*
G01X271250Y141583D02*
X271667Y141250D01*
X272250Y141000D01*
X272750D01*
X273250Y141167D01*
X273583Y141417D01*
X273750Y141750D01*
X273667Y142250D01*
X273333Y142500D01*
X271833Y143000D01*
X271500Y143583D01*
X271667Y144000D01*
X272000Y144250D01*
X272500Y144333D01*
X273000Y144250D01*
X273500Y144000D01*
G01X276600Y139333D02*
Y144333D01*
G01Y143583D02*
X277017Y144000D01*
X277433Y144250D01*
X278100Y144333D01*
X278683Y144250D01*
X279267Y143833D01*
X279517Y143250D01*
X279600Y142667D01*
X279517Y142083D01*
X279267Y141500D01*
X278767Y141167D01*
X278100Y141000D01*
X277517Y141083D01*
X276933Y141333D01*
X276600Y141667D01*
G01X282450Y143250D02*
X285117D01*
X284867Y143833D01*
X284450Y144167D01*
X283867Y144333D01*
X283283Y144250D01*
X282783Y144000D01*
X282450Y143417D01*
X282283Y142917D01*
Y142417D01*
X282450Y141917D01*
X282867Y141417D01*
X283367Y141083D01*
X283950Y141000D01*
X284533Y141167D01*
X285117Y141667D01*
G01X290633Y143917D02*
X290050Y144250D01*
X289550Y144333D01*
X288883Y144167D01*
X288383Y143833D01*
X288050Y143250D01*
X287967Y142667D01*
X288050Y142083D01*
X288383Y141583D01*
X288883Y141167D01*
X289550Y141000D01*
X290133Y141167D01*
X290633Y141500D01*
G01X294900Y144333D02*
Y141000D01*
G01Y145667D02*
X294733Y145750D01*
Y145917D01*
X294900Y146000D01*
X295067Y145917D01*
Y145750D01*
X294900Y145667D01*
G01X300000Y141000D02*
Y145250D01*
X300167Y145667D01*
X300500Y145917D01*
X301000Y146000D01*
X301500Y145833D01*
X301750Y145417D01*
G01X300750Y144000D02*
X299083D01*
G01X306100Y144333D02*
Y141000D01*
G01Y145667D02*
X305933Y145750D01*
Y145917D01*
X306100Y146000D01*
X306267Y145917D01*
Y145750D01*
X306100Y145667D01*
G01X313033Y143917D02*
X312450Y144250D01*
X311950Y144333D01*
X311283Y144167D01*
X310783Y143833D01*
X310450Y143250D01*
X310367Y142667D01*
X310450Y142083D01*
X310783Y141583D01*
X311283Y141167D01*
X311950Y141000D01*
X312533Y141167D01*
X313033Y141500D01*
G01X318800Y141000D02*
Y144333D01*
G01Y143750D02*
X318467Y144083D01*
X317967Y144250D01*
X317383Y144333D01*
X316800Y144167D01*
X316300Y143833D01*
X315967Y143333D01*
X315800Y142667D01*
X315967Y142000D01*
X316300Y141500D01*
X316800Y141167D01*
X317383Y141000D01*
X317967Y141083D01*
X318467Y141333D01*
X318800Y141667D01*
G01X322900Y146000D02*
Y141000D01*
G01X321733Y144333D02*
X324067D01*
G01X328500D02*
Y141000D01*
G01Y145667D02*
X328333Y145750D01*
Y145917D01*
X328500Y146000D01*
X328667Y145917D01*
Y145750D01*
X328500Y145667D01*
G01X334100Y141000D02*
X333600Y141083D01*
X333100Y141417D01*
X332767Y142000D01*
X332600Y142667D01*
X332767Y143333D01*
X333100Y143917D01*
X333600Y144250D01*
X334100Y144333D01*
X334600Y144250D01*
X335100Y143917D01*
X335433Y143333D01*
X335517Y142667D01*
X335433Y142000D01*
X335100Y141417D01*
X334600Y141083D01*
X334100Y141000D01*
G01X338283D02*
Y144333D01*
G01Y143500D02*
X338617Y143917D01*
X339117Y144250D01*
X339783Y144333D01*
X340367Y144250D01*
X340867Y143917D01*
X341117Y143333D01*
Y141000D01*
G01X345300Y140833D02*
X345133Y140917D01*
Y141083D01*
X345300Y141167D01*
X345467Y141083D01*
Y140917D01*
X345300Y140833D01*
G01X270833Y110000D02*
Y115000D01*
X272917D01*
X273583Y114750D01*
X274000Y114417D01*
X274167Y113750D01*
X274000Y113083D01*
X273500Y112667D01*
X272917Y112417D01*
X270833D01*
G01X272917D02*
X274167Y110000D01*
G01X276850Y112250D02*
X279517D01*
X279267Y112833D01*
X278850Y113167D01*
X278267Y113333D01*
X277683Y113250D01*
X277183Y113000D01*
X276850Y112417D01*
X276683Y111917D01*
Y111417D01*
X276850Y110917D01*
X277267Y110417D01*
X277767Y110083D01*
X278350Y110000D01*
X278933Y110167D01*
X279517Y110667D01*
G01X283700Y110000D02*
Y115000D01*
G01X290800Y110000D02*
Y113333D01*
G01Y112750D02*
X290467Y113083D01*
X289967Y113250D01*
X289383Y113333D01*
X288800Y113167D01*
X288300Y112833D01*
X287967Y112333D01*
X287800Y111667D01*
X287967Y111000D01*
X288300Y110500D01*
X288800Y110167D01*
X289383Y110000D01*
X289967Y110083D01*
X290467Y110333D01*
X290800Y110667D01*
G01X294900Y115000D02*
Y110000D01*
G01X293733Y113333D02*
X296067D01*
G01X300500D02*
Y110000D01*
G01Y114667D02*
X300333Y114750D01*
Y114917D01*
X300500Y115000D01*
X300667Y114917D01*
Y114750D01*
X300500Y114667D01*
G01X304600Y113333D02*
X306100Y110000D01*
X307600Y113333D01*
G01X310450Y112250D02*
X313117D01*
X312867Y112833D01*
X312450Y113167D01*
X311867Y113333D01*
X311283Y113250D01*
X310783Y113000D01*
X310450Y112417D01*
X310283Y111917D01*
Y111417D01*
X310450Y110917D01*
X310867Y110417D01*
X311367Y110083D01*
X311950Y110000D01*
X312533Y110167D01*
X313117Y110667D01*
G01X321400Y108333D02*
Y113333D01*
G01Y112583D02*
X321817Y113000D01*
X322233Y113250D01*
X322900Y113333D01*
X323483Y113250D01*
X324067Y112833D01*
X324317Y112250D01*
X324400Y111667D01*
X324317Y111083D01*
X324067Y110500D01*
X323567Y110167D01*
X322900Y110000D01*
X322317Y110083D01*
X321733Y110333D01*
X321400Y110667D01*
G01X328500Y110000D02*
X328000Y110083D01*
X327500Y110417D01*
X327167Y111000D01*
X327000Y111667D01*
X327167Y112333D01*
X327500Y112917D01*
X328000Y113250D01*
X328500Y113333D01*
X329000Y113250D01*
X329500Y112917D01*
X329833Y112333D01*
X329917Y111667D01*
X329833Y111000D01*
X329500Y110417D01*
X329000Y110083D01*
X328500Y110000D01*
G01X332850Y110583D02*
X333267Y110250D01*
X333850Y110000D01*
X334350D01*
X334850Y110167D01*
X335183Y110417D01*
X335350Y110750D01*
X335267Y111250D01*
X334933Y111500D01*
X333433Y112000D01*
X333100Y112583D01*
X333267Y113000D01*
X333600Y113250D01*
X334100Y113333D01*
X334600Y113250D01*
X335100Y113000D01*
G01X339700Y113333D02*
Y110000D01*
G01Y114667D02*
X339533Y114750D01*
Y114917D01*
X339700Y115000D01*
X339867Y114917D01*
Y114750D01*
X339700Y114667D01*
G01X345300Y115000D02*
Y110000D01*
G01X344133Y113333D02*
X346467D01*
G01X350900D02*
Y110000D01*
G01Y114667D02*
X350733Y114750D01*
Y114917D01*
X350900Y115000D01*
X351067Y114917D01*
Y114750D01*
X350900Y114667D01*
G01X356500Y110000D02*
X356000Y110083D01*
X355500Y110417D01*
X355167Y111000D01*
X355000Y111667D01*
X355167Y112333D01*
X355500Y112917D01*
X356000Y113250D01*
X356500Y113333D01*
X357000Y113250D01*
X357500Y112917D01*
X357833Y112333D01*
X357917Y111667D01*
X357833Y111000D01*
X357500Y110417D01*
X357000Y110083D01*
X356500Y110000D01*
G01X360683D02*
Y113333D01*
G01Y112500D02*
X361017Y112917D01*
X361517Y113250D01*
X362183Y113333D01*
X362767Y113250D01*
X363267Y112917D01*
X363517Y112333D01*
Y110000D01*
G01X371800D02*
Y115000D01*
G01Y112500D02*
X372217Y113000D01*
X372717Y113250D01*
X373217Y113333D01*
X373967Y113167D01*
X374467Y112833D01*
X374800Y112250D01*
Y111583D01*
X374633Y110917D01*
X374300Y110417D01*
X373717Y110083D01*
X373217Y110000D01*
X372717Y110083D01*
X372217Y110333D01*
X371800Y110750D01*
G01X377650Y112250D02*
X380317D01*
X380067Y112833D01*
X379650Y113167D01*
X379067Y113333D01*
X378483Y113250D01*
X377983Y113000D01*
X377650Y112417D01*
X377483Y111917D01*
Y111417D01*
X377650Y110917D01*
X378067Y110417D01*
X378567Y110083D01*
X379150Y110000D01*
X379733Y110167D01*
X380317Y110667D01*
G01X384500Y115000D02*
Y110000D01*
G01X383333Y113333D02*
X385667D01*
G01X388017D02*
X389017Y110000D01*
X390100Y113333D01*
X391183Y110000D01*
X392183Y113333D01*
G01X394450Y112250D02*
X397117D01*
X396867Y112833D01*
X396450Y113167D01*
X395867Y113333D01*
X395283Y113250D01*
X394783Y113000D01*
X394450Y112417D01*
X394283Y111917D01*
Y111417D01*
X394450Y110917D01*
X394867Y110417D01*
X395367Y110083D01*
X395950Y110000D01*
X396533Y110167D01*
X397117Y110667D01*
G01X400050Y112250D02*
X402717D01*
X402467Y112833D01*
X402050Y113167D01*
X401467Y113333D01*
X400883Y113250D01*
X400383Y113000D01*
X400050Y112417D01*
X399883Y111917D01*
Y111417D01*
X400050Y110917D01*
X400467Y110417D01*
X400967Y110083D01*
X401550Y110000D01*
X402133Y110167D01*
X402717Y110667D01*
G01X405483Y110000D02*
Y113333D01*
G01Y112500D02*
X405817Y112917D01*
X406317Y113250D01*
X406983Y113333D01*
X407567Y113250D01*
X408067Y112917D01*
X408317Y112333D01*
Y110000D01*
G01X419600D02*
Y113333D01*
G01Y112750D02*
X419267Y113083D01*
X418767Y113250D01*
X418183Y113333D01*
X417600Y113167D01*
X417100Y112833D01*
X416767Y112333D01*
X416600Y111667D01*
X416767Y111000D01*
X417100Y110500D01*
X417600Y110167D01*
X418183Y110000D01*
X418767Y110083D01*
X419267Y110333D01*
X419600Y110667D01*
G01X422283Y110000D02*
Y113333D01*
G01Y112500D02*
X422617Y112917D01*
X423117Y113250D01*
X423783Y113333D01*
X424367Y113250D01*
X424867Y112917D01*
X425117Y112333D01*
Y110000D01*
G01X427550Y108500D02*
X428050Y108333D01*
X428717Y108500D01*
X429133Y108833D01*
X429467Y109250D01*
X429967Y110583D01*
X431050Y113333D01*
G01X428383D02*
X429967Y110583D01*
G01X439000Y108333D02*
Y113333D01*
G01Y112583D02*
X439417Y113000D01*
X439833Y113250D01*
X440500Y113333D01*
X441083Y113250D01*
X441667Y112833D01*
X441917Y112250D01*
X442000Y111667D01*
X441917Y111083D01*
X441667Y110500D01*
X441167Y110167D01*
X440500Y110000D01*
X439917Y110083D01*
X439333Y110333D01*
X439000Y110667D01*
G01X447600Y110000D02*
Y113333D01*
G01Y112750D02*
X447267Y113083D01*
X446767Y113250D01*
X446183Y113333D01*
X445600Y113167D01*
X445100Y112833D01*
X444767Y112333D01*
X444600Y111667D01*
X444767Y111000D01*
X445100Y110500D01*
X445600Y110167D01*
X446183Y110000D01*
X446767Y110083D01*
X447267Y110333D01*
X447600Y110667D01*
G01X453200Y115000D02*
Y110000D01*
G01Y110750D02*
X452867Y110333D01*
X452367Y110083D01*
X451783Y110000D01*
X451117Y110167D01*
X450617Y110583D01*
X450283Y111083D01*
X450200Y111667D01*
X450283Y112250D01*
X450617Y112750D01*
X451117Y113167D01*
X451783Y113333D01*
X452367Y113250D01*
X452783Y113083D01*
X453200Y112750D01*
G01X462900Y115000D02*
Y110000D01*
G01X461733Y113333D02*
X464067D01*
G01X468500Y110000D02*
X468000Y110083D01*
X467500Y110417D01*
X467167Y111000D01*
X467000Y111667D01*
X467167Y112333D01*
X467500Y112917D01*
X468000Y113250D01*
X468500Y113333D01*
X469000Y113250D01*
X469500Y112917D01*
X469833Y112333D01*
X469917Y111667D01*
X469833Y111000D01*
X469500Y110417D01*
X469000Y110083D01*
X468500Y110000D01*
G01X478200Y108333D02*
Y113333D01*
G01Y112583D02*
X478617Y113000D01*
X479033Y113250D01*
X479700Y113333D01*
X480283Y113250D01*
X480867Y112833D01*
X481117Y112250D01*
X481200Y111667D01*
X481117Y111083D01*
X480867Y110500D01*
X480367Y110167D01*
X479700Y110000D01*
X479117Y110083D01*
X478533Y110333D01*
X478200Y110667D01*
G01X486800Y110000D02*
Y113333D01*
G01Y112750D02*
X486467Y113083D01*
X485967Y113250D01*
X485383Y113333D01*
X484800Y113167D01*
X484300Y112833D01*
X483967Y112333D01*
X483800Y111667D01*
X483967Y111000D01*
X484300Y110500D01*
X484800Y110167D01*
X485383Y110000D01*
X485967Y110083D01*
X486467Y110333D01*
X486800Y110667D01*
G01X492400Y115000D02*
Y110000D01*
G01Y110750D02*
X492067Y110333D01*
X491567Y110083D01*
X490983Y110000D01*
X490317Y110167D01*
X489817Y110583D01*
X489483Y111083D01*
X489400Y111667D01*
X489483Y112250D01*
X489817Y112750D01*
X490317Y113167D01*
X490983Y113333D01*
X491567Y113250D01*
X491983Y113083D01*
X492400Y112750D01*
G01X270750Y125000D02*
Y130000D01*
G01X274250D02*
Y125000D01*
G01Y127500D02*
X270750D01*
G01X276267Y125000D02*
Y130000D01*
X277933D01*
X278600Y129750D01*
X279100Y129417D01*
X279517Y128917D01*
X279850Y128333D01*
X279933Y127500D01*
X279850Y126667D01*
X279517Y126083D01*
X279100Y125583D01*
X278600Y125250D01*
X277933Y125000D01*
X276267D01*
G01X282700Y130000D02*
X284700D01*
G01X283700D02*
Y125000D01*
G01X282700D02*
X284700D01*
G01X293233D02*
Y130000D01*
X295233D01*
X295900Y129750D01*
X296400Y129167D01*
X296567Y128500D01*
X296400Y127833D01*
X295983Y127333D01*
X295233Y127083D01*
X293233D01*
G01X302333Y129583D02*
X301833Y129833D01*
X301250Y130000D01*
X300583D01*
X299833Y129750D01*
X299250Y129333D01*
X298833Y128833D01*
X298500Y128000D01*
X298417Y127250D01*
X298583Y126500D01*
X298833Y126000D01*
X299333Y125500D01*
X299917Y125167D01*
X300500Y125000D01*
X301083D01*
X301667Y125167D01*
X302167Y125417D01*
X302583Y125750D01*
G01X306767Y127667D02*
X307100Y127917D01*
X307350Y128333D01*
X307517Y128917D01*
X307350Y129417D01*
X307017Y129750D01*
X306433Y130000D01*
X304183D01*
Y125000D01*
X306933D01*
X307517Y125333D01*
X307850Y125833D01*
X308017Y126417D01*
X307850Y127000D01*
X307350Y127500D01*
X306767Y127667D01*
X304183D01*
G01X311700Y124833D02*
X311533Y124917D01*
Y125083D01*
X311700Y125167D01*
X311867Y125083D01*
Y124917D01*
X311700Y124833D01*
G01X270750Y150667D02*
X271417Y150250D01*
X272167Y150000D01*
X272833D01*
X273500Y150250D01*
X274000Y150667D01*
X274250Y151250D01*
X274083Y151833D01*
X273667Y152333D01*
X272917Y152667D01*
X271917Y152833D01*
X271333Y153167D01*
X271083Y153750D01*
X271250Y154333D01*
X271667Y154750D01*
X272250Y155000D01*
X272833D01*
X273417Y154833D01*
X273917Y154417D01*
G01X276850Y152250D02*
X279517D01*
X279267Y152833D01*
X278850Y153167D01*
X278267Y153333D01*
X277683Y153250D01*
X277183Y153000D01*
X276850Y152417D01*
X276683Y151917D01*
Y151417D01*
X276850Y150917D01*
X277267Y150417D01*
X277767Y150083D01*
X278350Y150000D01*
X278933Y150167D01*
X279517Y150667D01*
G01X282533Y150000D02*
Y153333D01*
G01Y152667D02*
X282950Y153000D01*
X283367Y153250D01*
X283950Y153333D01*
X284367Y153250D01*
X284867Y153000D01*
G01X287800Y153333D02*
X289300Y150000D01*
X290800Y153333D01*
G01X293650Y152250D02*
X296317D01*
X296067Y152833D01*
X295650Y153167D01*
X295067Y153333D01*
X294483Y153250D01*
X293983Y153000D01*
X293650Y152417D01*
X293483Y151917D01*
Y151417D01*
X293650Y150917D01*
X294067Y150417D01*
X294567Y150083D01*
X295150Y150000D01*
X295733Y150167D01*
X296317Y150667D01*
G01X299333Y150000D02*
Y153333D01*
G01Y152667D02*
X299750Y153000D01*
X300167Y153250D01*
X300750Y153333D01*
X301167Y153250D01*
X301667Y153000D01*
G01X310033Y150000D02*
Y155000D01*
X312033D01*
X312700Y154750D01*
X313200Y154167D01*
X313367Y153500D01*
X313200Y152833D01*
X312783Y152333D01*
X312033Y152083D01*
X310033D01*
G01X319133Y154583D02*
X318633Y154833D01*
X318050Y155000D01*
X317383D01*
X316633Y154750D01*
X316050Y154333D01*
X315633Y153833D01*
X315300Y153000D01*
X315217Y152250D01*
X315383Y151500D01*
X315633Y151000D01*
X316133Y150500D01*
X316717Y150167D01*
X317300Y150000D01*
X317883D01*
X318467Y150167D01*
X318967Y150417D01*
X319383Y150750D01*
G01X323567Y152667D02*
X323900Y152917D01*
X324150Y153333D01*
X324317Y153917D01*
X324150Y154417D01*
X323817Y154750D01*
X323233Y155000D01*
X320983D01*
Y150000D01*
X323733D01*
X324317Y150333D01*
X324650Y150833D01*
X324817Y151417D01*
X324650Y152000D01*
X324150Y152500D01*
X323567Y152667D01*
X320983D01*
G01X328500Y149833D02*
X328333Y149917D01*
Y150083D01*
X328500Y150167D01*
X328667Y150083D01*
Y149917D01*
X328500Y149833D01*
G01Y152083D02*
X328333Y152167D01*
Y152333D01*
X328500Y152417D01*
X328667Y152333D01*
Y152167D01*
X328500Y152083D01*
G01X332517Y150000D02*
Y155000D01*
X335683D01*
G01X334517Y152583D02*
X332517D01*
G01X339700Y150000D02*
X339200Y150083D01*
X338700Y150417D01*
X338367Y151000D01*
X338200Y151667D01*
X338367Y152333D01*
X338700Y152917D01*
X339200Y153250D01*
X339700Y153333D01*
X340200Y153250D01*
X340700Y152917D01*
X341033Y152333D01*
X341117Y151667D01*
X341033Y151000D01*
X340700Y150417D01*
X340200Y150083D01*
X339700Y150000D01*
G01X345300D02*
Y155000D01*
G01X350900Y150000D02*
Y155000D01*
G01X356500Y150000D02*
X356000Y150083D01*
X355500Y150417D01*
X355167Y151000D01*
X355000Y151667D01*
X355167Y152333D01*
X355500Y152917D01*
X356000Y153250D01*
X356500Y153333D01*
X357000Y153250D01*
X357500Y152917D01*
X357833Y152333D01*
X357917Y151667D01*
X357833Y151000D01*
X357500Y150417D01*
X357000Y150083D01*
X356500Y150000D01*
G01X360017Y153333D02*
X361017Y150000D01*
X362100Y153333D01*
X363183Y150000D01*
X364183Y153333D01*
G01X372133Y150000D02*
Y153333D01*
G01Y152667D02*
X372550Y153000D01*
X372967Y153250D01*
X373550Y153333D01*
X373967Y153250D01*
X374467Y153000D01*
G01X378900Y153333D02*
Y150000D01*
G01Y154667D02*
X378733Y154750D01*
Y154917D01*
X378900Y155000D01*
X379067Y154917D01*
Y154750D01*
X378900Y154667D01*
G01X383333Y148750D02*
X383917Y148417D01*
X384583Y148333D01*
X385167Y148417D01*
X385667Y148833D01*
X386000Y149417D01*
Y153333D01*
G01Y152667D02*
X385667Y153000D01*
X385167Y153250D01*
X384583Y153333D01*
X383917Y153167D01*
X383500Y152833D01*
X383167Y152250D01*
X383000Y151667D01*
X383083Y151167D01*
X383417Y150583D01*
X383917Y150167D01*
X384583Y150000D01*
X385083Y150083D01*
X385667Y150417D01*
X386000Y150750D01*
G01X388683Y150000D02*
Y155000D01*
G01Y152583D02*
X389100Y153000D01*
X389517Y153250D01*
X390183Y153333D01*
X390683Y153250D01*
X391267Y152917D01*
X391517Y152417D01*
Y150000D01*
G01X395700Y155000D02*
Y150000D01*
G01X394533Y153333D02*
X396867D01*
G01X405650Y150583D02*
X406067Y150250D01*
X406650Y150000D01*
X407150D01*
X407650Y150167D01*
X407983Y150417D01*
X408150Y150750D01*
X408067Y151250D01*
X407733Y151500D01*
X406233Y152000D01*
X405900Y152583D01*
X406067Y153000D01*
X406400Y153250D01*
X406900Y153333D01*
X407400Y153250D01*
X407900Y153000D01*
G01X412500Y153333D02*
Y150000D01*
G01Y154667D02*
X412333Y154750D01*
Y154917D01*
X412500Y155000D01*
X412667Y154917D01*
Y154750D01*
X412500Y154667D01*
G01X419600Y155000D02*
Y150000D01*
G01Y150750D02*
X419267Y150333D01*
X418767Y150083D01*
X418183Y150000D01*
X417517Y150167D01*
X417017Y150583D01*
X416683Y151083D01*
X416600Y151667D01*
X416683Y152250D01*
X417017Y152750D01*
X417517Y153167D01*
X418183Y153333D01*
X418767Y153250D01*
X419183Y153083D01*
X419600Y152750D01*
G01X422450Y152250D02*
X425117D01*
X424867Y152833D01*
X424450Y153167D01*
X423867Y153333D01*
X423283Y153250D01*
X422783Y153000D01*
X422450Y152417D01*
X422283Y151917D01*
Y151417D01*
X422450Y150917D01*
X422867Y150417D01*
X423367Y150083D01*
X423950Y150000D01*
X424533Y150167D01*
X425117Y150667D01*
G01X433650Y150583D02*
X434067Y150250D01*
X434650Y150000D01*
X435150D01*
X435650Y150167D01*
X435983Y150417D01*
X436150Y150750D01*
X436067Y151250D01*
X435733Y151500D01*
X434233Y152000D01*
X433900Y152583D01*
X434067Y153000D01*
X434400Y153250D01*
X434900Y153333D01*
X435400Y153250D01*
X435900Y153000D01*
G01X439000Y148333D02*
Y153333D01*
G01Y152583D02*
X439417Y153000D01*
X439833Y153250D01*
X440500Y153333D01*
X441083Y153250D01*
X441667Y152833D01*
X441917Y152250D01*
X442000Y151667D01*
X441917Y151083D01*
X441667Y150500D01*
X441167Y150167D01*
X440500Y150000D01*
X439917Y150083D01*
X439333Y150333D01*
X439000Y150667D01*
G01X444850Y152250D02*
X447517D01*
X447267Y152833D01*
X446850Y153167D01*
X446267Y153333D01*
X445683Y153250D01*
X445183Y153000D01*
X444850Y152417D01*
X444683Y151917D01*
Y151417D01*
X444850Y150917D01*
X445267Y150417D01*
X445767Y150083D01*
X446350Y150000D01*
X446933Y150167D01*
X447517Y150667D01*
G01X453033Y152917D02*
X452450Y153250D01*
X451950Y153333D01*
X451283Y153167D01*
X450783Y152833D01*
X450450Y152250D01*
X450367Y151667D01*
X450450Y151083D01*
X450783Y150583D01*
X451283Y150167D01*
X451950Y150000D01*
X452533Y150167D01*
X453033Y150500D01*
G01X462733Y149083D02*
X463067Y150167D01*
G01X468500Y153333D02*
Y150000D01*
G01Y154667D02*
X468333Y154750D01*
Y154917D01*
X468500Y155000D01*
X468667Y154917D01*
Y154750D01*
X468500Y154667D01*
G01X473600Y150000D02*
Y154250D01*
X473767Y154667D01*
X474100Y154917D01*
X474600Y155000D01*
X475100Y154833D01*
X475350Y154417D01*
G01X474350Y153000D02*
X472683D01*
G01X484050Y150583D02*
X484467Y150250D01*
X485050Y150000D01*
X485550D01*
X486050Y150167D01*
X486383Y150417D01*
X486550Y150750D01*
X486467Y151250D01*
X486133Y151500D01*
X484633Y152000D01*
X484300Y152583D01*
X484467Y153000D01*
X484800Y153250D01*
X485300Y153333D01*
X485800Y153250D01*
X486300Y153000D01*
G01X490900Y155000D02*
Y150000D01*
G01X489733Y153333D02*
X492067D01*
G01X498000Y150000D02*
Y153333D01*
G01Y152750D02*
X497667Y153083D01*
X497167Y153250D01*
X496583Y153333D01*
X496000Y153167D01*
X495500Y152833D01*
X495167Y152333D01*
X495000Y151667D01*
X495167Y151000D01*
X495500Y150500D01*
X496000Y150167D01*
X496583Y150000D01*
X497167Y150083D01*
X497667Y150333D01*
X498000Y150667D01*
G01X503433Y152917D02*
X502850Y153250D01*
X502350Y153333D01*
X501683Y153167D01*
X501183Y152833D01*
X500850Y152250D01*
X500767Y151667D01*
X500850Y151083D01*
X501183Y150583D01*
X501683Y150167D01*
X502350Y150000D01*
X502933Y150167D01*
X503433Y150500D01*
G01X506283Y150000D02*
Y155000D01*
G01X508950Y153333D02*
X506283Y151417D01*
G01X507367Y152167D02*
X509117Y150000D01*
G01X517483Y153333D02*
Y151000D01*
X517817Y150417D01*
X518317Y150083D01*
X518900Y150000D01*
X519483Y150083D01*
X519983Y150417D01*
X520317Y151000D01*
G01Y150000D02*
Y153333D01*
G01X523000Y148333D02*
Y153333D01*
G01Y152583D02*
X523417Y153000D01*
X523833Y153250D01*
X524500Y153333D01*
X525083Y153250D01*
X525667Y152833D01*
X525917Y152250D01*
X526000Y151667D01*
X525917Y151083D01*
X525667Y150500D01*
X525167Y150167D01*
X524500Y150000D01*
X523917Y150083D01*
X523333Y150333D01*
X523000Y150667D01*
G01X533617Y153333D02*
X534617Y150000D01*
X535700Y153333D01*
X536783Y150000D01*
X537783Y153333D01*
G01X541300D02*
Y150000D01*
G01Y154667D02*
X541133Y154750D01*
Y154917D01*
X541300Y155000D01*
X541467Y154917D01*
Y154750D01*
X541300Y154667D01*
G01X546900Y155000D02*
Y150000D01*
G01X545733Y153333D02*
X548067D01*
G01X551083Y150000D02*
Y155000D01*
G01Y152583D02*
X551500Y153000D01*
X551917Y153250D01*
X552583Y153333D01*
X553083Y153250D01*
X553667Y152917D01*
X553917Y152417D01*
Y150000D01*
G01X558100D02*
X557600Y150083D01*
X557100Y150417D01*
X556767Y151000D01*
X556600Y151667D01*
X556767Y152333D01*
X557100Y152917D01*
X557600Y153250D01*
X558100Y153333D01*
X558600Y153250D01*
X559100Y152917D01*
X559433Y152333D01*
X559517Y151667D01*
X559433Y151000D01*
X559100Y150417D01*
X558600Y150083D01*
X558100Y150000D01*
G01X562283Y153333D02*
Y151000D01*
X562617Y150417D01*
X563117Y150083D01*
X563700Y150000D01*
X564283Y150083D01*
X564783Y150417D01*
X565117Y151000D01*
G01Y150000D02*
Y153333D01*
G01X569300Y155000D02*
Y150000D01*
G01X568133Y153333D02*
X570467D01*
G01X272500Y170000D02*
Y165000D01*
G01X270583Y170000D02*
X274417D01*
G01X276933Y165000D02*
Y168333D01*
G01Y167667D02*
X277350Y168000D01*
X277767Y168250D01*
X278350Y168333D01*
X278767Y168250D01*
X279267Y168000D01*
G01X285200Y165000D02*
Y168333D01*
G01Y167750D02*
X284867Y168083D01*
X284367Y168250D01*
X283783Y168333D01*
X283200Y168167D01*
X282700Y167833D01*
X282367Y167333D01*
X282200Y166667D01*
X282367Y166000D01*
X282700Y165500D01*
X283200Y165167D01*
X283783Y165000D01*
X284367Y165083D01*
X284867Y165333D01*
X285200Y165667D01*
G01X290800Y170000D02*
Y165000D01*
G01Y165750D02*
X290467Y165333D01*
X289967Y165083D01*
X289383Y165000D01*
X288717Y165167D01*
X288217Y165583D01*
X287883Y166083D01*
X287800Y166667D01*
X287883Y167250D01*
X288217Y167750D01*
X288717Y168167D01*
X289383Y168333D01*
X289967Y168250D01*
X290383Y168083D01*
X290800Y167750D01*
G01X294900Y168333D02*
Y165000D01*
G01Y169667D02*
X294733Y169750D01*
Y169917D01*
X294900Y170000D01*
X295067Y169917D01*
Y169750D01*
X294900Y169667D01*
G01X300500Y170000D02*
Y165000D01*
G01X299333Y168333D02*
X301667D01*
G01X306100D02*
Y165000D01*
G01Y169667D02*
X305933Y169750D01*
Y169917D01*
X306100Y170000D01*
X306267Y169917D01*
Y169750D01*
X306100Y169667D01*
G01X311700Y165000D02*
X311200Y165083D01*
X310700Y165417D01*
X310367Y166000D01*
X310200Y166667D01*
X310367Y167333D01*
X310700Y167917D01*
X311200Y168250D01*
X311700Y168333D01*
X312200Y168250D01*
X312700Y167917D01*
X313033Y167333D01*
X313117Y166667D01*
X313033Y166000D01*
X312700Y165417D01*
X312200Y165083D01*
X311700Y165000D01*
G01X315883D02*
Y168333D01*
G01Y167500D02*
X316217Y167917D01*
X316717Y168250D01*
X317383Y168333D01*
X317967Y168250D01*
X318467Y167917D01*
X318717Y167333D01*
Y165000D01*
G01X324400D02*
Y168333D01*
G01Y167750D02*
X324067Y168083D01*
X323567Y168250D01*
X322983Y168333D01*
X322400Y168167D01*
X321900Y167833D01*
X321567Y167333D01*
X321400Y166667D01*
X321567Y166000D01*
X321900Y165500D01*
X322400Y165167D01*
X322983Y165000D01*
X323567Y165083D01*
X324067Y165333D01*
X324400Y165667D01*
G01X328500Y165000D02*
Y170000D01*
G01X338033Y165000D02*
Y170000D01*
X340033D01*
X340700Y169750D01*
X341200Y169167D01*
X341367Y168500D01*
X341200Y167833D01*
X340783Y167333D01*
X340033Y167083D01*
X338033D01*
G01X347133Y169583D02*
X346633Y169833D01*
X346050Y170000D01*
X345383D01*
X344633Y169750D01*
X344050Y169333D01*
X343633Y168833D01*
X343300Y168000D01*
X343217Y167250D01*
X343383Y166500D01*
X343633Y166000D01*
X344133Y165500D01*
X344717Y165167D01*
X345300Y165000D01*
X345883D01*
X346467Y165167D01*
X346967Y165417D01*
X347383Y165750D01*
G01X351567Y167667D02*
X351900Y167917D01*
X352150Y168333D01*
X352317Y168917D01*
X352150Y169417D01*
X351817Y169750D01*
X351233Y170000D01*
X348983D01*
Y165000D01*
X351733D01*
X352317Y165333D01*
X352650Y165833D01*
X352817Y166417D01*
X352650Y167000D01*
X352150Y167500D01*
X351567Y167667D01*
X348983D01*
G01X356500Y164833D02*
X356333Y164917D01*
Y165083D01*
X356500Y165167D01*
X356667Y165083D01*
Y164917D01*
X356500Y164833D01*
G01X322623Y303963D02*
X322890Y304163D01*
X323090Y304497D01*
X323223Y304963D01*
X323090Y305363D01*
X322823Y305630D01*
X322357Y305830D01*
X320557D01*
Y301830D01*
X322757D01*
X323223Y302097D01*
X323490Y302497D01*
X323623Y302963D01*
X323490Y303430D01*
X323090Y303830D01*
X322623Y303963D01*
X320557D01*
G01X322623D02*
X322890Y304163D01*
X323090Y304497D01*
X323223Y304963D01*
X323090Y305363D01*
X322823Y305630D01*
X322357Y305830D01*
X320557D01*
Y301830D01*
X322757D01*
X323223Y302097D01*
X323490Y302497D01*
X323623Y302963D01*
X323490Y303430D01*
X323090Y303830D01*
X322623Y303963D01*
X320557D01*
G01X320423Y351330D02*
X322090Y355330D01*
X323757Y351330D01*
G01X323157Y352730D02*
X321023D01*
G01X270000Y374000D02*
Y369000D01*
G01X268833Y372333D02*
X271167D01*
G01X275600Y369000D02*
X275100Y369083D01*
X274600Y369417D01*
X274267Y370000D01*
X274100Y370667D01*
X274267Y371333D01*
X274600Y371917D01*
X275100Y372250D01*
X275600Y372333D01*
X276100Y372250D01*
X276600Y371917D01*
X276933Y371333D01*
X277017Y370667D01*
X276933Y370000D01*
X276600Y369417D01*
X276100Y369083D01*
X275600Y369000D01*
G01X281200D02*
Y374000D01*
G01X285550Y371250D02*
X288217D01*
X287967Y371833D01*
X287550Y372167D01*
X286967Y372333D01*
X286383Y372250D01*
X285883Y372000D01*
X285550Y371417D01*
X285383Y370917D01*
Y370417D01*
X285550Y369917D01*
X285967Y369417D01*
X286467Y369083D01*
X287050Y369000D01*
X287633Y369167D01*
X288217Y369667D01*
G01X291233Y369000D02*
Y372333D01*
G01Y371667D02*
X291650Y372000D01*
X292067Y372250D01*
X292650Y372333D01*
X293067Y372250D01*
X293567Y372000D01*
G01X299500Y369000D02*
Y372333D01*
G01Y371750D02*
X299167Y372083D01*
X298667Y372250D01*
X298083Y372333D01*
X297500Y372167D01*
X297000Y371833D01*
X296667Y371333D01*
X296500Y370667D01*
X296667Y370000D01*
X297000Y369500D01*
X297500Y369167D01*
X298083Y369000D01*
X298667Y369083D01*
X299167Y369333D01*
X299500Y369667D01*
G01X302183Y369000D02*
Y372333D01*
G01Y371500D02*
X302517Y371917D01*
X303017Y372250D01*
X303683Y372333D01*
X304267Y372250D01*
X304767Y371917D01*
X305017Y371333D01*
Y369000D01*
G01X310533Y371917D02*
X309950Y372250D01*
X309450Y372333D01*
X308783Y372167D01*
X308283Y371833D01*
X307950Y371250D01*
X307867Y370667D01*
X307950Y370083D01*
X308283Y369583D01*
X308783Y369167D01*
X309450Y369000D01*
X310033Y369167D01*
X310533Y369500D01*
G01X313550Y371250D02*
X316217D01*
X315967Y371833D01*
X315550Y372167D01*
X314967Y372333D01*
X314383Y372250D01*
X313883Y372000D01*
X313550Y371417D01*
X313383Y370917D01*
Y370417D01*
X313550Y369917D01*
X313967Y369417D01*
X314467Y369083D01*
X315050Y369000D01*
X315633Y369167D01*
X316217Y369667D01*
G01X326000Y374000D02*
Y369000D01*
G01X324833Y372333D02*
X327167D01*
G01X333100Y369000D02*
Y372333D01*
G01Y371750D02*
X332767Y372083D01*
X332267Y372250D01*
X331683Y372333D01*
X331100Y372167D01*
X330600Y371833D01*
X330267Y371333D01*
X330100Y370667D01*
X330267Y370000D01*
X330600Y369500D01*
X331100Y369167D01*
X331683Y369000D01*
X332267Y369083D01*
X332767Y369333D01*
X333100Y369667D01*
G01X335700Y369000D02*
Y374000D01*
G01Y371500D02*
X336117Y372000D01*
X336617Y372250D01*
X337117Y372333D01*
X337867Y372167D01*
X338367Y371833D01*
X338700Y371250D01*
Y370583D01*
X338533Y369917D01*
X338200Y369417D01*
X337617Y369083D01*
X337117Y369000D01*
X336617Y369083D01*
X336117Y369333D01*
X335700Y369750D01*
G01X342800Y369000D02*
Y374000D01*
G01X347150Y371250D02*
X349817D01*
X349567Y371833D01*
X349150Y372167D01*
X348567Y372333D01*
X347983Y372250D01*
X347483Y372000D01*
X347150Y371417D01*
X346983Y370917D01*
Y370417D01*
X347150Y369917D01*
X347567Y369417D01*
X348067Y369083D01*
X348650Y369000D01*
X349233Y369167D01*
X349817Y369667D01*
G01X354000Y368833D02*
X353833Y368917D01*
Y369083D01*
X354000Y369167D01*
X354167Y369083D01*
Y368917D01*
X354000Y368833D01*
G01X268667Y379750D02*
X269250Y379417D01*
X269750Y379333D01*
X270417Y379500D01*
X270917Y379917D01*
X271167Y380667D01*
Y384333D01*
G01Y385667D02*
X271000Y385750D01*
Y385917D01*
X271167Y386000D01*
X271333Y385917D01*
Y385750D01*
X271167Y385667D01*
G01X274183Y384333D02*
Y382000D01*
X274517Y381417D01*
X275017Y381083D01*
X275600Y381000D01*
X276183Y381083D01*
X276683Y381417D01*
X277017Y382000D01*
G01Y381000D02*
Y384333D01*
G01X279783Y381000D02*
Y384333D01*
G01Y383500D02*
X280117Y383917D01*
X280617Y384250D01*
X281283Y384333D01*
X281867Y384250D01*
X282367Y383917D01*
X282617Y383333D01*
Y381000D01*
G01X288133Y383917D02*
X287550Y384250D01*
X287050Y384333D01*
X286383Y384167D01*
X285883Y383833D01*
X285550Y383250D01*
X285467Y382667D01*
X285550Y382083D01*
X285883Y381583D01*
X286383Y381167D01*
X287050Y381000D01*
X287633Y381167D01*
X288133Y381500D01*
G01X292400Y386000D02*
Y381000D01*
G01X291233Y384333D02*
X293567D01*
G01X298000D02*
Y381000D01*
G01Y385667D02*
X297833Y385750D01*
Y385917D01*
X298000Y386000D01*
X298167Y385917D01*
Y385750D01*
X298000Y385667D01*
G01X303600Y381000D02*
X303100Y381083D01*
X302600Y381417D01*
X302267Y382000D01*
X302100Y382667D01*
X302267Y383333D01*
X302600Y383917D01*
X303100Y384250D01*
X303600Y384333D01*
X304100Y384250D01*
X304600Y383917D01*
X304933Y383333D01*
X305017Y382667D01*
X304933Y382000D01*
X304600Y381417D01*
X304100Y381083D01*
X303600Y381000D01*
G01X307783D02*
Y384333D01*
G01Y383500D02*
X308117Y383917D01*
X308617Y384250D01*
X309283Y384333D01*
X309867Y384250D01*
X310367Y383917D01*
X310617Y383333D01*
Y381000D01*
G01X318900D02*
Y386000D01*
G01Y383500D02*
X319317Y384000D01*
X319817Y384250D01*
X320317Y384333D01*
X321067Y384167D01*
X321567Y383833D01*
X321900Y383250D01*
Y382583D01*
X321733Y381917D01*
X321400Y381417D01*
X320817Y381083D01*
X320317Y381000D01*
X319817Y381083D01*
X319317Y381333D01*
X318900Y381750D01*
G01X324750Y383250D02*
X327417D01*
X327167Y383833D01*
X326750Y384167D01*
X326167Y384333D01*
X325583Y384250D01*
X325083Y384000D01*
X324750Y383417D01*
X324583Y382917D01*
Y382417D01*
X324750Y381917D01*
X325167Y381417D01*
X325667Y381083D01*
X326250Y381000D01*
X326833Y381167D01*
X327417Y381667D01*
G01X331600Y381000D02*
Y386000D01*
G01X337200Y381000D02*
X336700Y381083D01*
X336200Y381417D01*
X335867Y382000D01*
X335700Y382667D01*
X335867Y383333D01*
X336200Y383917D01*
X336700Y384250D01*
X337200Y384333D01*
X337700Y384250D01*
X338200Y383917D01*
X338533Y383333D01*
X338617Y382667D01*
X338533Y382000D01*
X338200Y381417D01*
X337700Y381083D01*
X337200Y381000D01*
G01X340717Y384333D02*
X341717Y381000D01*
X342800Y384333D01*
X343883Y381000D01*
X344883Y384333D01*
G01X354000Y386000D02*
Y381000D01*
G01X352833Y384333D02*
X355167D01*
G01X358183Y381000D02*
Y386000D01*
G01Y383583D02*
X358600Y384000D01*
X359017Y384250D01*
X359683Y384333D01*
X360183Y384250D01*
X360767Y383917D01*
X361017Y383417D01*
Y381000D01*
G01X363950Y383250D02*
X366617D01*
X366367Y383833D01*
X365950Y384167D01*
X365367Y384333D01*
X364783Y384250D01*
X364283Y384000D01*
X363950Y383417D01*
X363783Y382917D01*
Y382417D01*
X363950Y381917D01*
X364367Y381417D01*
X364867Y381083D01*
X365450Y381000D01*
X366033Y381167D01*
X366617Y381667D01*
G01X373900Y381000D02*
Y384333D01*
G01Y383417D02*
X374150Y383833D01*
X374567Y384167D01*
X375150Y384333D01*
X375733Y384167D01*
X376150Y383833D01*
X376400Y383417D01*
Y381000D01*
G01Y383417D02*
X376650Y383833D01*
X377067Y384167D01*
X377650Y384333D01*
X378233Y384167D01*
X378650Y383833D01*
X378900Y383333D01*
Y381000D01*
G01X382000Y384333D02*
Y381000D01*
G01Y385667D02*
X381833Y385750D01*
Y385917D01*
X382000Y386000D01*
X382167Y385917D01*
Y385750D01*
X382000Y385667D01*
G01X386183Y381000D02*
Y384333D01*
G01Y383500D02*
X386517Y383917D01*
X387017Y384250D01*
X387683Y384333D01*
X388267Y384250D01*
X388767Y383917D01*
X389017Y383333D01*
Y381000D01*
G01X400133Y383917D02*
X399550Y384250D01*
X399050Y384333D01*
X398383Y384167D01*
X397883Y383833D01*
X397550Y383250D01*
X397467Y382667D01*
X397550Y382083D01*
X397883Y381583D01*
X398383Y381167D01*
X399050Y381000D01*
X399633Y381167D01*
X400133Y381500D01*
G01X404400Y381000D02*
X403900Y381083D01*
X403400Y381417D01*
X403067Y382000D01*
X402900Y382667D01*
X403067Y383333D01*
X403400Y383917D01*
X403900Y384250D01*
X404400Y384333D01*
X404900Y384250D01*
X405400Y383917D01*
X405733Y383333D01*
X405817Y382667D01*
X405733Y382000D01*
X405400Y381417D01*
X404900Y381083D01*
X404400Y381000D01*
G01X408583D02*
Y384333D01*
G01Y383500D02*
X408917Y383917D01*
X409417Y384250D01*
X410083Y384333D01*
X410667Y384250D01*
X411167Y383917D01*
X411417Y383333D01*
Y381000D01*
G01X417100Y386000D02*
Y381000D01*
G01Y381750D02*
X416767Y381333D01*
X416267Y381083D01*
X415683Y381000D01*
X415017Y381167D01*
X414517Y381583D01*
X414183Y382083D01*
X414100Y382667D01*
X414183Y383250D01*
X414517Y383750D01*
X415017Y384167D01*
X415683Y384333D01*
X416267Y384250D01*
X416683Y384083D01*
X417100Y383750D01*
G01X419783Y384333D02*
Y382000D01*
X420117Y381417D01*
X420617Y381083D01*
X421200Y381000D01*
X421783Y381083D01*
X422283Y381417D01*
X422617Y382000D01*
G01Y381000D02*
Y384333D01*
G01X428133Y383917D02*
X427550Y384250D01*
X427050Y384333D01*
X426383Y384167D01*
X425883Y383833D01*
X425550Y383250D01*
X425467Y382667D01*
X425550Y382083D01*
X425883Y381583D01*
X426383Y381167D01*
X427050Y381000D01*
X427633Y381167D01*
X428133Y381500D01*
G01X432400Y386000D02*
Y381000D01*
G01X431233Y384333D02*
X433567D01*
G01X438000Y381000D02*
X437500Y381083D01*
X437000Y381417D01*
X436667Y382000D01*
X436500Y382667D01*
X436667Y383333D01*
X437000Y383917D01*
X437500Y384250D01*
X438000Y384333D01*
X438500Y384250D01*
X439000Y383917D01*
X439333Y383333D01*
X439417Y382667D01*
X439333Y382000D01*
X439000Y381417D01*
X438500Y381083D01*
X438000Y381000D01*
G01X442433D02*
Y384333D01*
G01Y383667D02*
X442850Y384000D01*
X443267Y384250D01*
X443850Y384333D01*
X444267Y384250D01*
X444767Y384000D01*
G01X452717Y384333D02*
X453717Y381000D01*
X454800Y384333D01*
X455883Y381000D01*
X456883Y384333D01*
G01X460400D02*
Y381000D01*
G01Y385667D02*
X460233Y385750D01*
Y385917D01*
X460400Y386000D01*
X460567Y385917D01*
Y385750D01*
X460400Y385667D01*
G01X467500Y386000D02*
Y381000D01*
G01Y381750D02*
X467167Y381333D01*
X466667Y381083D01*
X466083Y381000D01*
X465417Y381167D01*
X464917Y381583D01*
X464583Y382083D01*
X464500Y382667D01*
X464583Y383250D01*
X464917Y383750D01*
X465417Y384167D01*
X466083Y384333D01*
X466667Y384250D01*
X467083Y384083D01*
X467500Y383750D01*
G01X471600Y386000D02*
Y381000D01*
G01X470433Y384333D02*
X472767D01*
G01X475783Y381000D02*
Y386000D01*
G01Y383583D02*
X476200Y384000D01*
X476617Y384250D01*
X477283Y384333D01*
X477783Y384250D01*
X478367Y383917D01*
X478617Y383417D01*
Y381000D01*
G01X487150Y381583D02*
X487567Y381250D01*
X488150Y381000D01*
X488650D01*
X489150Y381167D01*
X489483Y381417D01*
X489650Y381750D01*
X489567Y382250D01*
X489233Y382500D01*
X487733Y383000D01*
X487400Y383583D01*
X487567Y384000D01*
X487900Y384250D01*
X488400Y384333D01*
X488900Y384250D01*
X489400Y384000D01*
G01X492500Y379333D02*
Y384333D01*
G01Y383583D02*
X492917Y384000D01*
X493333Y384250D01*
X494000Y384333D01*
X494583Y384250D01*
X495167Y383833D01*
X495417Y383250D01*
X495500Y382667D01*
X495417Y382083D01*
X495167Y381500D01*
X494667Y381167D01*
X494000Y381000D01*
X493417Y381083D01*
X492833Y381333D01*
X492500Y381667D01*
G01X498350Y383250D02*
X501017D01*
X500767Y383833D01*
X500350Y384167D01*
X499767Y384333D01*
X499183Y384250D01*
X498683Y384000D01*
X498350Y383417D01*
X498183Y382917D01*
Y382417D01*
X498350Y381917D01*
X498767Y381417D01*
X499267Y381083D01*
X499850Y381000D01*
X500433Y381167D01*
X501017Y381667D01*
G01X506533Y383917D02*
X505950Y384250D01*
X505450Y384333D01*
X504783Y384167D01*
X504283Y383833D01*
X503950Y383250D01*
X503867Y382667D01*
X503950Y382083D01*
X504283Y381583D01*
X504783Y381167D01*
X505450Y381000D01*
X506033Y381167D01*
X506533Y381500D01*
G01X510800Y384333D02*
Y381000D01*
G01Y385667D02*
X510633Y385750D01*
Y385917D01*
X510800Y386000D01*
X510967Y385917D01*
Y385750D01*
X510800Y385667D01*
G01X515900Y381000D02*
Y385250D01*
X516067Y385667D01*
X516400Y385917D01*
X516900Y386000D01*
X517400Y385833D01*
X517650Y385417D01*
G01X516650Y384000D02*
X514983D01*
G01X522000Y384333D02*
Y381000D01*
G01Y385667D02*
X521833Y385750D01*
Y385917D01*
X522000Y386000D01*
X522167Y385917D01*
Y385750D01*
X522000Y385667D01*
G01X526350Y383250D02*
X529017D01*
X528767Y383833D01*
X528350Y384167D01*
X527767Y384333D01*
X527183Y384250D01*
X526683Y384000D01*
X526350Y383417D01*
X526183Y382917D01*
Y382417D01*
X526350Y381917D01*
X526767Y381417D01*
X527267Y381083D01*
X527850Y381000D01*
X528433Y381167D01*
X529017Y381667D01*
G01X534700Y386000D02*
Y381000D01*
G01Y381750D02*
X534367Y381333D01*
X533867Y381083D01*
X533283Y381000D01*
X532617Y381167D01*
X532117Y381583D01*
X531783Y382083D01*
X531700Y382667D01*
X531783Y383250D01*
X532117Y383750D01*
X532617Y384167D01*
X533283Y384333D01*
X533867Y384250D01*
X534283Y384083D01*
X534700Y383750D01*
G01X544400Y381000D02*
X543900Y381083D01*
X543400Y381417D01*
X543067Y382000D01*
X542900Y382667D01*
X543067Y383333D01*
X543400Y383917D01*
X543900Y384250D01*
X544400Y384333D01*
X544900Y384250D01*
X545400Y383917D01*
X545733Y383333D01*
X545817Y382667D01*
X545733Y382000D01*
X545400Y381417D01*
X544900Y381083D01*
X544400Y381000D01*
G01X548583D02*
Y384333D01*
G01Y383500D02*
X548917Y383917D01*
X549417Y384250D01*
X550083Y384333D01*
X550667Y384250D01*
X551167Y383917D01*
X551417Y383333D01*
Y381000D01*
G01X561200Y386000D02*
Y381000D01*
G01X560033Y384333D02*
X562367D01*
G01X565383Y381000D02*
Y386000D01*
G01Y383583D02*
X565800Y384000D01*
X566217Y384250D01*
X566883Y384333D01*
X567383Y384250D01*
X567967Y383917D01*
X568217Y383417D01*
Y381000D01*
G01X571150Y383250D02*
X573817D01*
X573567Y383833D01*
X573150Y384167D01*
X572567Y384333D01*
X571983Y384250D01*
X571483Y384000D01*
X571150Y383417D01*
X570983Y382917D01*
Y382417D01*
X571150Y381917D01*
X571567Y381417D01*
X572067Y381083D01*
X572650Y381000D01*
X573233Y381167D01*
X573817Y381667D01*
G01X268250Y391500D02*
Y396500D01*
G01X271750D02*
Y391500D01*
G01Y394000D02*
X268250D01*
G01X275600Y391500D02*
X275100Y391583D01*
X274600Y391917D01*
X274267Y392500D01*
X274100Y393167D01*
X274267Y393833D01*
X274600Y394417D01*
X275100Y394750D01*
X275600Y394833D01*
X276100Y394750D01*
X276600Y394417D01*
X276933Y393833D01*
X277017Y393167D01*
X276933Y392500D01*
X276600Y391917D01*
X276100Y391583D01*
X275600Y391500D01*
G01X279117Y394833D02*
X280117Y391500D01*
X281200Y394833D01*
X282283Y391500D01*
X283283Y394833D01*
G01X285550Y393750D02*
X288217D01*
X287967Y394333D01*
X287550Y394667D01*
X286967Y394833D01*
X286383Y394750D01*
X285883Y394500D01*
X285550Y393917D01*
X285383Y393417D01*
Y392917D01*
X285550Y392417D01*
X285967Y391917D01*
X286467Y391583D01*
X287050Y391500D01*
X287633Y391667D01*
X288217Y392167D01*
G01X290900Y394833D02*
X292400Y391500D01*
X293900Y394833D01*
G01X296750Y393750D02*
X299417D01*
X299167Y394333D01*
X298750Y394667D01*
X298167Y394833D01*
X297583Y394750D01*
X297083Y394500D01*
X296750Y393917D01*
X296583Y393417D01*
Y392917D01*
X296750Y392417D01*
X297167Y391917D01*
X297667Y391583D01*
X298250Y391500D01*
X298833Y391667D01*
X299417Y392167D01*
G01X302433Y391500D02*
Y394833D01*
G01Y394167D02*
X302850Y394500D01*
X303267Y394750D01*
X303850Y394833D01*
X304267Y394750D01*
X304767Y394500D01*
G01X309033Y390583D02*
X309367Y391667D01*
G01X314800Y396500D02*
Y391500D01*
G01X313633Y394833D02*
X315967D01*
G01X318983Y391500D02*
Y396500D01*
G01Y394083D02*
X319400Y394500D01*
X319817Y394750D01*
X320483Y394833D01*
X320983Y394750D01*
X321567Y394417D01*
X321817Y393917D01*
Y391500D01*
G01X324750Y393750D02*
X327417D01*
X327167Y394333D01*
X326750Y394667D01*
X326167Y394833D01*
X325583Y394750D01*
X325083Y394500D01*
X324750Y393917D01*
X324583Y393417D01*
Y392917D01*
X324750Y392417D01*
X325167Y391917D01*
X325667Y391583D01*
X326250Y391500D01*
X326833Y391667D01*
X327417Y392167D01*
G01X337200Y396500D02*
Y391500D01*
G01X336033Y394833D02*
X338367D01*
G01X344300Y391500D02*
Y394833D01*
G01Y394250D02*
X343967Y394583D01*
X343467Y394750D01*
X342883Y394833D01*
X342300Y394667D01*
X341800Y394333D01*
X341467Y393833D01*
X341300Y393167D01*
X341467Y392500D01*
X341800Y392000D01*
X342300Y391667D01*
X342883Y391500D01*
X343467Y391583D01*
X343967Y391833D01*
X344300Y392167D01*
G01X346983Y391500D02*
Y394833D01*
G01Y394000D02*
X347317Y394417D01*
X347817Y394750D01*
X348483Y394833D01*
X349067Y394750D01*
X349567Y394417D01*
X349817Y393833D01*
Y391500D01*
G01X352833Y390250D02*
X353417Y389917D01*
X354083Y389833D01*
X354667Y389917D01*
X355167Y390333D01*
X355500Y390917D01*
Y394833D01*
G01Y394167D02*
X355167Y394500D01*
X354667Y394750D01*
X354083Y394833D01*
X353417Y394667D01*
X353000Y394333D01*
X352667Y393750D01*
X352500Y393167D01*
X352583Y392667D01*
X352917Y392083D01*
X353417Y391667D01*
X354083Y391500D01*
X354583Y391583D01*
X355167Y391917D01*
X355500Y392250D01*
G01X358350Y393750D02*
X361017D01*
X360767Y394333D01*
X360350Y394667D01*
X359767Y394833D01*
X359183Y394750D01*
X358683Y394500D01*
X358350Y393917D01*
X358183Y393417D01*
Y392917D01*
X358350Y392417D01*
X358767Y391917D01*
X359267Y391583D01*
X359850Y391500D01*
X360433Y391667D01*
X361017Y392167D01*
G01X363783Y391500D02*
Y394833D01*
G01Y394000D02*
X364117Y394417D01*
X364617Y394750D01*
X365283Y394833D01*
X365867Y394750D01*
X366367Y394417D01*
X366617Y393833D01*
Y391500D01*
G01X372133Y394417D02*
X371550Y394750D01*
X371050Y394833D01*
X370383Y394667D01*
X369883Y394333D01*
X369550Y393750D01*
X369467Y393167D01*
X369550Y392583D01*
X369883Y392083D01*
X370383Y391667D01*
X371050Y391500D01*
X371633Y391667D01*
X372133Y392000D01*
G01X374650Y390000D02*
X375150Y389833D01*
X375817Y390000D01*
X376233Y390333D01*
X376567Y390750D01*
X377067Y392083D01*
X378150Y394833D01*
G01X375483D02*
X377067Y392083D01*
G01X386350D02*
X386767Y391750D01*
X387350Y391500D01*
X387850D01*
X388350Y391667D01*
X388683Y391917D01*
X388850Y392250D01*
X388767Y392750D01*
X388433Y393000D01*
X386933Y393500D01*
X386600Y394083D01*
X386767Y394500D01*
X387100Y394750D01*
X387600Y394833D01*
X388100Y394750D01*
X388600Y394500D01*
G01X391783Y391500D02*
Y396500D01*
G01Y394083D02*
X392200Y394500D01*
X392617Y394750D01*
X393283Y394833D01*
X393783Y394750D01*
X394367Y394417D01*
X394617Y393917D01*
Y391500D01*
G01X398800D02*
X398300Y391583D01*
X397800Y391917D01*
X397467Y392500D01*
X397300Y393167D01*
X397467Y393833D01*
X397800Y394417D01*
X398300Y394750D01*
X398800Y394833D01*
X399300Y394750D01*
X399800Y394417D01*
X400133Y393833D01*
X400217Y393167D01*
X400133Y392500D01*
X399800Y391917D01*
X399300Y391583D01*
X398800Y391500D01*
G01X402983Y394833D02*
Y392500D01*
X403317Y391917D01*
X403817Y391583D01*
X404400Y391500D01*
X404983Y391583D01*
X405483Y391917D01*
X405817Y392500D01*
G01Y391500D02*
Y394833D01*
G01X410000Y391500D02*
Y396500D01*
G01X417100D02*
Y391500D01*
G01Y392250D02*
X416767Y391833D01*
X416267Y391583D01*
X415683Y391500D01*
X415017Y391667D01*
X414517Y392083D01*
X414183Y392583D01*
X414100Y393167D01*
X414183Y393750D01*
X414517Y394250D01*
X415017Y394667D01*
X415683Y394833D01*
X416267Y394750D01*
X416683Y394583D01*
X417100Y394250D01*
G01X425383Y391500D02*
Y394833D01*
G01Y394000D02*
X425717Y394417D01*
X426217Y394750D01*
X426883Y394833D01*
X427467Y394750D01*
X427967Y394417D01*
X428217Y393833D01*
Y391500D01*
G01X432400D02*
X431900Y391583D01*
X431400Y391917D01*
X431067Y392500D01*
X430900Y393167D01*
X431067Y393833D01*
X431400Y394417D01*
X431900Y394750D01*
X432400Y394833D01*
X432900Y394750D01*
X433400Y394417D01*
X433733Y393833D01*
X433817Y393167D01*
X433733Y392500D01*
X433400Y391917D01*
X432900Y391583D01*
X432400Y391500D01*
G01X438000Y396500D02*
Y391500D01*
G01X436833Y394833D02*
X439167D01*
G01X448033Y391500D02*
Y394833D01*
G01Y394167D02*
X448450Y394500D01*
X448867Y394750D01*
X449450Y394833D01*
X449867Y394750D01*
X450367Y394500D01*
G01X453550Y393750D02*
X456217D01*
X455967Y394333D01*
X455550Y394667D01*
X454967Y394833D01*
X454383Y394750D01*
X453883Y394500D01*
X453550Y393917D01*
X453383Y393417D01*
Y392917D01*
X453550Y392417D01*
X453967Y391917D01*
X454467Y391583D01*
X455050Y391500D01*
X455633Y391667D01*
X456217Y392167D01*
G01X461900Y396500D02*
Y391500D01*
G01Y392250D02*
X461567Y391833D01*
X461067Y391583D01*
X460483Y391500D01*
X459817Y391667D01*
X459317Y392083D01*
X458983Y392583D01*
X458900Y393167D01*
X458983Y393750D01*
X459317Y394250D01*
X459817Y394667D01*
X460483Y394833D01*
X461067Y394750D01*
X461483Y394583D01*
X461900Y394250D01*
G01X464583Y394833D02*
Y392500D01*
X464917Y391917D01*
X465417Y391583D01*
X466000Y391500D01*
X466583Y391583D01*
X467083Y391917D01*
X467417Y392500D01*
G01Y391500D02*
Y394833D01*
G01X472933Y394417D02*
X472350Y394750D01*
X471850Y394833D01*
X471183Y394667D01*
X470683Y394333D01*
X470350Y393750D01*
X470267Y393167D01*
X470350Y392583D01*
X470683Y392083D01*
X471183Y391667D01*
X471850Y391500D01*
X472433Y391667D01*
X472933Y392000D01*
G01X475950Y393750D02*
X478617D01*
X478367Y394333D01*
X477950Y394667D01*
X477367Y394833D01*
X476783Y394750D01*
X476283Y394500D01*
X475950Y393917D01*
X475783Y393417D01*
Y392917D01*
X475950Y392417D01*
X476367Y391917D01*
X476867Y391583D01*
X477450Y391500D01*
X478033Y391667D01*
X478617Y392167D01*
G01X488400Y396500D02*
Y391500D01*
G01X487233Y394833D02*
X489567D01*
G01X492583Y391500D02*
Y396500D01*
G01Y394083D02*
X493000Y394500D01*
X493417Y394750D01*
X494083Y394833D01*
X494583Y394750D01*
X495167Y394417D01*
X495417Y393917D01*
Y391500D01*
G01X498350Y393750D02*
X501017D01*
X500767Y394333D01*
X500350Y394667D01*
X499767Y394833D01*
X499183Y394750D01*
X498683Y394500D01*
X498350Y393917D01*
X498183Y393417D01*
Y392917D01*
X498350Y392417D01*
X498767Y391917D01*
X499267Y391583D01*
X499850Y391500D01*
X500433Y391667D01*
X501017Y392167D01*
G01X510800Y391500D02*
Y396500D01*
G01X517900Y391500D02*
Y394833D01*
G01Y394250D02*
X517567Y394583D01*
X517067Y394750D01*
X516483Y394833D01*
X515900Y394667D01*
X515400Y394333D01*
X515067Y393833D01*
X514900Y393167D01*
X515067Y392500D01*
X515400Y392000D01*
X515900Y391667D01*
X516483Y391500D01*
X517067Y391583D01*
X517567Y391833D01*
X517900Y392167D01*
G01X520583Y391500D02*
Y394833D01*
G01Y394000D02*
X520917Y394417D01*
X521417Y394750D01*
X522083Y394833D01*
X522667Y394750D01*
X523167Y394417D01*
X523417Y393833D01*
Y391500D01*
G01X529100Y396500D02*
Y391500D01*
G01Y392250D02*
X528767Y391833D01*
X528267Y391583D01*
X527683Y391500D01*
X527017Y391667D01*
X526517Y392083D01*
X526183Y392583D01*
X526100Y393167D01*
X526183Y393750D01*
X526517Y394250D01*
X527017Y394667D01*
X527683Y394833D01*
X528267Y394750D01*
X528683Y394583D01*
X529100Y394250D01*
G01X531700Y391333D02*
X534700Y396500D01*
G01X540133Y394417D02*
X539550Y394750D01*
X539050Y394833D01*
X538383Y394667D01*
X537883Y394333D01*
X537550Y393750D01*
X537467Y393167D01*
X537550Y392583D01*
X537883Y392083D01*
X538383Y391667D01*
X539050Y391500D01*
X539633Y391667D01*
X540133Y392000D01*
G01X544400Y391500D02*
X543900Y391583D01*
X543400Y391917D01*
X543067Y392500D01*
X542900Y393167D01*
X543067Y393833D01*
X543400Y394417D01*
X543900Y394750D01*
X544400Y394833D01*
X544900Y394750D01*
X545400Y394417D01*
X545733Y393833D01*
X545817Y393167D01*
X545733Y392500D01*
X545400Y391917D01*
X544900Y391583D01*
X544400Y391500D01*
G01X548583D02*
Y394833D01*
G01Y394000D02*
X548917Y394417D01*
X549417Y394750D01*
X550083Y394833D01*
X550667Y394750D01*
X551167Y394417D01*
X551417Y393833D01*
Y391500D01*
G01X557100Y396500D02*
Y391500D01*
G01Y392250D02*
X556767Y391833D01*
X556267Y391583D01*
X555683Y391500D01*
X555017Y391667D01*
X554517Y392083D01*
X554183Y392583D01*
X554100Y393167D01*
X554183Y393750D01*
X554517Y394250D01*
X555017Y394667D01*
X555683Y394833D01*
X556267Y394750D01*
X556683Y394583D01*
X557100Y394250D01*
G01X559783Y394833D02*
Y392500D01*
X560117Y391917D01*
X560617Y391583D01*
X561200Y391500D01*
X561783Y391583D01*
X562283Y391917D01*
X562617Y392500D01*
G01Y391500D02*
Y394833D01*
G01X568133Y394417D02*
X567550Y394750D01*
X567050Y394833D01*
X566383Y394667D01*
X565883Y394333D01*
X565550Y393750D01*
X565467Y393167D01*
X565550Y392583D01*
X565883Y392083D01*
X566383Y391667D01*
X567050Y391500D01*
X567633Y391667D01*
X568133Y392000D01*
G01X572400Y396500D02*
Y391500D01*
G01X571233Y394833D02*
X573567D01*
G01X578000Y391500D02*
X577500Y391583D01*
X577000Y391917D01*
X576667Y392500D01*
X576500Y393167D01*
X576667Y393833D01*
X577000Y394417D01*
X577500Y394750D01*
X578000Y394833D01*
X578500Y394750D01*
X579000Y394417D01*
X579333Y393833D01*
X579417Y393167D01*
X579333Y392500D01*
X579000Y391917D01*
X578500Y391583D01*
X578000Y391500D01*
G01X582433D02*
Y394833D01*
G01Y394167D02*
X582850Y394500D01*
X583267Y394750D01*
X583850Y394833D01*
X584267Y394750D01*
X584767Y394500D01*
G01X271500Y402000D02*
Y405333D01*
G01Y404750D02*
X271167Y405083D01*
X270667Y405250D01*
X270083Y405333D01*
X269500Y405167D01*
X269000Y404833D01*
X268667Y404333D01*
X268500Y403667D01*
X268667Y403000D01*
X269000Y402500D01*
X269500Y402167D01*
X270083Y402000D01*
X270667Y402083D01*
X271167Y402333D01*
X271500Y402667D01*
G01X276933Y404917D02*
X276350Y405250D01*
X275850Y405333D01*
X275183Y405167D01*
X274683Y404833D01*
X274350Y404250D01*
X274267Y403667D01*
X274350Y403083D01*
X274683Y402583D01*
X275183Y402167D01*
X275850Y402000D01*
X276433Y402167D01*
X276933Y402500D01*
G01X282533Y404917D02*
X281950Y405250D01*
X281450Y405333D01*
X280783Y405167D01*
X280283Y404833D01*
X279950Y404250D01*
X279867Y403667D01*
X279950Y403083D01*
X280283Y402583D01*
X280783Y402167D01*
X281450Y402000D01*
X282033Y402167D01*
X282533Y402500D01*
G01X285550Y404250D02*
X288217D01*
X287967Y404833D01*
X287550Y405167D01*
X286967Y405333D01*
X286383Y405250D01*
X285883Y405000D01*
X285550Y404417D01*
X285383Y403917D01*
Y403417D01*
X285550Y402917D01*
X285967Y402417D01*
X286467Y402083D01*
X287050Y402000D01*
X287633Y402167D01*
X288217Y402667D01*
G01X290900Y400333D02*
Y405333D01*
G01Y404583D02*
X291317Y405000D01*
X291733Y405250D01*
X292400Y405333D01*
X292983Y405250D01*
X293567Y404833D01*
X293817Y404250D01*
X293900Y403667D01*
X293817Y403083D01*
X293567Y402500D01*
X293067Y402167D01*
X292400Y402000D01*
X291817Y402083D01*
X291233Y402333D01*
X290900Y402667D01*
G01X298000Y407000D02*
Y402000D01*
G01X296833Y405333D02*
X299167D01*
G01X305100Y402000D02*
Y405333D01*
G01Y404750D02*
X304767Y405083D01*
X304267Y405250D01*
X303683Y405333D01*
X303100Y405167D01*
X302600Y404833D01*
X302267Y404333D01*
X302100Y403667D01*
X302267Y403000D01*
X302600Y402500D01*
X303100Y402167D01*
X303683Y402000D01*
X304267Y402083D01*
X304767Y402333D01*
X305100Y402667D01*
G01X307700Y402000D02*
Y407000D01*
G01Y404500D02*
X308117Y405000D01*
X308617Y405250D01*
X309117Y405333D01*
X309867Y405167D01*
X310367Y404833D01*
X310700Y404250D01*
Y403583D01*
X310533Y402917D01*
X310200Y402417D01*
X309617Y402083D01*
X309117Y402000D01*
X308617Y402083D01*
X308117Y402333D01*
X307700Y402750D01*
G01X314800Y402000D02*
Y407000D01*
G01X319150Y404250D02*
X321817D01*
X321567Y404833D01*
X321150Y405167D01*
X320567Y405333D01*
X319983Y405250D01*
X319483Y405000D01*
X319150Y404417D01*
X318983Y403917D01*
Y403417D01*
X319150Y402917D01*
X319567Y402417D01*
X320067Y402083D01*
X320650Y402000D01*
X321233Y402167D01*
X321817Y402667D01*
G01X326000Y401833D02*
X325833Y401917D01*
Y402083D01*
X326000Y402167D01*
X326167Y402083D01*
Y401917D01*
X326000Y401833D01*
G01X270000Y417500D02*
Y412500D01*
G01X268083Y417500D02*
X271917D01*
G01X274183Y412500D02*
Y417500D01*
G01Y415083D02*
X274600Y415500D01*
X275017Y415750D01*
X275683Y415833D01*
X276183Y415750D01*
X276767Y415417D01*
X277017Y414917D01*
Y412500D01*
G01X279950Y414750D02*
X282617D01*
X282367Y415333D01*
X281950Y415667D01*
X281367Y415833D01*
X280783Y415750D01*
X280283Y415500D01*
X279950Y414917D01*
X279783Y414417D01*
Y413917D01*
X279950Y413417D01*
X280367Y412917D01*
X280867Y412583D01*
X281450Y412500D01*
X282033Y412667D01*
X282617Y413167D01*
G01X290900Y412500D02*
Y417500D01*
G01Y415000D02*
X291317Y415500D01*
X291817Y415750D01*
X292317Y415833D01*
X293067Y415667D01*
X293567Y415333D01*
X293900Y414750D01*
Y414083D01*
X293733Y413417D01*
X293400Y412917D01*
X292817Y412583D01*
X292317Y412500D01*
X291817Y412583D01*
X291317Y412833D01*
X290900Y413250D01*
G01X296833Y412500D02*
Y415833D01*
G01Y415167D02*
X297250Y415500D01*
X297667Y415750D01*
X298250Y415833D01*
X298667Y415750D01*
X299167Y415500D01*
G01X302350Y414750D02*
X305017D01*
X304767Y415333D01*
X304350Y415667D01*
X303767Y415833D01*
X303183Y415750D01*
X302683Y415500D01*
X302350Y414917D01*
X302183Y414417D01*
Y413917D01*
X302350Y413417D01*
X302767Y412917D01*
X303267Y412583D01*
X303850Y412500D01*
X304433Y412667D01*
X305017Y413167D01*
G01X310700Y412500D02*
Y415833D01*
G01Y415250D02*
X310367Y415583D01*
X309867Y415750D01*
X309283Y415833D01*
X308700Y415667D01*
X308200Y415333D01*
X307867Y414833D01*
X307700Y414167D01*
X307867Y413500D01*
X308200Y413000D01*
X308700Y412667D01*
X309283Y412500D01*
X309867Y412583D01*
X310367Y412833D01*
X310700Y413167D01*
G01X313383Y412500D02*
Y417500D01*
G01X316050Y415833D02*
X313383Y413917D01*
G01X314467Y414667D02*
X316217Y412500D01*
G01X320400D02*
X319900Y412583D01*
X319400Y412917D01*
X319067Y413500D01*
X318900Y414167D01*
X319067Y414833D01*
X319400Y415417D01*
X319900Y415750D01*
X320400Y415833D01*
X320900Y415750D01*
X321400Y415417D01*
X321733Y414833D01*
X321817Y414167D01*
X321733Y413500D01*
X321400Y412917D01*
X320900Y412583D01*
X320400Y412500D01*
G01X324583Y415833D02*
Y413500D01*
X324917Y412917D01*
X325417Y412583D01*
X326000Y412500D01*
X326583Y412583D01*
X327083Y412917D01*
X327417Y413500D01*
G01Y412500D02*
Y415833D01*
G01X331600Y417500D02*
Y412500D01*
G01X330433Y415833D02*
X332767D01*
G01X342800D02*
Y412500D01*
G01Y417167D02*
X342633Y417250D01*
Y417417D01*
X342800Y417500D01*
X342967Y417417D01*
Y417250D01*
X342800Y417167D01*
G01X347150Y413083D02*
X347567Y412750D01*
X348150Y412500D01*
X348650D01*
X349150Y412667D01*
X349483Y412917D01*
X349650Y413250D01*
X349567Y413750D01*
X349233Y414000D01*
X347733Y414500D01*
X347400Y415083D01*
X347567Y415500D01*
X347900Y415750D01*
X348400Y415833D01*
X348900Y415750D01*
X349400Y415500D01*
G01X358183Y412500D02*
Y415833D01*
G01Y415000D02*
X358517Y415417D01*
X359017Y415750D01*
X359683Y415833D01*
X360267Y415750D01*
X360767Y415417D01*
X361017Y414833D01*
Y412500D01*
G01X365200D02*
X364700Y412583D01*
X364200Y412917D01*
X363867Y413500D01*
X363700Y414167D01*
X363867Y414833D01*
X364200Y415417D01*
X364700Y415750D01*
X365200Y415833D01*
X365700Y415750D01*
X366200Y415417D01*
X366533Y414833D01*
X366617Y414167D01*
X366533Y413500D01*
X366200Y412917D01*
X365700Y412583D01*
X365200Y412500D01*
G01X370800Y417500D02*
Y412500D01*
G01X369633Y415833D02*
X371967D01*
G01X383500Y412500D02*
Y415833D01*
G01Y415250D02*
X383167Y415583D01*
X382667Y415750D01*
X382083Y415833D01*
X381500Y415667D01*
X381000Y415333D01*
X380667Y414833D01*
X380500Y414167D01*
X380667Y413500D01*
X381000Y413000D01*
X381500Y412667D01*
X382083Y412500D01*
X382667Y412583D01*
X383167Y412833D01*
X383500Y413167D01*
G01X387600Y412500D02*
Y417500D01*
G01X393200Y412500D02*
Y417500D01*
G01X398800Y412500D02*
X398300Y412583D01*
X397800Y412917D01*
X397467Y413500D01*
X397300Y414167D01*
X397467Y414833D01*
X397800Y415417D01*
X398300Y415750D01*
X398800Y415833D01*
X399300Y415750D01*
X399800Y415417D01*
X400133Y414833D01*
X400217Y414167D01*
X400133Y413500D01*
X399800Y412917D01*
X399300Y412583D01*
X398800Y412500D01*
G01X402317Y415833D02*
X403317Y412500D01*
X404400Y415833D01*
X405483Y412500D01*
X406483Y415833D01*
G01X408750Y414750D02*
X411417D01*
X411167Y415333D01*
X410750Y415667D01*
X410167Y415833D01*
X409583Y415750D01*
X409083Y415500D01*
X408750Y414917D01*
X408583Y414417D01*
Y413917D01*
X408750Y413417D01*
X409167Y412917D01*
X409667Y412583D01*
X410250Y412500D01*
X410833Y412667D01*
X411417Y413167D01*
G01X417100Y417500D02*
Y412500D01*
G01Y413250D02*
X416767Y412833D01*
X416267Y412583D01*
X415683Y412500D01*
X415017Y412667D01*
X414517Y413083D01*
X414183Y413583D01*
X414100Y414167D01*
X414183Y414750D01*
X414517Y415250D01*
X415017Y415667D01*
X415683Y415833D01*
X416267Y415750D01*
X416683Y415583D01*
X417100Y415250D01*
G01X421033Y411583D02*
X421367Y412667D01*
G01X436500Y412500D02*
Y417500D01*
G01Y415000D02*
X436917Y415500D01*
X437417Y415750D01*
X437917Y415833D01*
X438667Y415667D01*
X439167Y415333D01*
X439500Y414750D01*
Y414083D01*
X439333Y413417D01*
X439000Y412917D01*
X438417Y412583D01*
X437917Y412500D01*
X437417Y412583D01*
X436917Y412833D01*
X436500Y413250D01*
G01X442183Y415833D02*
Y413500D01*
X442517Y412917D01*
X443017Y412583D01*
X443600Y412500D01*
X444183Y412583D01*
X444683Y412917D01*
X445017Y413500D01*
G01Y412500D02*
Y415833D01*
G01X449200Y417500D02*
Y412500D01*
G01X448033Y415833D02*
X450367D01*
G01X461900Y412500D02*
Y415833D01*
G01Y415250D02*
X461567Y415583D01*
X461067Y415750D01*
X460483Y415833D01*
X459900Y415667D01*
X459400Y415333D01*
X459067Y414833D01*
X458900Y414167D01*
X459067Y413500D01*
X459400Y413000D01*
X459900Y412667D01*
X460483Y412500D01*
X461067Y412583D01*
X461567Y412833D01*
X461900Y413167D01*
G01X464583Y412500D02*
Y415833D01*
G01Y415000D02*
X464917Y415417D01*
X465417Y415750D01*
X466083Y415833D01*
X466667Y415750D01*
X467167Y415417D01*
X467417Y414833D01*
Y412500D01*
G01X470183D02*
Y415833D01*
G01Y415000D02*
X470517Y415417D01*
X471017Y415750D01*
X471683Y415833D01*
X472267Y415750D01*
X472767Y415417D01*
X473017Y414833D01*
Y412500D01*
G01X475783Y415833D02*
Y413500D01*
X476117Y412917D01*
X476617Y412583D01*
X477200Y412500D01*
X477783Y412583D01*
X478283Y412917D01*
X478617Y413500D01*
G01Y412500D02*
Y415833D01*
G01X484300Y412500D02*
Y415833D01*
G01Y415250D02*
X483967Y415583D01*
X483467Y415750D01*
X482883Y415833D01*
X482300Y415667D01*
X481800Y415333D01*
X481467Y414833D01*
X481300Y414167D01*
X481467Y413500D01*
X481800Y413000D01*
X482300Y412667D01*
X482883Y412500D01*
X483467Y412583D01*
X483967Y412833D01*
X484300Y413167D01*
G01X488400Y412500D02*
Y417500D01*
G01X498433Y412500D02*
Y415833D01*
G01Y415167D02*
X498850Y415500D01*
X499267Y415750D01*
X499850Y415833D01*
X500267Y415750D01*
X500767Y415500D01*
G01X505200Y415833D02*
Y412500D01*
G01Y417167D02*
X505033Y417250D01*
Y417417D01*
X505200Y417500D01*
X505367Y417417D01*
Y417250D01*
X505200Y417167D01*
G01X509383Y412500D02*
Y415833D01*
G01Y415000D02*
X509717Y415417D01*
X510217Y415750D01*
X510883Y415833D01*
X511467Y415750D01*
X511967Y415417D01*
X512217Y414833D01*
Y412500D01*
G01X515233Y411250D02*
X515817Y410917D01*
X516483Y410833D01*
X517067Y410917D01*
X517567Y411333D01*
X517900Y411917D01*
Y415833D01*
G01Y415167D02*
X517567Y415500D01*
X517067Y415750D01*
X516483Y415833D01*
X515817Y415667D01*
X515400Y415333D01*
X515067Y414750D01*
X514900Y414167D01*
X514983Y413667D01*
X515317Y413083D01*
X515817Y412667D01*
X516483Y412500D01*
X516983Y412583D01*
X517567Y412917D01*
X517900Y413250D01*
G01X527600Y417500D02*
Y412500D01*
G01X526433Y415833D02*
X528767D01*
G01X534700Y412500D02*
Y415833D01*
G01Y415250D02*
X534367Y415583D01*
X533867Y415750D01*
X533283Y415833D01*
X532700Y415667D01*
X532200Y415333D01*
X531867Y414833D01*
X531700Y414167D01*
X531867Y413500D01*
X532200Y413000D01*
X532700Y412667D01*
X533283Y412500D01*
X533867Y412583D01*
X534367Y412833D01*
X534700Y413167D01*
G01X537383Y412500D02*
Y415833D01*
G01Y415000D02*
X537717Y415417D01*
X538217Y415750D01*
X538883Y415833D01*
X539467Y415750D01*
X539967Y415417D01*
X540217Y414833D01*
Y412500D01*
G01X543233Y411250D02*
X543817Y410917D01*
X544483Y410833D01*
X545067Y410917D01*
X545567Y411333D01*
X545900Y411917D01*
Y415833D01*
G01Y415167D02*
X545567Y415500D01*
X545067Y415750D01*
X544483Y415833D01*
X543817Y415667D01*
X543400Y415333D01*
X543067Y414750D01*
X542900Y414167D01*
X542983Y413667D01*
X543317Y413083D01*
X543817Y412667D01*
X544483Y412500D01*
X544983Y412583D01*
X545567Y412917D01*
X545900Y413250D01*
G01X548750Y414750D02*
X551417D01*
X551167Y415333D01*
X550750Y415667D01*
X550167Y415833D01*
X549583Y415750D01*
X549083Y415500D01*
X548750Y414917D01*
X548583Y414417D01*
Y413917D01*
X548750Y413417D01*
X549167Y412917D01*
X549667Y412583D01*
X550250Y412500D01*
X550833Y412667D01*
X551417Y413167D01*
G01X554183Y412500D02*
Y415833D01*
G01Y415000D02*
X554517Y415417D01*
X555017Y415750D01*
X555683Y415833D01*
X556267Y415750D01*
X556767Y415417D01*
X557017Y414833D01*
Y412500D01*
G01X562533Y415417D02*
X561950Y415750D01*
X561450Y415833D01*
X560783Y415667D01*
X560283Y415333D01*
X559950Y414750D01*
X559867Y414167D01*
X559950Y413583D01*
X560283Y413083D01*
X560783Y412667D01*
X561450Y412500D01*
X562033Y412667D01*
X562533Y413000D01*
G01X565050Y411000D02*
X565550Y410833D01*
X566217Y411000D01*
X566633Y411333D01*
X566967Y411750D01*
X567467Y413083D01*
X568550Y415833D01*
G01X565883D02*
X567467Y413083D01*
G01X578000Y415833D02*
Y412500D01*
G01Y417167D02*
X577833Y417250D01*
Y417417D01*
X578000Y417500D01*
X578167Y417417D01*
Y417250D01*
X578000Y417167D01*
G01X582350Y413083D02*
X582767Y412750D01*
X583350Y412500D01*
X583850D01*
X584350Y412667D01*
X584683Y412917D01*
X584850Y413250D01*
X584767Y413750D01*
X584433Y414000D01*
X582933Y414500D01*
X582600Y415083D01*
X582767Y415500D01*
X583100Y415750D01*
X583600Y415833D01*
X584100Y415750D01*
X584600Y415500D01*
G01X320423Y351330D02*
X322090Y355330D01*
X323757Y351330D01*
G01X323157Y352730D02*
X321023D01*
G01X270000Y374000D02*
Y369000D01*
G01X268833Y372333D02*
X271167D01*
G01X275600Y369000D02*
X275100Y369083D01*
X274600Y369417D01*
X274267Y370000D01*
X274100Y370667D01*
X274267Y371333D01*
X274600Y371917D01*
X275100Y372250D01*
X275600Y372333D01*
X276100Y372250D01*
X276600Y371917D01*
X276933Y371333D01*
X277017Y370667D01*
X276933Y370000D01*
X276600Y369417D01*
X276100Y369083D01*
X275600Y369000D01*
G01X281200D02*
Y374000D01*
G01X285550Y371250D02*
X288217D01*
X287967Y371833D01*
X287550Y372167D01*
X286967Y372333D01*
X286383Y372250D01*
X285883Y372000D01*
X285550Y371417D01*
X285383Y370917D01*
Y370417D01*
X285550Y369917D01*
X285967Y369417D01*
X286467Y369083D01*
X287050Y369000D01*
X287633Y369167D01*
X288217Y369667D01*
G01X291233Y369000D02*
Y372333D01*
G01Y371667D02*
X291650Y372000D01*
X292067Y372250D01*
X292650Y372333D01*
X293067Y372250D01*
X293567Y372000D01*
G01X299500Y369000D02*
Y372333D01*
G01Y371750D02*
X299167Y372083D01*
X298667Y372250D01*
X298083Y372333D01*
X297500Y372167D01*
X297000Y371833D01*
X296667Y371333D01*
X296500Y370667D01*
X296667Y370000D01*
X297000Y369500D01*
X297500Y369167D01*
X298083Y369000D01*
X298667Y369083D01*
X299167Y369333D01*
X299500Y369667D01*
G01X302183Y369000D02*
Y372333D01*
G01Y371500D02*
X302517Y371917D01*
X303017Y372250D01*
X303683Y372333D01*
X304267Y372250D01*
X304767Y371917D01*
X305017Y371333D01*
Y369000D01*
G01X310533Y371917D02*
X309950Y372250D01*
X309450Y372333D01*
X308783Y372167D01*
X308283Y371833D01*
X307950Y371250D01*
X307867Y370667D01*
X307950Y370083D01*
X308283Y369583D01*
X308783Y369167D01*
X309450Y369000D01*
X310033Y369167D01*
X310533Y369500D01*
G01X313550Y371250D02*
X316217D01*
X315967Y371833D01*
X315550Y372167D01*
X314967Y372333D01*
X314383Y372250D01*
X313883Y372000D01*
X313550Y371417D01*
X313383Y370917D01*
Y370417D01*
X313550Y369917D01*
X313967Y369417D01*
X314467Y369083D01*
X315050Y369000D01*
X315633Y369167D01*
X316217Y369667D01*
G01X326000Y374000D02*
Y369000D01*
G01X324833Y372333D02*
X327167D01*
G01X333100Y369000D02*
Y372333D01*
G01Y371750D02*
X332767Y372083D01*
X332267Y372250D01*
X331683Y372333D01*
X331100Y372167D01*
X330600Y371833D01*
X330267Y371333D01*
X330100Y370667D01*
X330267Y370000D01*
X330600Y369500D01*
X331100Y369167D01*
X331683Y369000D01*
X332267Y369083D01*
X332767Y369333D01*
X333100Y369667D01*
G01X335700Y369000D02*
Y374000D01*
G01Y371500D02*
X336117Y372000D01*
X336617Y372250D01*
X337117Y372333D01*
X337867Y372167D01*
X338367Y371833D01*
X338700Y371250D01*
Y370583D01*
X338533Y369917D01*
X338200Y369417D01*
X337617Y369083D01*
X337117Y369000D01*
X336617Y369083D01*
X336117Y369333D01*
X335700Y369750D01*
G01X342800Y369000D02*
Y374000D01*
G01X347150Y371250D02*
X349817D01*
X349567Y371833D01*
X349150Y372167D01*
X348567Y372333D01*
X347983Y372250D01*
X347483Y372000D01*
X347150Y371417D01*
X346983Y370917D01*
Y370417D01*
X347150Y369917D01*
X347567Y369417D01*
X348067Y369083D01*
X348650Y369000D01*
X349233Y369167D01*
X349817Y369667D01*
G01X354000Y368833D02*
X353833Y368917D01*
Y369083D01*
X354000Y369167D01*
X354167Y369083D01*
Y368917D01*
X354000Y368833D01*
G01X268667Y379750D02*
X269250Y379417D01*
X269750Y379333D01*
X270417Y379500D01*
X270917Y379917D01*
X271167Y380667D01*
Y384333D01*
G01Y385667D02*
X271000Y385750D01*
Y385917D01*
X271167Y386000D01*
X271333Y385917D01*
Y385750D01*
X271167Y385667D01*
G01X274183Y384333D02*
Y382000D01*
X274517Y381417D01*
X275017Y381083D01*
X275600Y381000D01*
X276183Y381083D01*
X276683Y381417D01*
X277017Y382000D01*
G01Y381000D02*
Y384333D01*
G01X279783Y381000D02*
Y384333D01*
G01Y383500D02*
X280117Y383917D01*
X280617Y384250D01*
X281283Y384333D01*
X281867Y384250D01*
X282367Y383917D01*
X282617Y383333D01*
Y381000D01*
G01X288133Y383917D02*
X287550Y384250D01*
X287050Y384333D01*
X286383Y384167D01*
X285883Y383833D01*
X285550Y383250D01*
X285467Y382667D01*
X285550Y382083D01*
X285883Y381583D01*
X286383Y381167D01*
X287050Y381000D01*
X287633Y381167D01*
X288133Y381500D01*
G01X292400Y386000D02*
Y381000D01*
G01X291233Y384333D02*
X293567D01*
G01X298000D02*
Y381000D01*
G01Y385667D02*
X297833Y385750D01*
Y385917D01*
X298000Y386000D01*
X298167Y385917D01*
Y385750D01*
X298000Y385667D01*
G01X303600Y381000D02*
X303100Y381083D01*
X302600Y381417D01*
X302267Y382000D01*
X302100Y382667D01*
X302267Y383333D01*
X302600Y383917D01*
X303100Y384250D01*
X303600Y384333D01*
X304100Y384250D01*
X304600Y383917D01*
X304933Y383333D01*
X305017Y382667D01*
X304933Y382000D01*
X304600Y381417D01*
X304100Y381083D01*
X303600Y381000D01*
G01X307783D02*
Y384333D01*
G01Y383500D02*
X308117Y383917D01*
X308617Y384250D01*
X309283Y384333D01*
X309867Y384250D01*
X310367Y383917D01*
X310617Y383333D01*
Y381000D01*
G01X318900D02*
Y386000D01*
G01Y383500D02*
X319317Y384000D01*
X319817Y384250D01*
X320317Y384333D01*
X321067Y384167D01*
X321567Y383833D01*
X321900Y383250D01*
Y382583D01*
X321733Y381917D01*
X321400Y381417D01*
X320817Y381083D01*
X320317Y381000D01*
X319817Y381083D01*
X319317Y381333D01*
X318900Y381750D01*
G01X324750Y383250D02*
X327417D01*
X327167Y383833D01*
X326750Y384167D01*
X326167Y384333D01*
X325583Y384250D01*
X325083Y384000D01*
X324750Y383417D01*
X324583Y382917D01*
Y382417D01*
X324750Y381917D01*
X325167Y381417D01*
X325667Y381083D01*
X326250Y381000D01*
X326833Y381167D01*
X327417Y381667D01*
G01X331600Y381000D02*
Y386000D01*
G01X337200Y381000D02*
X336700Y381083D01*
X336200Y381417D01*
X335867Y382000D01*
X335700Y382667D01*
X335867Y383333D01*
X336200Y383917D01*
X336700Y384250D01*
X337200Y384333D01*
X337700Y384250D01*
X338200Y383917D01*
X338533Y383333D01*
X338617Y382667D01*
X338533Y382000D01*
X338200Y381417D01*
X337700Y381083D01*
X337200Y381000D01*
G01X340717Y384333D02*
X341717Y381000D01*
X342800Y384333D01*
X343883Y381000D01*
X344883Y384333D01*
G01X354000Y386000D02*
Y381000D01*
G01X352833Y384333D02*
X355167D01*
G01X358183Y381000D02*
Y386000D01*
G01Y383583D02*
X358600Y384000D01*
X359017Y384250D01*
X359683Y384333D01*
X360183Y384250D01*
X360767Y383917D01*
X361017Y383417D01*
Y381000D01*
G01X363950Y383250D02*
X366617D01*
X366367Y383833D01*
X365950Y384167D01*
X365367Y384333D01*
X364783Y384250D01*
X364283Y384000D01*
X363950Y383417D01*
X363783Y382917D01*
Y382417D01*
X363950Y381917D01*
X364367Y381417D01*
X364867Y381083D01*
X365450Y381000D01*
X366033Y381167D01*
X366617Y381667D01*
G01X373900Y381000D02*
Y384333D01*
G01Y383417D02*
X374150Y383833D01*
X374567Y384167D01*
X375150Y384333D01*
X375733Y384167D01*
X376150Y383833D01*
X376400Y383417D01*
Y381000D01*
G01Y383417D02*
X376650Y383833D01*
X377067Y384167D01*
X377650Y384333D01*
X378233Y384167D01*
X378650Y383833D01*
X378900Y383333D01*
Y381000D01*
G01X382000Y384333D02*
Y381000D01*
G01Y385667D02*
X381833Y385750D01*
Y385917D01*
X382000Y386000D01*
X382167Y385917D01*
Y385750D01*
X382000Y385667D01*
G01X386183Y381000D02*
Y384333D01*
G01Y383500D02*
X386517Y383917D01*
X387017Y384250D01*
X387683Y384333D01*
X388267Y384250D01*
X388767Y383917D01*
X389017Y383333D01*
Y381000D01*
G01X400133Y383917D02*
X399550Y384250D01*
X399050Y384333D01*
X398383Y384167D01*
X397883Y383833D01*
X397550Y383250D01*
X397467Y382667D01*
X397550Y382083D01*
X397883Y381583D01*
X398383Y381167D01*
X399050Y381000D01*
X399633Y381167D01*
X400133Y381500D01*
G01X404400Y381000D02*
X403900Y381083D01*
X403400Y381417D01*
X403067Y382000D01*
X402900Y382667D01*
X403067Y383333D01*
X403400Y383917D01*
X403900Y384250D01*
X404400Y384333D01*
X404900Y384250D01*
X405400Y383917D01*
X405733Y383333D01*
X405817Y382667D01*
X405733Y382000D01*
X405400Y381417D01*
X404900Y381083D01*
X404400Y381000D01*
G01X408583D02*
Y384333D01*
G01Y383500D02*
X408917Y383917D01*
X409417Y384250D01*
X410083Y384333D01*
X410667Y384250D01*
X411167Y383917D01*
X411417Y383333D01*
Y381000D01*
G01X417100Y386000D02*
Y381000D01*
G01Y381750D02*
X416767Y381333D01*
X416267Y381083D01*
X415683Y381000D01*
X415017Y381167D01*
X414517Y381583D01*
X414183Y382083D01*
X414100Y382667D01*
X414183Y383250D01*
X414517Y383750D01*
X415017Y384167D01*
X415683Y384333D01*
X416267Y384250D01*
X416683Y384083D01*
X417100Y383750D01*
G01X419783Y384333D02*
Y382000D01*
X420117Y381417D01*
X420617Y381083D01*
X421200Y381000D01*
X421783Y381083D01*
X422283Y381417D01*
X422617Y382000D01*
G01Y381000D02*
Y384333D01*
G01X428133Y383917D02*
X427550Y384250D01*
X427050Y384333D01*
X426383Y384167D01*
X425883Y383833D01*
X425550Y383250D01*
X425467Y382667D01*
X425550Y382083D01*
X425883Y381583D01*
X426383Y381167D01*
X427050Y381000D01*
X427633Y381167D01*
X428133Y381500D01*
G01X432400Y386000D02*
Y381000D01*
G01X431233Y384333D02*
X433567D01*
G01X438000Y381000D02*
X437500Y381083D01*
X437000Y381417D01*
X436667Y382000D01*
X436500Y382667D01*
X436667Y383333D01*
X437000Y383917D01*
X437500Y384250D01*
X438000Y384333D01*
X438500Y384250D01*
X439000Y383917D01*
X439333Y383333D01*
X439417Y382667D01*
X439333Y382000D01*
X439000Y381417D01*
X438500Y381083D01*
X438000Y381000D01*
G01X442433D02*
Y384333D01*
G01Y383667D02*
X442850Y384000D01*
X443267Y384250D01*
X443850Y384333D01*
X444267Y384250D01*
X444767Y384000D01*
G01X452717Y384333D02*
X453717Y381000D01*
X454800Y384333D01*
X455883Y381000D01*
X456883Y384333D01*
G01X460400D02*
Y381000D01*
G01Y385667D02*
X460233Y385750D01*
Y385917D01*
X460400Y386000D01*
X460567Y385917D01*
Y385750D01*
X460400Y385667D01*
G01X467500Y386000D02*
Y381000D01*
G01Y381750D02*
X467167Y381333D01*
X466667Y381083D01*
X466083Y381000D01*
X465417Y381167D01*
X464917Y381583D01*
X464583Y382083D01*
X464500Y382667D01*
X464583Y383250D01*
X464917Y383750D01*
X465417Y384167D01*
X466083Y384333D01*
X466667Y384250D01*
X467083Y384083D01*
X467500Y383750D01*
G01X471600Y386000D02*
Y381000D01*
G01X470433Y384333D02*
X472767D01*
G01X475783Y381000D02*
Y386000D01*
G01Y383583D02*
X476200Y384000D01*
X476617Y384250D01*
X477283Y384333D01*
X477783Y384250D01*
X478367Y383917D01*
X478617Y383417D01*
Y381000D01*
G01X487150Y381583D02*
X487567Y381250D01*
X488150Y381000D01*
X488650D01*
X489150Y381167D01*
X489483Y381417D01*
X489650Y381750D01*
X489567Y382250D01*
X489233Y382500D01*
X487733Y383000D01*
X487400Y383583D01*
X487567Y384000D01*
X487900Y384250D01*
X488400Y384333D01*
X488900Y384250D01*
X489400Y384000D01*
G01X492500Y379333D02*
Y384333D01*
G01Y383583D02*
X492917Y384000D01*
X493333Y384250D01*
X494000Y384333D01*
X494583Y384250D01*
X495167Y383833D01*
X495417Y383250D01*
X495500Y382667D01*
X495417Y382083D01*
X495167Y381500D01*
X494667Y381167D01*
X494000Y381000D01*
X493417Y381083D01*
X492833Y381333D01*
X492500Y381667D01*
G01X498350Y383250D02*
X501017D01*
X500767Y383833D01*
X500350Y384167D01*
X499767Y384333D01*
X499183Y384250D01*
X498683Y384000D01*
X498350Y383417D01*
X498183Y382917D01*
Y382417D01*
X498350Y381917D01*
X498767Y381417D01*
X499267Y381083D01*
X499850Y381000D01*
X500433Y381167D01*
X501017Y381667D01*
G01X506533Y383917D02*
X505950Y384250D01*
X505450Y384333D01*
X504783Y384167D01*
X504283Y383833D01*
X503950Y383250D01*
X503867Y382667D01*
X503950Y382083D01*
X504283Y381583D01*
X504783Y381167D01*
X505450Y381000D01*
X506033Y381167D01*
X506533Y381500D01*
G01X510800Y384333D02*
Y381000D01*
G01Y385667D02*
X510633Y385750D01*
Y385917D01*
X510800Y386000D01*
X510967Y385917D01*
Y385750D01*
X510800Y385667D01*
G01X515900Y381000D02*
Y385250D01*
X516067Y385667D01*
X516400Y385917D01*
X516900Y386000D01*
X517400Y385833D01*
X517650Y385417D01*
G01X516650Y384000D02*
X514983D01*
G01X522000Y384333D02*
Y381000D01*
G01Y385667D02*
X521833Y385750D01*
Y385917D01*
X522000Y386000D01*
X522167Y385917D01*
Y385750D01*
X522000Y385667D01*
G01X526350Y383250D02*
X529017D01*
X528767Y383833D01*
X528350Y384167D01*
X527767Y384333D01*
X527183Y384250D01*
X526683Y384000D01*
X526350Y383417D01*
X526183Y382917D01*
Y382417D01*
X526350Y381917D01*
X526767Y381417D01*
X527267Y381083D01*
X527850Y381000D01*
X528433Y381167D01*
X529017Y381667D01*
G01X534700Y386000D02*
Y381000D01*
G01Y381750D02*
X534367Y381333D01*
X533867Y381083D01*
X533283Y381000D01*
X532617Y381167D01*
X532117Y381583D01*
X531783Y382083D01*
X531700Y382667D01*
X531783Y383250D01*
X532117Y383750D01*
X532617Y384167D01*
X533283Y384333D01*
X533867Y384250D01*
X534283Y384083D01*
X534700Y383750D01*
G01X544400Y381000D02*
X543900Y381083D01*
X543400Y381417D01*
X543067Y382000D01*
X542900Y382667D01*
X543067Y383333D01*
X543400Y383917D01*
X543900Y384250D01*
X544400Y384333D01*
X544900Y384250D01*
X545400Y383917D01*
X545733Y383333D01*
X545817Y382667D01*
X545733Y382000D01*
X545400Y381417D01*
X544900Y381083D01*
X544400Y381000D01*
G01X548583D02*
Y384333D01*
G01Y383500D02*
X548917Y383917D01*
X549417Y384250D01*
X550083Y384333D01*
X550667Y384250D01*
X551167Y383917D01*
X551417Y383333D01*
Y381000D01*
G01X561200Y386000D02*
Y381000D01*
G01X560033Y384333D02*
X562367D01*
G01X565383Y381000D02*
Y386000D01*
G01Y383583D02*
X565800Y384000D01*
X566217Y384250D01*
X566883Y384333D01*
X567383Y384250D01*
X567967Y383917D01*
X568217Y383417D01*
Y381000D01*
G01X571150Y383250D02*
X573817D01*
X573567Y383833D01*
X573150Y384167D01*
X572567Y384333D01*
X571983Y384250D01*
X571483Y384000D01*
X571150Y383417D01*
X570983Y382917D01*
Y382417D01*
X571150Y381917D01*
X571567Y381417D01*
X572067Y381083D01*
X572650Y381000D01*
X573233Y381167D01*
X573817Y381667D01*
G01X268250Y391500D02*
Y396500D01*
G01X271750D02*
Y391500D01*
G01Y394000D02*
X268250D01*
G01X275600Y391500D02*
X275100Y391583D01*
X274600Y391917D01*
X274267Y392500D01*
X274100Y393167D01*
X274267Y393833D01*
X274600Y394417D01*
X275100Y394750D01*
X275600Y394833D01*
X276100Y394750D01*
X276600Y394417D01*
X276933Y393833D01*
X277017Y393167D01*
X276933Y392500D01*
X276600Y391917D01*
X276100Y391583D01*
X275600Y391500D01*
G01X279117Y394833D02*
X280117Y391500D01*
X281200Y394833D01*
X282283Y391500D01*
X283283Y394833D01*
G01X285550Y393750D02*
X288217D01*
X287967Y394333D01*
X287550Y394667D01*
X286967Y394833D01*
X286383Y394750D01*
X285883Y394500D01*
X285550Y393917D01*
X285383Y393417D01*
Y392917D01*
X285550Y392417D01*
X285967Y391917D01*
X286467Y391583D01*
X287050Y391500D01*
X287633Y391667D01*
X288217Y392167D01*
G01X290900Y394833D02*
X292400Y391500D01*
X293900Y394833D01*
G01X296750Y393750D02*
X299417D01*
X299167Y394333D01*
X298750Y394667D01*
X298167Y394833D01*
X297583Y394750D01*
X297083Y394500D01*
X296750Y393917D01*
X296583Y393417D01*
Y392917D01*
X296750Y392417D01*
X297167Y391917D01*
X297667Y391583D01*
X298250Y391500D01*
X298833Y391667D01*
X299417Y392167D01*
G01X302433Y391500D02*
Y394833D01*
G01Y394167D02*
X302850Y394500D01*
X303267Y394750D01*
X303850Y394833D01*
X304267Y394750D01*
X304767Y394500D01*
G01X309033Y390583D02*
X309367Y391667D01*
G01X314800Y396500D02*
Y391500D01*
G01X313633Y394833D02*
X315967D01*
G01X318983Y391500D02*
Y396500D01*
G01Y394083D02*
X319400Y394500D01*
X319817Y394750D01*
X320483Y394833D01*
X320983Y394750D01*
X321567Y394417D01*
X321817Y393917D01*
Y391500D01*
G01X324750Y393750D02*
X327417D01*
X327167Y394333D01*
X326750Y394667D01*
X326167Y394833D01*
X325583Y394750D01*
X325083Y394500D01*
X324750Y393917D01*
X324583Y393417D01*
Y392917D01*
X324750Y392417D01*
X325167Y391917D01*
X325667Y391583D01*
X326250Y391500D01*
X326833Y391667D01*
X327417Y392167D01*
G01X337200Y396500D02*
Y391500D01*
G01X336033Y394833D02*
X338367D01*
G01X344300Y391500D02*
Y394833D01*
G01Y394250D02*
X343967Y394583D01*
X343467Y394750D01*
X342883Y394833D01*
X342300Y394667D01*
X341800Y394333D01*
X341467Y393833D01*
X341300Y393167D01*
X341467Y392500D01*
X341800Y392000D01*
X342300Y391667D01*
X342883Y391500D01*
X343467Y391583D01*
X343967Y391833D01*
X344300Y392167D01*
G01X346983Y391500D02*
Y394833D01*
G01Y394000D02*
X347317Y394417D01*
X347817Y394750D01*
X348483Y394833D01*
X349067Y394750D01*
X349567Y394417D01*
X349817Y393833D01*
Y391500D01*
G01X352833Y390250D02*
X353417Y389917D01*
X354083Y389833D01*
X354667Y389917D01*
X355167Y390333D01*
X355500Y390917D01*
Y394833D01*
G01Y394167D02*
X355167Y394500D01*
X354667Y394750D01*
X354083Y394833D01*
X353417Y394667D01*
X353000Y394333D01*
X352667Y393750D01*
X352500Y393167D01*
X352583Y392667D01*
X352917Y392083D01*
X353417Y391667D01*
X354083Y391500D01*
X354583Y391583D01*
X355167Y391917D01*
X355500Y392250D01*
G01X358350Y393750D02*
X361017D01*
X360767Y394333D01*
X360350Y394667D01*
X359767Y394833D01*
X359183Y394750D01*
X358683Y394500D01*
X358350Y393917D01*
X358183Y393417D01*
Y392917D01*
X358350Y392417D01*
X358767Y391917D01*
X359267Y391583D01*
X359850Y391500D01*
X360433Y391667D01*
X361017Y392167D01*
G01X363783Y391500D02*
Y394833D01*
G01Y394000D02*
X364117Y394417D01*
X364617Y394750D01*
X365283Y394833D01*
X365867Y394750D01*
X366367Y394417D01*
X366617Y393833D01*
Y391500D01*
G01X372133Y394417D02*
X371550Y394750D01*
X371050Y394833D01*
X370383Y394667D01*
X369883Y394333D01*
X369550Y393750D01*
X369467Y393167D01*
X369550Y392583D01*
X369883Y392083D01*
X370383Y391667D01*
X371050Y391500D01*
X371633Y391667D01*
X372133Y392000D01*
G01X374650Y390000D02*
X375150Y389833D01*
X375817Y390000D01*
X376233Y390333D01*
X376567Y390750D01*
X377067Y392083D01*
X378150Y394833D01*
G01X375483D02*
X377067Y392083D01*
G01X386350D02*
X386767Y391750D01*
X387350Y391500D01*
X387850D01*
X388350Y391667D01*
X388683Y391917D01*
X388850Y392250D01*
X388767Y392750D01*
X388433Y393000D01*
X386933Y393500D01*
X386600Y394083D01*
X386767Y394500D01*
X387100Y394750D01*
X387600Y394833D01*
X388100Y394750D01*
X388600Y394500D01*
G01X391783Y391500D02*
Y396500D01*
G01Y394083D02*
X392200Y394500D01*
X392617Y394750D01*
X393283Y394833D01*
X393783Y394750D01*
X394367Y394417D01*
X394617Y393917D01*
Y391500D01*
G01X398800D02*
X398300Y391583D01*
X397800Y391917D01*
X397467Y392500D01*
X397300Y393167D01*
X397467Y393833D01*
X397800Y394417D01*
X398300Y394750D01*
X398800Y394833D01*
X399300Y394750D01*
X399800Y394417D01*
X400133Y393833D01*
X400217Y393167D01*
X400133Y392500D01*
X399800Y391917D01*
X399300Y391583D01*
X398800Y391500D01*
G01X402983Y394833D02*
Y392500D01*
X403317Y391917D01*
X403817Y391583D01*
X404400Y391500D01*
X404983Y391583D01*
X405483Y391917D01*
X405817Y392500D01*
G01Y391500D02*
Y394833D01*
G01X410000Y391500D02*
Y396500D01*
G01X417100D02*
Y391500D01*
G01Y392250D02*
X416767Y391833D01*
X416267Y391583D01*
X415683Y391500D01*
X415017Y391667D01*
X414517Y392083D01*
X414183Y392583D01*
X414100Y393167D01*
X414183Y393750D01*
X414517Y394250D01*
X415017Y394667D01*
X415683Y394833D01*
X416267Y394750D01*
X416683Y394583D01*
X417100Y394250D01*
G01X425383Y391500D02*
Y394833D01*
G01Y394000D02*
X425717Y394417D01*
X426217Y394750D01*
X426883Y394833D01*
X427467Y394750D01*
X427967Y394417D01*
X428217Y393833D01*
Y391500D01*
G01X432400D02*
X431900Y391583D01*
X431400Y391917D01*
X431067Y392500D01*
X430900Y393167D01*
X431067Y393833D01*
X431400Y394417D01*
X431900Y394750D01*
X432400Y394833D01*
X432900Y394750D01*
X433400Y394417D01*
X433733Y393833D01*
X433817Y393167D01*
X433733Y392500D01*
X433400Y391917D01*
X432900Y391583D01*
X432400Y391500D01*
G01X438000Y396500D02*
Y391500D01*
G01X436833Y394833D02*
X439167D01*
G01X448033Y391500D02*
Y394833D01*
G01Y394167D02*
X448450Y394500D01*
X448867Y394750D01*
X449450Y394833D01*
X449867Y394750D01*
X450367Y394500D01*
G01X453550Y393750D02*
X456217D01*
X455967Y394333D01*
X455550Y394667D01*
X454967Y394833D01*
X454383Y394750D01*
X453883Y394500D01*
X453550Y393917D01*
X453383Y393417D01*
Y392917D01*
X453550Y392417D01*
X453967Y391917D01*
X454467Y391583D01*
X455050Y391500D01*
X455633Y391667D01*
X456217Y392167D01*
G01X461900Y396500D02*
Y391500D01*
G01Y392250D02*
X461567Y391833D01*
X461067Y391583D01*
X460483Y391500D01*
X459817Y391667D01*
X459317Y392083D01*
X458983Y392583D01*
X458900Y393167D01*
X458983Y393750D01*
X459317Y394250D01*
X459817Y394667D01*
X460483Y394833D01*
X461067Y394750D01*
X461483Y394583D01*
X461900Y394250D01*
G01X464583Y394833D02*
Y392500D01*
X464917Y391917D01*
X465417Y391583D01*
X466000Y391500D01*
X466583Y391583D01*
X467083Y391917D01*
X467417Y392500D01*
G01Y391500D02*
Y394833D01*
G01X472933Y394417D02*
X472350Y394750D01*
X471850Y394833D01*
X471183Y394667D01*
X470683Y394333D01*
X470350Y393750D01*
X470267Y393167D01*
X470350Y392583D01*
X470683Y392083D01*
X471183Y391667D01*
X471850Y391500D01*
X472433Y391667D01*
X472933Y392000D01*
G01X475950Y393750D02*
X478617D01*
X478367Y394333D01*
X477950Y394667D01*
X477367Y394833D01*
X476783Y394750D01*
X476283Y394500D01*
X475950Y393917D01*
X475783Y393417D01*
Y392917D01*
X475950Y392417D01*
X476367Y391917D01*
X476867Y391583D01*
X477450Y391500D01*
X478033Y391667D01*
X478617Y392167D01*
G01X488400Y396500D02*
Y391500D01*
G01X487233Y394833D02*
X489567D01*
G01X492583Y391500D02*
Y396500D01*
G01Y394083D02*
X493000Y394500D01*
X493417Y394750D01*
X494083Y394833D01*
X494583Y394750D01*
X495167Y394417D01*
X495417Y393917D01*
Y391500D01*
G01X498350Y393750D02*
X501017D01*
X500767Y394333D01*
X500350Y394667D01*
X499767Y394833D01*
X499183Y394750D01*
X498683Y394500D01*
X498350Y393917D01*
X498183Y393417D01*
Y392917D01*
X498350Y392417D01*
X498767Y391917D01*
X499267Y391583D01*
X499850Y391500D01*
X500433Y391667D01*
X501017Y392167D01*
G01X510800Y391500D02*
Y396500D01*
G01X517900Y391500D02*
Y394833D01*
G01Y394250D02*
X517567Y394583D01*
X517067Y394750D01*
X516483Y394833D01*
X515900Y394667D01*
X515400Y394333D01*
X515067Y393833D01*
X514900Y393167D01*
X515067Y392500D01*
X515400Y392000D01*
X515900Y391667D01*
X516483Y391500D01*
X517067Y391583D01*
X517567Y391833D01*
X517900Y392167D01*
G01X520583Y391500D02*
Y394833D01*
G01Y394000D02*
X520917Y394417D01*
X521417Y394750D01*
X522083Y394833D01*
X522667Y394750D01*
X523167Y394417D01*
X523417Y393833D01*
Y391500D01*
G01X529100Y396500D02*
Y391500D01*
G01Y392250D02*
X528767Y391833D01*
X528267Y391583D01*
X527683Y391500D01*
X527017Y391667D01*
X526517Y392083D01*
X526183Y392583D01*
X526100Y393167D01*
X526183Y393750D01*
X526517Y394250D01*
X527017Y394667D01*
X527683Y394833D01*
X528267Y394750D01*
X528683Y394583D01*
X529100Y394250D01*
G01X531700Y391333D02*
X534700Y396500D01*
G01X540133Y394417D02*
X539550Y394750D01*
X539050Y394833D01*
X538383Y394667D01*
X537883Y394333D01*
X537550Y393750D01*
X537467Y393167D01*
X537550Y392583D01*
X537883Y392083D01*
X538383Y391667D01*
X539050Y391500D01*
X539633Y391667D01*
X540133Y392000D01*
G01X544400Y391500D02*
X543900Y391583D01*
X543400Y391917D01*
X543067Y392500D01*
X542900Y393167D01*
X543067Y393833D01*
X543400Y394417D01*
X543900Y394750D01*
X544400Y394833D01*
X544900Y394750D01*
X545400Y394417D01*
X545733Y393833D01*
X545817Y393167D01*
X545733Y392500D01*
X545400Y391917D01*
X544900Y391583D01*
X544400Y391500D01*
G01X548583D02*
Y394833D01*
G01Y394000D02*
X548917Y394417D01*
X549417Y394750D01*
X550083Y394833D01*
X550667Y394750D01*
X551167Y394417D01*
X551417Y393833D01*
Y391500D01*
G01X557100Y396500D02*
Y391500D01*
G01Y392250D02*
X556767Y391833D01*
X556267Y391583D01*
X555683Y391500D01*
X555017Y391667D01*
X554517Y392083D01*
X554183Y392583D01*
X554100Y393167D01*
X554183Y393750D01*
X554517Y394250D01*
X555017Y394667D01*
X555683Y394833D01*
X556267Y394750D01*
X556683Y394583D01*
X557100Y394250D01*
G01X559783Y394833D02*
Y392500D01*
X560117Y391917D01*
X560617Y391583D01*
X561200Y391500D01*
X561783Y391583D01*
X562283Y391917D01*
X562617Y392500D01*
G01Y391500D02*
Y394833D01*
G01X568133Y394417D02*
X567550Y394750D01*
X567050Y394833D01*
X566383Y394667D01*
X565883Y394333D01*
X565550Y393750D01*
X565467Y393167D01*
X565550Y392583D01*
X565883Y392083D01*
X566383Y391667D01*
X567050Y391500D01*
X567633Y391667D01*
X568133Y392000D01*
G01X572400Y396500D02*
Y391500D01*
G01X571233Y394833D02*
X573567D01*
G01X578000Y391500D02*
X577500Y391583D01*
X577000Y391917D01*
X576667Y392500D01*
X576500Y393167D01*
X576667Y393833D01*
X577000Y394417D01*
X577500Y394750D01*
X578000Y394833D01*
X578500Y394750D01*
X579000Y394417D01*
X579333Y393833D01*
X579417Y393167D01*
X579333Y392500D01*
X579000Y391917D01*
X578500Y391583D01*
X578000Y391500D01*
G01X582433D02*
Y394833D01*
G01Y394167D02*
X582850Y394500D01*
X583267Y394750D01*
X583850Y394833D01*
X584267Y394750D01*
X584767Y394500D01*
G01X271500Y402000D02*
Y405333D01*
G01Y404750D02*
X271167Y405083D01*
X270667Y405250D01*
X270083Y405333D01*
X269500Y405167D01*
X269000Y404833D01*
X268667Y404333D01*
X268500Y403667D01*
X268667Y403000D01*
X269000Y402500D01*
X269500Y402167D01*
X270083Y402000D01*
X270667Y402083D01*
X271167Y402333D01*
X271500Y402667D01*
G01X276933Y404917D02*
X276350Y405250D01*
X275850Y405333D01*
X275183Y405167D01*
X274683Y404833D01*
X274350Y404250D01*
X274267Y403667D01*
X274350Y403083D01*
X274683Y402583D01*
X275183Y402167D01*
X275850Y402000D01*
X276433Y402167D01*
X276933Y402500D01*
G01X282533Y404917D02*
X281950Y405250D01*
X281450Y405333D01*
X280783Y405167D01*
X280283Y404833D01*
X279950Y404250D01*
X279867Y403667D01*
X279950Y403083D01*
X280283Y402583D01*
X280783Y402167D01*
X281450Y402000D01*
X282033Y402167D01*
X282533Y402500D01*
G01X285550Y404250D02*
X288217D01*
X287967Y404833D01*
X287550Y405167D01*
X286967Y405333D01*
X286383Y405250D01*
X285883Y405000D01*
X285550Y404417D01*
X285383Y403917D01*
Y403417D01*
X285550Y402917D01*
X285967Y402417D01*
X286467Y402083D01*
X287050Y402000D01*
X287633Y402167D01*
X288217Y402667D01*
G01X290900Y400333D02*
Y405333D01*
G01Y404583D02*
X291317Y405000D01*
X291733Y405250D01*
X292400Y405333D01*
X292983Y405250D01*
X293567Y404833D01*
X293817Y404250D01*
X293900Y403667D01*
X293817Y403083D01*
X293567Y402500D01*
X293067Y402167D01*
X292400Y402000D01*
X291817Y402083D01*
X291233Y402333D01*
X290900Y402667D01*
G01X298000Y407000D02*
Y402000D01*
G01X296833Y405333D02*
X299167D01*
G01X305100Y402000D02*
Y405333D01*
G01Y404750D02*
X304767Y405083D01*
X304267Y405250D01*
X303683Y405333D01*
X303100Y405167D01*
X302600Y404833D01*
X302267Y404333D01*
X302100Y403667D01*
X302267Y403000D01*
X302600Y402500D01*
X303100Y402167D01*
X303683Y402000D01*
X304267Y402083D01*
X304767Y402333D01*
X305100Y402667D01*
G01X307700Y402000D02*
Y407000D01*
G01Y404500D02*
X308117Y405000D01*
X308617Y405250D01*
X309117Y405333D01*
X309867Y405167D01*
X310367Y404833D01*
X310700Y404250D01*
Y403583D01*
X310533Y402917D01*
X310200Y402417D01*
X309617Y402083D01*
X309117Y402000D01*
X308617Y402083D01*
X308117Y402333D01*
X307700Y402750D01*
G01X314800Y402000D02*
Y407000D01*
G01X319150Y404250D02*
X321817D01*
X321567Y404833D01*
X321150Y405167D01*
X320567Y405333D01*
X319983Y405250D01*
X319483Y405000D01*
X319150Y404417D01*
X318983Y403917D01*
Y403417D01*
X319150Y402917D01*
X319567Y402417D01*
X320067Y402083D01*
X320650Y402000D01*
X321233Y402167D01*
X321817Y402667D01*
G01X326000Y401833D02*
X325833Y401917D01*
Y402083D01*
X326000Y402167D01*
X326167Y402083D01*
Y401917D01*
X326000Y401833D01*
G01X270000Y417500D02*
Y412500D01*
G01X268083Y417500D02*
X271917D01*
G01X274183Y412500D02*
Y417500D01*
G01Y415083D02*
X274600Y415500D01*
X275017Y415750D01*
X275683Y415833D01*
X276183Y415750D01*
X276767Y415417D01*
X277017Y414917D01*
Y412500D01*
G01X279950Y414750D02*
X282617D01*
X282367Y415333D01*
X281950Y415667D01*
X281367Y415833D01*
X280783Y415750D01*
X280283Y415500D01*
X279950Y414917D01*
X279783Y414417D01*
Y413917D01*
X279950Y413417D01*
X280367Y412917D01*
X280867Y412583D01*
X281450Y412500D01*
X282033Y412667D01*
X282617Y413167D01*
G01X290900Y412500D02*
Y417500D01*
G01Y415000D02*
X291317Y415500D01*
X291817Y415750D01*
X292317Y415833D01*
X293067Y415667D01*
X293567Y415333D01*
X293900Y414750D01*
Y414083D01*
X293733Y413417D01*
X293400Y412917D01*
X292817Y412583D01*
X292317Y412500D01*
X291817Y412583D01*
X291317Y412833D01*
X290900Y413250D01*
G01X296833Y412500D02*
Y415833D01*
G01Y415167D02*
X297250Y415500D01*
X297667Y415750D01*
X298250Y415833D01*
X298667Y415750D01*
X299167Y415500D01*
G01X302350Y414750D02*
X305017D01*
X304767Y415333D01*
X304350Y415667D01*
X303767Y415833D01*
X303183Y415750D01*
X302683Y415500D01*
X302350Y414917D01*
X302183Y414417D01*
Y413917D01*
X302350Y413417D01*
X302767Y412917D01*
X303267Y412583D01*
X303850Y412500D01*
X304433Y412667D01*
X305017Y413167D01*
G01X310700Y412500D02*
Y415833D01*
G01Y415250D02*
X310367Y415583D01*
X309867Y415750D01*
X309283Y415833D01*
X308700Y415667D01*
X308200Y415333D01*
X307867Y414833D01*
X307700Y414167D01*
X307867Y413500D01*
X308200Y413000D01*
X308700Y412667D01*
X309283Y412500D01*
X309867Y412583D01*
X310367Y412833D01*
X310700Y413167D01*
G01X313383Y412500D02*
Y417500D01*
G01X316050Y415833D02*
X313383Y413917D01*
G01X314467Y414667D02*
X316217Y412500D01*
G01X320400D02*
X319900Y412583D01*
X319400Y412917D01*
X319067Y413500D01*
X318900Y414167D01*
X319067Y414833D01*
X319400Y415417D01*
X319900Y415750D01*
X320400Y415833D01*
X320900Y415750D01*
X321400Y415417D01*
X321733Y414833D01*
X321817Y414167D01*
X321733Y413500D01*
X321400Y412917D01*
X320900Y412583D01*
X320400Y412500D01*
G01X324583Y415833D02*
Y413500D01*
X324917Y412917D01*
X325417Y412583D01*
X326000Y412500D01*
X326583Y412583D01*
X327083Y412917D01*
X327417Y413500D01*
G01Y412500D02*
Y415833D01*
G01X331600Y417500D02*
Y412500D01*
G01X330433Y415833D02*
X332767D01*
G01X342800D02*
Y412500D01*
G01Y417167D02*
X342633Y417250D01*
Y417417D01*
X342800Y417500D01*
X342967Y417417D01*
Y417250D01*
X342800Y417167D01*
G01X347150Y413083D02*
X347567Y412750D01*
X348150Y412500D01*
X348650D01*
X349150Y412667D01*
X349483Y412917D01*
X349650Y413250D01*
X349567Y413750D01*
X349233Y414000D01*
X347733Y414500D01*
X347400Y415083D01*
X347567Y415500D01*
X347900Y415750D01*
X348400Y415833D01*
X348900Y415750D01*
X349400Y415500D01*
G01X358183Y412500D02*
Y415833D01*
G01Y415000D02*
X358517Y415417D01*
X359017Y415750D01*
X359683Y415833D01*
X360267Y415750D01*
X360767Y415417D01*
X361017Y414833D01*
Y412500D01*
G01X365200D02*
X364700Y412583D01*
X364200Y412917D01*
X363867Y413500D01*
X363700Y414167D01*
X363867Y414833D01*
X364200Y415417D01*
X364700Y415750D01*
X365200Y415833D01*
X365700Y415750D01*
X366200Y415417D01*
X366533Y414833D01*
X366617Y414167D01*
X366533Y413500D01*
X366200Y412917D01*
X365700Y412583D01*
X365200Y412500D01*
G01X370800Y417500D02*
Y412500D01*
G01X369633Y415833D02*
X371967D01*
G01X383500Y412500D02*
Y415833D01*
G01Y415250D02*
X383167Y415583D01*
X382667Y415750D01*
X382083Y415833D01*
X381500Y415667D01*
X381000Y415333D01*
X380667Y414833D01*
X380500Y414167D01*
X380667Y413500D01*
X381000Y413000D01*
X381500Y412667D01*
X382083Y412500D01*
X382667Y412583D01*
X383167Y412833D01*
X383500Y413167D01*
G01X387600Y412500D02*
Y417500D01*
G01X393200Y412500D02*
Y417500D01*
G01X398800Y412500D02*
X398300Y412583D01*
X397800Y412917D01*
X397467Y413500D01*
X397300Y414167D01*
X397467Y414833D01*
X397800Y415417D01*
X398300Y415750D01*
X398800Y415833D01*
X399300Y415750D01*
X399800Y415417D01*
X400133Y414833D01*
X400217Y414167D01*
X400133Y413500D01*
X399800Y412917D01*
X399300Y412583D01*
X398800Y412500D01*
G01X402317Y415833D02*
X403317Y412500D01*
X404400Y415833D01*
X405483Y412500D01*
X406483Y415833D01*
G01X408750Y414750D02*
X411417D01*
X411167Y415333D01*
X410750Y415667D01*
X410167Y415833D01*
X409583Y415750D01*
X409083Y415500D01*
X408750Y414917D01*
X408583Y414417D01*
Y413917D01*
X408750Y413417D01*
X409167Y412917D01*
X409667Y412583D01*
X410250Y412500D01*
X410833Y412667D01*
X411417Y413167D01*
G01X417100Y417500D02*
Y412500D01*
G01Y413250D02*
X416767Y412833D01*
X416267Y412583D01*
X415683Y412500D01*
X415017Y412667D01*
X414517Y413083D01*
X414183Y413583D01*
X414100Y414167D01*
X414183Y414750D01*
X414517Y415250D01*
X415017Y415667D01*
X415683Y415833D01*
X416267Y415750D01*
X416683Y415583D01*
X417100Y415250D01*
G01X421033Y411583D02*
X421367Y412667D01*
G01X436500Y412500D02*
Y417500D01*
G01Y415000D02*
X436917Y415500D01*
X437417Y415750D01*
X437917Y415833D01*
X438667Y415667D01*
X439167Y415333D01*
X439500Y414750D01*
Y414083D01*
X439333Y413417D01*
X439000Y412917D01*
X438417Y412583D01*
X437917Y412500D01*
X437417Y412583D01*
X436917Y412833D01*
X436500Y413250D01*
G01X442183Y415833D02*
Y413500D01*
X442517Y412917D01*
X443017Y412583D01*
X443600Y412500D01*
X444183Y412583D01*
X444683Y412917D01*
X445017Y413500D01*
G01Y412500D02*
Y415833D01*
G01X449200Y417500D02*
Y412500D01*
G01X448033Y415833D02*
X450367D01*
G01X461900Y412500D02*
Y415833D01*
G01Y415250D02*
X461567Y415583D01*
X461067Y415750D01*
X460483Y415833D01*
X459900Y415667D01*
X459400Y415333D01*
X459067Y414833D01*
X458900Y414167D01*
X459067Y413500D01*
X459400Y413000D01*
X459900Y412667D01*
X460483Y412500D01*
X461067Y412583D01*
X461567Y412833D01*
X461900Y413167D01*
G01X464583Y412500D02*
Y415833D01*
G01Y415000D02*
X464917Y415417D01*
X465417Y415750D01*
X466083Y415833D01*
X466667Y415750D01*
X467167Y415417D01*
X467417Y414833D01*
Y412500D01*
G01X470183D02*
Y415833D01*
G01Y415000D02*
X470517Y415417D01*
X471017Y415750D01*
X471683Y415833D01*
X472267Y415750D01*
X472767Y415417D01*
X473017Y414833D01*
Y412500D01*
G01X475783Y415833D02*
Y413500D01*
X476117Y412917D01*
X476617Y412583D01*
X477200Y412500D01*
X477783Y412583D01*
X478283Y412917D01*
X478617Y413500D01*
G01Y412500D02*
Y415833D01*
G01X484300Y412500D02*
Y415833D01*
G01Y415250D02*
X483967Y415583D01*
X483467Y415750D01*
X482883Y415833D01*
X482300Y415667D01*
X481800Y415333D01*
X481467Y414833D01*
X481300Y414167D01*
X481467Y413500D01*
X481800Y413000D01*
X482300Y412667D01*
X482883Y412500D01*
X483467Y412583D01*
X483967Y412833D01*
X484300Y413167D01*
G01X488400Y412500D02*
Y417500D01*
G01X498433Y412500D02*
Y415833D01*
G01Y415167D02*
X498850Y415500D01*
X499267Y415750D01*
X499850Y415833D01*
X500267Y415750D01*
X500767Y415500D01*
G01X505200Y415833D02*
Y412500D01*
G01Y417167D02*
X505033Y417250D01*
Y417417D01*
X505200Y417500D01*
X505367Y417417D01*
Y417250D01*
X505200Y417167D01*
G01X509383Y412500D02*
Y415833D01*
G01Y415000D02*
X509717Y415417D01*
X510217Y415750D01*
X510883Y415833D01*
X511467Y415750D01*
X511967Y415417D01*
X512217Y414833D01*
Y412500D01*
G01X515233Y411250D02*
X515817Y410917D01*
X516483Y410833D01*
X517067Y410917D01*
X517567Y411333D01*
X517900Y411917D01*
Y415833D01*
G01Y415167D02*
X517567Y415500D01*
X517067Y415750D01*
X516483Y415833D01*
X515817Y415667D01*
X515400Y415333D01*
X515067Y414750D01*
X514900Y414167D01*
X514983Y413667D01*
X515317Y413083D01*
X515817Y412667D01*
X516483Y412500D01*
X516983Y412583D01*
X517567Y412917D01*
X517900Y413250D01*
G01X527600Y417500D02*
Y412500D01*
G01X526433Y415833D02*
X528767D01*
G01X534700Y412500D02*
Y415833D01*
G01Y415250D02*
X534367Y415583D01*
X533867Y415750D01*
X533283Y415833D01*
X532700Y415667D01*
X532200Y415333D01*
X531867Y414833D01*
X531700Y414167D01*
X531867Y413500D01*
X532200Y413000D01*
X532700Y412667D01*
X533283Y412500D01*
X533867Y412583D01*
X534367Y412833D01*
X534700Y413167D01*
G01X537383Y412500D02*
Y415833D01*
G01Y415000D02*
X537717Y415417D01*
X538217Y415750D01*
X538883Y415833D01*
X539467Y415750D01*
X539967Y415417D01*
X540217Y414833D01*
Y412500D01*
G01X543233Y411250D02*
X543817Y410917D01*
X544483Y410833D01*
X545067Y410917D01*
X545567Y411333D01*
X545900Y411917D01*
Y415833D01*
G01Y415167D02*
X545567Y415500D01*
X545067Y415750D01*
X544483Y415833D01*
X543817Y415667D01*
X543400Y415333D01*
X543067Y414750D01*
X542900Y414167D01*
X542983Y413667D01*
X543317Y413083D01*
X543817Y412667D01*
X544483Y412500D01*
X544983Y412583D01*
X545567Y412917D01*
X545900Y413250D01*
G01X548750Y414750D02*
X551417D01*
X551167Y415333D01*
X550750Y415667D01*
X550167Y415833D01*
X549583Y415750D01*
X549083Y415500D01*
X548750Y414917D01*
X548583Y414417D01*
Y413917D01*
X548750Y413417D01*
X549167Y412917D01*
X549667Y412583D01*
X550250Y412500D01*
X550833Y412667D01*
X551417Y413167D01*
G01X554183Y412500D02*
Y415833D01*
G01Y415000D02*
X554517Y415417D01*
X555017Y415750D01*
X555683Y415833D01*
X556267Y415750D01*
X556767Y415417D01*
X557017Y414833D01*
Y412500D01*
G01X562533Y415417D02*
X561950Y415750D01*
X561450Y415833D01*
X560783Y415667D01*
X560283Y415333D01*
X559950Y414750D01*
X559867Y414167D01*
X559950Y413583D01*
X560283Y413083D01*
X560783Y412667D01*
X561450Y412500D01*
X562033Y412667D01*
X562533Y413000D01*
G01X565050Y411000D02*
X565550Y410833D01*
X566217Y411000D01*
X566633Y411333D01*
X566967Y411750D01*
X567467Y413083D01*
X568550Y415833D01*
G01X565883D02*
X567467Y413083D01*
G01X578000Y415833D02*
Y412500D01*
G01Y417167D02*
X577833Y417250D01*
Y417417D01*
X578000Y417500D01*
X578167Y417417D01*
Y417250D01*
X578000Y417167D01*
G01X582350Y413083D02*
X582767Y412750D01*
X583350Y412500D01*
X583850D01*
X584350Y412667D01*
X584683Y412917D01*
X584850Y413250D01*
X584767Y413750D01*
X584433Y414000D01*
X582933Y414500D01*
X582600Y415083D01*
X582767Y415500D01*
X583100Y415750D01*
X583600Y415833D01*
X584100Y415750D01*
X584600Y415500D01*
G01X273000Y437500D02*
Y432500D01*
G01Y433250D02*
X272667Y432833D01*
X272167Y432583D01*
X271583Y432500D01*
X270917Y432667D01*
X270417Y433083D01*
X270083Y433583D01*
X270000Y434167D01*
X270083Y434750D01*
X270417Y435250D01*
X270917Y435667D01*
X271583Y435833D01*
X272167Y435750D01*
X272583Y435583D01*
X273000Y435250D01*
G01X275850Y434750D02*
X278517D01*
X278267Y435333D01*
X277850Y435667D01*
X277267Y435833D01*
X276683Y435750D01*
X276183Y435500D01*
X275850Y434917D01*
X275683Y434417D01*
Y433917D01*
X275850Y433417D01*
X276267Y432917D01*
X276767Y432583D01*
X277350Y432500D01*
X277933Y432667D01*
X278517Y433167D01*
G01X281200Y430833D02*
Y435833D01*
G01Y435083D02*
X281617Y435500D01*
X282033Y435750D01*
X282700Y435833D01*
X283283Y435750D01*
X283867Y435333D01*
X284117Y434750D01*
X284200Y434167D01*
X284117Y433583D01*
X283867Y433000D01*
X283367Y432667D01*
X282700Y432500D01*
X282117Y432583D01*
X281533Y432833D01*
X281200Y433167D01*
G01X288300Y437500D02*
Y432500D01*
G01X287133Y435833D02*
X289467D01*
G01X292483Y432500D02*
Y437500D01*
G01Y435083D02*
X292900Y435500D01*
X293317Y435750D01*
X293983Y435833D01*
X294483Y435750D01*
X295067Y435417D01*
X295317Y434917D01*
Y432500D01*
G01X305100Y437500D02*
Y432500D01*
G01X303933Y435833D02*
X306267D01*
G01X310700Y432500D02*
X310200Y432583D01*
X309700Y432917D01*
X309367Y433500D01*
X309200Y434167D01*
X309367Y434833D01*
X309700Y435417D01*
X310200Y435750D01*
X310700Y435833D01*
X311200Y435750D01*
X311700Y435417D01*
X312033Y434833D01*
X312117Y434167D01*
X312033Y433500D01*
X311700Y432917D01*
X311200Y432583D01*
X310700Y432500D01*
G01X316300D02*
Y437500D01*
G01X320650Y434750D02*
X323317D01*
X323067Y435333D01*
X322650Y435667D01*
X322067Y435833D01*
X321483Y435750D01*
X320983Y435500D01*
X320650Y434917D01*
X320483Y434417D01*
Y433917D01*
X320650Y433417D01*
X321067Y432917D01*
X321567Y432583D01*
X322150Y432500D01*
X322733Y432667D01*
X323317Y433167D01*
G01X326333Y432500D02*
Y435833D01*
G01Y435167D02*
X326750Y435500D01*
X327167Y435750D01*
X327750Y435833D01*
X328167Y435750D01*
X328667Y435500D01*
G01X334600Y432500D02*
Y435833D01*
G01Y435250D02*
X334267Y435583D01*
X333767Y435750D01*
X333183Y435833D01*
X332600Y435667D01*
X332100Y435333D01*
X331767Y434833D01*
X331600Y434167D01*
X331767Y433500D01*
X332100Y433000D01*
X332600Y432667D01*
X333183Y432500D01*
X333767Y432583D01*
X334267Y432833D01*
X334600Y433167D01*
G01X337283Y432500D02*
Y435833D01*
G01Y435000D02*
X337617Y435417D01*
X338117Y435750D01*
X338783Y435833D01*
X339367Y435750D01*
X339867Y435417D01*
X340117Y434833D01*
Y432500D01*
G01X345633Y435417D02*
X345050Y435750D01*
X344550Y435833D01*
X343883Y435667D01*
X343383Y435333D01*
X343050Y434750D01*
X342967Y434167D01*
X343050Y433583D01*
X343383Y433083D01*
X343883Y432667D01*
X344550Y432500D01*
X345133Y432667D01*
X345633Y433000D01*
G01X348650Y434750D02*
X351317D01*
X351067Y435333D01*
X350650Y435667D01*
X350067Y435833D01*
X349483Y435750D01*
X348983Y435500D01*
X348650Y434917D01*
X348483Y434417D01*
Y433917D01*
X348650Y433417D01*
X349067Y432917D01*
X349567Y432583D01*
X350150Y432500D01*
X350733Y432667D01*
X351317Y433167D01*
G01X270750Y453500D02*
Y458500D01*
G01X274250D02*
Y453500D01*
G01Y456000D02*
X270750D01*
G01X278100Y453500D02*
X277600Y453583D01*
X277100Y453917D01*
X276767Y454500D01*
X276600Y455167D01*
X276767Y455833D01*
X277100Y456417D01*
X277600Y456750D01*
X278100Y456833D01*
X278600Y456750D01*
X279100Y456417D01*
X279433Y455833D01*
X279517Y455167D01*
X279433Y454500D01*
X279100Y453917D01*
X278600Y453583D01*
X278100Y453500D01*
G01X283700D02*
Y458500D01*
G01X288050Y455750D02*
X290717D01*
X290467Y456333D01*
X290050Y456667D01*
X289467Y456833D01*
X288883Y456750D01*
X288383Y456500D01*
X288050Y455917D01*
X287883Y455417D01*
Y454917D01*
X288050Y454417D01*
X288467Y453917D01*
X288967Y453583D01*
X289550Y453500D01*
X290133Y453667D01*
X290717Y454167D01*
G01X298000Y458500D02*
X299167Y453500D01*
X300500Y458500D01*
X301833Y453500D01*
X303000Y458500D01*
G01X307600Y453500D02*
Y456833D01*
G01Y456250D02*
X307267Y456583D01*
X306767Y456750D01*
X306183Y456833D01*
X305600Y456667D01*
X305100Y456333D01*
X304767Y455833D01*
X304600Y455167D01*
X304767Y454500D01*
X305100Y454000D01*
X305600Y453667D01*
X306183Y453500D01*
X306767Y453583D01*
X307267Y453833D01*
X307600Y454167D01*
G01X311700Y453500D02*
Y458500D01*
G01X317300Y453500D02*
Y458500D01*
G01X326833Y453500D02*
Y458500D01*
X328917D01*
X329583Y458250D01*
X330000Y457917D01*
X330167Y457250D01*
X330000Y456583D01*
X329500Y456167D01*
X328917Y455917D01*
X326833D01*
G01X328917D02*
X330167Y453500D01*
G01X334100D02*
X333600Y453583D01*
X333100Y453917D01*
X332767Y454500D01*
X332600Y455167D01*
X332767Y455833D01*
X333100Y456417D01*
X333600Y456750D01*
X334100Y456833D01*
X334600Y456750D01*
X335100Y456417D01*
X335433Y455833D01*
X335517Y455167D01*
X335433Y454500D01*
X335100Y453917D01*
X334600Y453583D01*
X334100Y453500D01*
G01X338283Y456833D02*
Y454500D01*
X338617Y453917D01*
X339117Y453583D01*
X339700Y453500D01*
X340283Y453583D01*
X340783Y453917D01*
X341117Y454500D01*
G01Y453500D02*
Y456833D01*
G01X344133Y452250D02*
X344717Y451917D01*
X345383Y451833D01*
X345967Y451917D01*
X346467Y452333D01*
X346800Y452917D01*
Y456833D01*
G01Y456167D02*
X346467Y456500D01*
X345967Y456750D01*
X345383Y456833D01*
X344717Y456667D01*
X344300Y456333D01*
X343967Y455750D01*
X343800Y455167D01*
X343883Y454667D01*
X344217Y454083D01*
X344717Y453667D01*
X345383Y453500D01*
X345883Y453583D01*
X346467Y453917D01*
X346800Y454250D01*
G01X349483Y453500D02*
Y458500D01*
G01Y456083D02*
X349900Y456500D01*
X350317Y456750D01*
X350983Y456833D01*
X351483Y456750D01*
X352067Y456417D01*
X352317Y455917D01*
Y453500D01*
G01X355083D02*
Y456833D01*
G01Y456000D02*
X355417Y456417D01*
X355917Y456750D01*
X356583Y456833D01*
X357167Y456750D01*
X357667Y456417D01*
X357917Y455833D01*
Y453500D01*
G01X360850Y455750D02*
X363517D01*
X363267Y456333D01*
X362850Y456667D01*
X362267Y456833D01*
X361683Y456750D01*
X361183Y456500D01*
X360850Y455917D01*
X360683Y455417D01*
Y454917D01*
X360850Y454417D01*
X361267Y453917D01*
X361767Y453583D01*
X362350Y453500D01*
X362933Y453667D01*
X363517Y454167D01*
G01X366450Y454083D02*
X366867Y453750D01*
X367450Y453500D01*
X367950D01*
X368450Y453667D01*
X368783Y453917D01*
X368950Y454250D01*
X368867Y454750D01*
X368533Y455000D01*
X367033Y455500D01*
X366700Y456083D01*
X366867Y456500D01*
X367200Y456750D01*
X367700Y456833D01*
X368200Y456750D01*
X368700Y456500D01*
G01X372050Y454083D02*
X372467Y453750D01*
X373050Y453500D01*
X373550D01*
X374050Y453667D01*
X374383Y453917D01*
X374550Y454250D01*
X374467Y454750D01*
X374133Y455000D01*
X372633Y455500D01*
X372300Y456083D01*
X372467Y456500D01*
X372800Y456750D01*
X373300Y456833D01*
X373800Y456750D01*
X374300Y456500D01*
G01X272500Y470000D02*
X271833Y470083D01*
X271250Y470417D01*
X270750Y470917D01*
X270417Y471500D01*
X270250Y472167D01*
Y472833D01*
X270417Y473500D01*
X270750Y474083D01*
X271250Y474583D01*
X271833Y474917D01*
X272500Y475000D01*
X273167Y474917D01*
X273750Y474583D01*
X274250Y474083D01*
X274583Y473500D01*
X274750Y472833D01*
Y472167D01*
X274583Y471500D01*
X274250Y470917D01*
X273750Y470417D01*
X273167Y470083D01*
X272500Y470000D01*
G01X278100Y475000D02*
Y470000D01*
G01X276933Y473333D02*
X279267D01*
G01X282283Y470000D02*
Y475000D01*
G01Y472583D02*
X282700Y473000D01*
X283117Y473250D01*
X283783Y473333D01*
X284283Y473250D01*
X284867Y472917D01*
X285117Y472417D01*
Y470000D01*
G01X288050Y472250D02*
X290717D01*
X290467Y472833D01*
X290050Y473167D01*
X289467Y473333D01*
X288883Y473250D01*
X288383Y473000D01*
X288050Y472417D01*
X287883Y471917D01*
Y471417D01*
X288050Y470917D01*
X288467Y470417D01*
X288967Y470083D01*
X289550Y470000D01*
X290133Y470167D01*
X290717Y470667D01*
G01X293733Y470000D02*
Y473333D01*
G01Y472667D02*
X294150Y473000D01*
X294567Y473250D01*
X295150Y473333D01*
X295567Y473250D01*
X296067Y473000D01*
G01X299250Y470583D02*
X299667Y470250D01*
X300250Y470000D01*
X300750D01*
X301250Y470167D01*
X301583Y470417D01*
X301750Y470750D01*
X301667Y471250D01*
X301333Y471500D01*
X299833Y472000D01*
X299500Y472583D01*
X299667Y473000D01*
X300000Y473250D01*
X300500Y473333D01*
X301000Y473250D01*
X301500Y473000D01*
G01X311283Y468333D02*
X310450Y469167D01*
X310033Y470000D01*
Y473333D01*
X310450Y474167D01*
X311283Y475000D01*
G01X317300Y470000D02*
Y475000D01*
G01X322900Y473333D02*
Y470000D01*
G01Y474667D02*
X322733Y474750D01*
Y474917D01*
X322900Y475000D01*
X323067Y474917D01*
Y474750D01*
X322900Y474667D01*
G01X327083Y470000D02*
Y475000D01*
G01X329750Y473333D02*
X327083Y471417D01*
G01X328167Y472167D02*
X329917Y470000D01*
G01X332850Y472250D02*
X335517D01*
X335267Y472833D01*
X334850Y473167D01*
X334267Y473333D01*
X333683Y473250D01*
X333183Y473000D01*
X332850Y472417D01*
X332683Y471917D01*
Y471417D01*
X332850Y470917D01*
X333267Y470417D01*
X333767Y470083D01*
X334350Y470000D01*
X334933Y470167D01*
X335517Y470667D01*
G01X344050Y472250D02*
X346717D01*
X346467Y472833D01*
X346050Y473167D01*
X345467Y473333D01*
X344883Y473250D01*
X344383Y473000D01*
X344050Y472417D01*
X343883Y471917D01*
Y471417D01*
X344050Y470917D01*
X344467Y470417D01*
X344967Y470083D01*
X345550Y470000D01*
X346133Y470167D01*
X346717Y470667D01*
G01X350900Y470000D02*
Y475000D01*
G01X356500Y470000D02*
Y475000D01*
G01X362100Y473333D02*
Y470000D01*
G01Y474667D02*
X361933Y474750D01*
Y474917D01*
X362100Y475000D01*
X362267Y474917D01*
Y474750D01*
X362100Y474667D01*
G01X366200Y468333D02*
Y473333D01*
G01Y472583D02*
X366617Y473000D01*
X367033Y473250D01*
X367700Y473333D01*
X368283Y473250D01*
X368867Y472833D01*
X369117Y472250D01*
X369200Y471667D01*
X369117Y471083D01*
X368867Y470500D01*
X368367Y470167D01*
X367700Y470000D01*
X367117Y470083D01*
X366533Y470333D01*
X366200Y470667D01*
G01X372050Y470583D02*
X372467Y470250D01*
X373050Y470000D01*
X373550D01*
X374050Y470167D01*
X374383Y470417D01*
X374550Y470750D01*
X374467Y471250D01*
X374133Y471500D01*
X372633Y472000D01*
X372300Y472583D01*
X372467Y473000D01*
X372800Y473250D01*
X373300Y473333D01*
X373800Y473250D01*
X374300Y473000D01*
G01X377650Y472250D02*
X380317D01*
X380067Y472833D01*
X379650Y473167D01*
X379067Y473333D01*
X378483Y473250D01*
X377983Y473000D01*
X377650Y472417D01*
X377483Y471917D01*
Y471417D01*
X377650Y470917D01*
X378067Y470417D01*
X378567Y470083D01*
X379150Y470000D01*
X379733Y470167D01*
X380317Y470667D01*
G01X391600Y470000D02*
Y473333D01*
G01Y472750D02*
X391267Y473083D01*
X390767Y473250D01*
X390183Y473333D01*
X389600Y473167D01*
X389100Y472833D01*
X388767Y472333D01*
X388600Y471667D01*
X388767Y471000D01*
X389100Y470500D01*
X389600Y470167D01*
X390183Y470000D01*
X390767Y470083D01*
X391267Y470333D01*
X391600Y470667D01*
G01X394283Y470000D02*
Y473333D01*
G01Y472500D02*
X394617Y472917D01*
X395117Y473250D01*
X395783Y473333D01*
X396367Y473250D01*
X396867Y472917D01*
X397117Y472333D01*
Y470000D01*
G01X402800Y475000D02*
Y470000D01*
G01Y470750D02*
X402467Y470333D01*
X401967Y470083D01*
X401383Y470000D01*
X400717Y470167D01*
X400217Y470583D01*
X399883Y471083D01*
X399800Y471667D01*
X399883Y472250D01*
X400217Y472750D01*
X400717Y473167D01*
X401383Y473333D01*
X401967Y473250D01*
X402383Y473083D01*
X402800Y472750D01*
G01X412500Y470000D02*
X412000Y470083D01*
X411500Y470417D01*
X411167Y471000D01*
X411000Y471667D01*
X411167Y472333D01*
X411500Y472917D01*
X412000Y473250D01*
X412500Y473333D01*
X413000Y473250D01*
X413500Y472917D01*
X413833Y472333D01*
X413917Y471667D01*
X413833Y471000D01*
X413500Y470417D01*
X413000Y470083D01*
X412500Y470000D01*
G01X418100Y475000D02*
Y470000D01*
G01X416933Y473333D02*
X419267D01*
G01X422283Y470000D02*
Y475000D01*
G01Y472583D02*
X422700Y473000D01*
X423117Y473250D01*
X423783Y473333D01*
X424283Y473250D01*
X424867Y472917D01*
X425117Y472417D01*
Y470000D01*
G01X428050Y472250D02*
X430717D01*
X430467Y472833D01*
X430050Y473167D01*
X429467Y473333D01*
X428883Y473250D01*
X428383Y473000D01*
X428050Y472417D01*
X427883Y471917D01*
Y471417D01*
X428050Y470917D01*
X428467Y470417D01*
X428967Y470083D01*
X429550Y470000D01*
X430133Y470167D01*
X430717Y470667D01*
G01X433733Y470000D02*
Y473333D01*
G01Y472667D02*
X434150Y473000D01*
X434567Y473250D01*
X435150Y473333D01*
X435567Y473250D01*
X436067Y473000D01*
G01X439250Y470583D02*
X439667Y470250D01*
X440250Y470000D01*
X440750D01*
X441250Y470167D01*
X441583Y470417D01*
X441750Y470750D01*
X441667Y471250D01*
X441333Y471500D01*
X439833Y472000D01*
X439500Y472583D01*
X439667Y473000D01*
X440000Y473250D01*
X440500Y473333D01*
X441000Y473250D01*
X441500Y473000D01*
G01X446517Y468333D02*
X447350Y469167D01*
X447767Y470000D01*
Y473333D01*
X447350Y474167D01*
X446517Y475000D01*
G01X270833Y485000D02*
Y490000D01*
X272833D01*
X273500Y489750D01*
X274000Y489167D01*
X274167Y488500D01*
X274000Y487833D01*
X273583Y487333D01*
X272833Y487083D01*
X270833D01*
G01X278100Y490000D02*
Y485000D01*
G01X276183Y490000D02*
X280017D01*
G01X281950Y485000D02*
Y490000D01*
G01X285450D02*
Y485000D01*
G01Y487500D02*
X281950D01*
G01X287800Y484833D02*
X290800Y490000D01*
G01X292983Y485000D02*
Y490000D01*
X296817Y485000D01*
Y490000D01*
G01X298833Y485000D02*
Y490000D01*
X300833D01*
X301500Y489750D01*
X302000Y489167D01*
X302167Y488500D01*
X302000Y487833D01*
X301583Y487333D01*
X300833Y487083D01*
X298833D01*
G01X306100Y490000D02*
Y485000D01*
G01X304183Y490000D02*
X308017D01*
G01X309950Y485000D02*
Y490000D01*
G01X313450D02*
Y485000D01*
G01Y487500D02*
X309950D01*
G01X321233Y485000D02*
X324567Y486667D01*
X321233Y488333D01*
G01X327417Y485917D02*
X329583D01*
G01Y487417D02*
X327417D01*
G01X332267Y485750D02*
X332767Y485333D01*
X333350Y485083D01*
X334100Y485000D01*
X334850Y485167D01*
X335433Y485500D01*
X335850Y486083D01*
X335933Y486750D01*
X335767Y487417D01*
X335350Y487833D01*
X334767Y488167D01*
X334183Y488250D01*
X333600Y488167D01*
X332850Y487833D01*
X333100Y490000D01*
X335350D01*
G01X342800Y485000D02*
Y488333D01*
G01Y487417D02*
X343050Y487833D01*
X343467Y488167D01*
X344050Y488333D01*
X344633Y488167D01*
X345050Y487833D01*
X345300Y487417D01*
Y485000D01*
G01Y487417D02*
X345550Y487833D01*
X345967Y488167D01*
X346550Y488333D01*
X347133Y488167D01*
X347550Y487833D01*
X347800Y487333D01*
Y485000D01*
G01X348400D02*
Y488333D01*
G01Y487417D02*
X348650Y487833D01*
X349067Y488167D01*
X349650Y488333D01*
X350233Y488167D01*
X350650Y487833D01*
X350900Y487417D01*
Y485000D01*
G01Y487417D02*
X351150Y487833D01*
X351567Y488167D01*
X352150Y488333D01*
X352733Y488167D01*
X353150Y487833D01*
X353400Y487333D01*
Y485000D01*
G01X270583Y498500D02*
Y503500D01*
X274417Y498500D01*
Y503500D01*
G01X276433Y498500D02*
Y503500D01*
X278433D01*
X279100Y503250D01*
X279600Y502667D01*
X279767Y502000D01*
X279600Y501333D01*
X279183Y500833D01*
X278433Y500583D01*
X276433D01*
G01X283700Y503500D02*
Y498500D01*
G01X281783Y503500D02*
X285617D01*
G01X287550Y498500D02*
Y503500D01*
G01X291050D02*
Y498500D01*
G01Y501000D02*
X287550D01*
G01X298750Y499167D02*
X299417Y498750D01*
X300167Y498500D01*
X300833D01*
X301500Y498750D01*
X302000Y499167D01*
X302250Y499750D01*
X302083Y500333D01*
X301667Y500833D01*
X300917Y501167D01*
X299917Y501333D01*
X299333Y501667D01*
X299083Y502250D01*
X299250Y502833D01*
X299667Y503250D01*
X300250Y503500D01*
X300833D01*
X301417Y503333D01*
X301917Y502917D01*
G01X306100Y501833D02*
Y498500D01*
G01Y503167D02*
X305933Y503250D01*
Y503417D01*
X306100Y503500D01*
X306267Y503417D01*
Y503250D01*
X306100Y503167D01*
G01X310450Y501833D02*
X312950D01*
X310450Y498500D01*
X312950D01*
G01X316050Y500750D02*
X318717D01*
X318467Y501333D01*
X318050Y501667D01*
X317467Y501833D01*
X316883Y501750D01*
X316383Y501500D01*
X316050Y500917D01*
X315883Y500417D01*
Y499917D01*
X316050Y499417D01*
X316467Y498917D01*
X316967Y498583D01*
X317550Y498500D01*
X318133Y498667D01*
X318717Y499167D01*
G01X326667Y499500D02*
X327167Y498917D01*
X327833Y498583D01*
X328583Y498500D01*
X329250Y498583D01*
X329917Y499000D01*
X330333Y499500D01*
X330417Y500000D01*
X330250Y500583D01*
X329667Y501000D01*
X329083Y501167D01*
X328333D01*
G01X329083D02*
X329583Y501417D01*
X330000Y501833D01*
X330167Y502333D01*
X330000Y502833D01*
X329583Y503250D01*
X328833Y503500D01*
X328083Y503417D01*
X327333Y503083D01*
G01X334100Y498333D02*
X333933Y498417D01*
Y498583D01*
X334100Y498667D01*
X334267Y498583D01*
Y498417D01*
X334100Y498333D01*
G01X337867Y499250D02*
X338367Y498833D01*
X338950Y498583D01*
X339700Y498500D01*
X340450Y498667D01*
X341033Y499000D01*
X341450Y499583D01*
X341533Y500250D01*
X341367Y500917D01*
X340950Y501333D01*
X340367Y501667D01*
X339783Y501750D01*
X339200Y501667D01*
X338450Y501333D01*
X338700Y503500D01*
X340950D01*
G01X343467Y499250D02*
X343967Y498833D01*
X344550Y498583D01*
X345300Y498500D01*
X346050Y498667D01*
X346633Y499000D01*
X347050Y499583D01*
X347133Y500250D01*
X346967Y500917D01*
X346550Y501333D01*
X345967Y501667D01*
X345383Y501750D01*
X344800Y501667D01*
X344050Y501333D01*
X344300Y503500D01*
X346550D01*
G01X348400Y498500D02*
Y501833D01*
G01Y500917D02*
X348650Y501333D01*
X349067Y501667D01*
X349650Y501833D01*
X350233Y501667D01*
X350650Y501333D01*
X350900Y500917D01*
Y498500D01*
G01Y500917D02*
X351150Y501333D01*
X351567Y501667D01*
X352150Y501833D01*
X352733Y501667D01*
X353150Y501333D01*
X353400Y500833D01*
Y498500D01*
G01X354000D02*
Y501833D01*
G01Y500917D02*
X354250Y501333D01*
X354667Y501667D01*
X355250Y501833D01*
X355833Y501667D01*
X356250Y501333D01*
X356500Y500917D01*
Y498500D01*
G01Y500917D02*
X356750Y501333D01*
X357167Y501667D01*
X357750Y501833D01*
X358333Y501667D01*
X358750Y501333D01*
X359000Y500833D01*
Y498500D01*
G01X273000Y437500D02*
Y432500D01*
G01Y433250D02*
X272667Y432833D01*
X272167Y432583D01*
X271583Y432500D01*
X270917Y432667D01*
X270417Y433083D01*
X270083Y433583D01*
X270000Y434167D01*
X270083Y434750D01*
X270417Y435250D01*
X270917Y435667D01*
X271583Y435833D01*
X272167Y435750D01*
X272583Y435583D01*
X273000Y435250D01*
G01X275850Y434750D02*
X278517D01*
X278267Y435333D01*
X277850Y435667D01*
X277267Y435833D01*
X276683Y435750D01*
X276183Y435500D01*
X275850Y434917D01*
X275683Y434417D01*
Y433917D01*
X275850Y433417D01*
X276267Y432917D01*
X276767Y432583D01*
X277350Y432500D01*
X277933Y432667D01*
X278517Y433167D01*
G01X281200Y430833D02*
Y435833D01*
G01Y435083D02*
X281617Y435500D01*
X282033Y435750D01*
X282700Y435833D01*
X283283Y435750D01*
X283867Y435333D01*
X284117Y434750D01*
X284200Y434167D01*
X284117Y433583D01*
X283867Y433000D01*
X283367Y432667D01*
X282700Y432500D01*
X282117Y432583D01*
X281533Y432833D01*
X281200Y433167D01*
G01X288300Y437500D02*
Y432500D01*
G01X287133Y435833D02*
X289467D01*
G01X292483Y432500D02*
Y437500D01*
G01Y435083D02*
X292900Y435500D01*
X293317Y435750D01*
X293983Y435833D01*
X294483Y435750D01*
X295067Y435417D01*
X295317Y434917D01*
Y432500D01*
G01X305100Y437500D02*
Y432500D01*
G01X303933Y435833D02*
X306267D01*
G01X310700Y432500D02*
X310200Y432583D01*
X309700Y432917D01*
X309367Y433500D01*
X309200Y434167D01*
X309367Y434833D01*
X309700Y435417D01*
X310200Y435750D01*
X310700Y435833D01*
X311200Y435750D01*
X311700Y435417D01*
X312033Y434833D01*
X312117Y434167D01*
X312033Y433500D01*
X311700Y432917D01*
X311200Y432583D01*
X310700Y432500D01*
G01X316300D02*
Y437500D01*
G01X320650Y434750D02*
X323317D01*
X323067Y435333D01*
X322650Y435667D01*
X322067Y435833D01*
X321483Y435750D01*
X320983Y435500D01*
X320650Y434917D01*
X320483Y434417D01*
Y433917D01*
X320650Y433417D01*
X321067Y432917D01*
X321567Y432583D01*
X322150Y432500D01*
X322733Y432667D01*
X323317Y433167D01*
G01X326333Y432500D02*
Y435833D01*
G01Y435167D02*
X326750Y435500D01*
X327167Y435750D01*
X327750Y435833D01*
X328167Y435750D01*
X328667Y435500D01*
G01X334600Y432500D02*
Y435833D01*
G01Y435250D02*
X334267Y435583D01*
X333767Y435750D01*
X333183Y435833D01*
X332600Y435667D01*
X332100Y435333D01*
X331767Y434833D01*
X331600Y434167D01*
X331767Y433500D01*
X332100Y433000D01*
X332600Y432667D01*
X333183Y432500D01*
X333767Y432583D01*
X334267Y432833D01*
X334600Y433167D01*
G01X337283Y432500D02*
Y435833D01*
G01Y435000D02*
X337617Y435417D01*
X338117Y435750D01*
X338783Y435833D01*
X339367Y435750D01*
X339867Y435417D01*
X340117Y434833D01*
Y432500D01*
G01X345633Y435417D02*
X345050Y435750D01*
X344550Y435833D01*
X343883Y435667D01*
X343383Y435333D01*
X343050Y434750D01*
X342967Y434167D01*
X343050Y433583D01*
X343383Y433083D01*
X343883Y432667D01*
X344550Y432500D01*
X345133Y432667D01*
X345633Y433000D01*
G01X348650Y434750D02*
X351317D01*
X351067Y435333D01*
X350650Y435667D01*
X350067Y435833D01*
X349483Y435750D01*
X348983Y435500D01*
X348650Y434917D01*
X348483Y434417D01*
Y433917D01*
X348650Y433417D01*
X349067Y432917D01*
X349567Y432583D01*
X350150Y432500D01*
X350733Y432667D01*
X351317Y433167D01*
G01X270750Y453500D02*
Y458500D01*
G01X274250D02*
Y453500D01*
G01Y456000D02*
X270750D01*
G01X278100Y453500D02*
X277600Y453583D01*
X277100Y453917D01*
X276767Y454500D01*
X276600Y455167D01*
X276767Y455833D01*
X277100Y456417D01*
X277600Y456750D01*
X278100Y456833D01*
X278600Y456750D01*
X279100Y456417D01*
X279433Y455833D01*
X279517Y455167D01*
X279433Y454500D01*
X279100Y453917D01*
X278600Y453583D01*
X278100Y453500D01*
G01X283700D02*
Y458500D01*
G01X288050Y455750D02*
X290717D01*
X290467Y456333D01*
X290050Y456667D01*
X289467Y456833D01*
X288883Y456750D01*
X288383Y456500D01*
X288050Y455917D01*
X287883Y455417D01*
Y454917D01*
X288050Y454417D01*
X288467Y453917D01*
X288967Y453583D01*
X289550Y453500D01*
X290133Y453667D01*
X290717Y454167D01*
G01X298000Y458500D02*
X299167Y453500D01*
X300500Y458500D01*
X301833Y453500D01*
X303000Y458500D01*
G01X307600Y453500D02*
Y456833D01*
G01Y456250D02*
X307267Y456583D01*
X306767Y456750D01*
X306183Y456833D01*
X305600Y456667D01*
X305100Y456333D01*
X304767Y455833D01*
X304600Y455167D01*
X304767Y454500D01*
X305100Y454000D01*
X305600Y453667D01*
X306183Y453500D01*
X306767Y453583D01*
X307267Y453833D01*
X307600Y454167D01*
G01X311700Y453500D02*
Y458500D01*
G01X317300Y453500D02*
Y458500D01*
G01X326833Y453500D02*
Y458500D01*
X328917D01*
X329583Y458250D01*
X330000Y457917D01*
X330167Y457250D01*
X330000Y456583D01*
X329500Y456167D01*
X328917Y455917D01*
X326833D01*
G01X328917D02*
X330167Y453500D01*
G01X334100D02*
X333600Y453583D01*
X333100Y453917D01*
X332767Y454500D01*
X332600Y455167D01*
X332767Y455833D01*
X333100Y456417D01*
X333600Y456750D01*
X334100Y456833D01*
X334600Y456750D01*
X335100Y456417D01*
X335433Y455833D01*
X335517Y455167D01*
X335433Y454500D01*
X335100Y453917D01*
X334600Y453583D01*
X334100Y453500D01*
G01X338283Y456833D02*
Y454500D01*
X338617Y453917D01*
X339117Y453583D01*
X339700Y453500D01*
X340283Y453583D01*
X340783Y453917D01*
X341117Y454500D01*
G01Y453500D02*
Y456833D01*
G01X344133Y452250D02*
X344717Y451917D01*
X345383Y451833D01*
X345967Y451917D01*
X346467Y452333D01*
X346800Y452917D01*
Y456833D01*
G01Y456167D02*
X346467Y456500D01*
X345967Y456750D01*
X345383Y456833D01*
X344717Y456667D01*
X344300Y456333D01*
X343967Y455750D01*
X343800Y455167D01*
X343883Y454667D01*
X344217Y454083D01*
X344717Y453667D01*
X345383Y453500D01*
X345883Y453583D01*
X346467Y453917D01*
X346800Y454250D01*
G01X349483Y453500D02*
Y458500D01*
G01Y456083D02*
X349900Y456500D01*
X350317Y456750D01*
X350983Y456833D01*
X351483Y456750D01*
X352067Y456417D01*
X352317Y455917D01*
Y453500D01*
G01X355083D02*
Y456833D01*
G01Y456000D02*
X355417Y456417D01*
X355917Y456750D01*
X356583Y456833D01*
X357167Y456750D01*
X357667Y456417D01*
X357917Y455833D01*
Y453500D01*
G01X360850Y455750D02*
X363517D01*
X363267Y456333D01*
X362850Y456667D01*
X362267Y456833D01*
X361683Y456750D01*
X361183Y456500D01*
X360850Y455917D01*
X360683Y455417D01*
Y454917D01*
X360850Y454417D01*
X361267Y453917D01*
X361767Y453583D01*
X362350Y453500D01*
X362933Y453667D01*
X363517Y454167D01*
G01X366450Y454083D02*
X366867Y453750D01*
X367450Y453500D01*
X367950D01*
X368450Y453667D01*
X368783Y453917D01*
X368950Y454250D01*
X368867Y454750D01*
X368533Y455000D01*
X367033Y455500D01*
X366700Y456083D01*
X366867Y456500D01*
X367200Y456750D01*
X367700Y456833D01*
X368200Y456750D01*
X368700Y456500D01*
G01X372050Y454083D02*
X372467Y453750D01*
X373050Y453500D01*
X373550D01*
X374050Y453667D01*
X374383Y453917D01*
X374550Y454250D01*
X374467Y454750D01*
X374133Y455000D01*
X372633Y455500D01*
X372300Y456083D01*
X372467Y456500D01*
X372800Y456750D01*
X373300Y456833D01*
X373800Y456750D01*
X374300Y456500D01*
G01X272500Y470000D02*
X271833Y470083D01*
X271250Y470417D01*
X270750Y470917D01*
X270417Y471500D01*
X270250Y472167D01*
Y472833D01*
X270417Y473500D01*
X270750Y474083D01*
X271250Y474583D01*
X271833Y474917D01*
X272500Y475000D01*
X273167Y474917D01*
X273750Y474583D01*
X274250Y474083D01*
X274583Y473500D01*
X274750Y472833D01*
Y472167D01*
X274583Y471500D01*
X274250Y470917D01*
X273750Y470417D01*
X273167Y470083D01*
X272500Y470000D01*
G01X278100Y475000D02*
Y470000D01*
G01X276933Y473333D02*
X279267D01*
G01X282283Y470000D02*
Y475000D01*
G01Y472583D02*
X282700Y473000D01*
X283117Y473250D01*
X283783Y473333D01*
X284283Y473250D01*
X284867Y472917D01*
X285117Y472417D01*
Y470000D01*
G01X288050Y472250D02*
X290717D01*
X290467Y472833D01*
X290050Y473167D01*
X289467Y473333D01*
X288883Y473250D01*
X288383Y473000D01*
X288050Y472417D01*
X287883Y471917D01*
Y471417D01*
X288050Y470917D01*
X288467Y470417D01*
X288967Y470083D01*
X289550Y470000D01*
X290133Y470167D01*
X290717Y470667D01*
G01X293733Y470000D02*
Y473333D01*
G01Y472667D02*
X294150Y473000D01*
X294567Y473250D01*
X295150Y473333D01*
X295567Y473250D01*
X296067Y473000D01*
G01X299250Y470583D02*
X299667Y470250D01*
X300250Y470000D01*
X300750D01*
X301250Y470167D01*
X301583Y470417D01*
X301750Y470750D01*
X301667Y471250D01*
X301333Y471500D01*
X299833Y472000D01*
X299500Y472583D01*
X299667Y473000D01*
X300000Y473250D01*
X300500Y473333D01*
X301000Y473250D01*
X301500Y473000D01*
G01X311283Y468333D02*
X310450Y469167D01*
X310033Y470000D01*
Y473333D01*
X310450Y474167D01*
X311283Y475000D01*
G01X317300Y470000D02*
Y475000D01*
G01X322900Y473333D02*
Y470000D01*
G01Y474667D02*
X322733Y474750D01*
Y474917D01*
X322900Y475000D01*
X323067Y474917D01*
Y474750D01*
X322900Y474667D01*
G01X327083Y470000D02*
Y475000D01*
G01X329750Y473333D02*
X327083Y471417D01*
G01X328167Y472167D02*
X329917Y470000D01*
G01X332850Y472250D02*
X335517D01*
X335267Y472833D01*
X334850Y473167D01*
X334267Y473333D01*
X333683Y473250D01*
X333183Y473000D01*
X332850Y472417D01*
X332683Y471917D01*
Y471417D01*
X332850Y470917D01*
X333267Y470417D01*
X333767Y470083D01*
X334350Y470000D01*
X334933Y470167D01*
X335517Y470667D01*
G01X344050Y472250D02*
X346717D01*
X346467Y472833D01*
X346050Y473167D01*
X345467Y473333D01*
X344883Y473250D01*
X344383Y473000D01*
X344050Y472417D01*
X343883Y471917D01*
Y471417D01*
X344050Y470917D01*
X344467Y470417D01*
X344967Y470083D01*
X345550Y470000D01*
X346133Y470167D01*
X346717Y470667D01*
G01X350900Y470000D02*
Y475000D01*
G01X356500Y470000D02*
Y475000D01*
G01X362100Y473333D02*
Y470000D01*
G01Y474667D02*
X361933Y474750D01*
Y474917D01*
X362100Y475000D01*
X362267Y474917D01*
Y474750D01*
X362100Y474667D01*
G01X366200Y468333D02*
Y473333D01*
G01Y472583D02*
X366617Y473000D01*
X367033Y473250D01*
X367700Y473333D01*
X368283Y473250D01*
X368867Y472833D01*
X369117Y472250D01*
X369200Y471667D01*
X369117Y471083D01*
X368867Y470500D01*
X368367Y470167D01*
X367700Y470000D01*
X367117Y470083D01*
X366533Y470333D01*
X366200Y470667D01*
G01X372050Y470583D02*
X372467Y470250D01*
X373050Y470000D01*
X373550D01*
X374050Y470167D01*
X374383Y470417D01*
X374550Y470750D01*
X374467Y471250D01*
X374133Y471500D01*
X372633Y472000D01*
X372300Y472583D01*
X372467Y473000D01*
X372800Y473250D01*
X373300Y473333D01*
X373800Y473250D01*
X374300Y473000D01*
G01X377650Y472250D02*
X380317D01*
X380067Y472833D01*
X379650Y473167D01*
X379067Y473333D01*
X378483Y473250D01*
X377983Y473000D01*
X377650Y472417D01*
X377483Y471917D01*
Y471417D01*
X377650Y470917D01*
X378067Y470417D01*
X378567Y470083D01*
X379150Y470000D01*
X379733Y470167D01*
X380317Y470667D01*
G01X391600Y470000D02*
Y473333D01*
G01Y472750D02*
X391267Y473083D01*
X390767Y473250D01*
X390183Y473333D01*
X389600Y473167D01*
X389100Y472833D01*
X388767Y472333D01*
X388600Y471667D01*
X388767Y471000D01*
X389100Y470500D01*
X389600Y470167D01*
X390183Y470000D01*
X390767Y470083D01*
X391267Y470333D01*
X391600Y470667D01*
G01X394283Y470000D02*
Y473333D01*
G01Y472500D02*
X394617Y472917D01*
X395117Y473250D01*
X395783Y473333D01*
X396367Y473250D01*
X396867Y472917D01*
X397117Y472333D01*
Y470000D01*
G01X402800Y475000D02*
Y470000D01*
G01Y470750D02*
X402467Y470333D01*
X401967Y470083D01*
X401383Y470000D01*
X400717Y470167D01*
X400217Y470583D01*
X399883Y471083D01*
X399800Y471667D01*
X399883Y472250D01*
X400217Y472750D01*
X400717Y473167D01*
X401383Y473333D01*
X401967Y473250D01*
X402383Y473083D01*
X402800Y472750D01*
G01X412500Y470000D02*
X412000Y470083D01*
X411500Y470417D01*
X411167Y471000D01*
X411000Y471667D01*
X411167Y472333D01*
X411500Y472917D01*
X412000Y473250D01*
X412500Y473333D01*
X413000Y473250D01*
X413500Y472917D01*
X413833Y472333D01*
X413917Y471667D01*
X413833Y471000D01*
X413500Y470417D01*
X413000Y470083D01*
X412500Y470000D01*
G01X418100Y475000D02*
Y470000D01*
G01X416933Y473333D02*
X419267D01*
G01X422283Y470000D02*
Y475000D01*
G01Y472583D02*
X422700Y473000D01*
X423117Y473250D01*
X423783Y473333D01*
X424283Y473250D01*
X424867Y472917D01*
X425117Y472417D01*
Y470000D01*
G01X428050Y472250D02*
X430717D01*
X430467Y472833D01*
X430050Y473167D01*
X429467Y473333D01*
X428883Y473250D01*
X428383Y473000D01*
X428050Y472417D01*
X427883Y471917D01*
Y471417D01*
X428050Y470917D01*
X428467Y470417D01*
X428967Y470083D01*
X429550Y470000D01*
X430133Y470167D01*
X430717Y470667D01*
G01X433733Y470000D02*
Y473333D01*
G01Y472667D02*
X434150Y473000D01*
X434567Y473250D01*
X435150Y473333D01*
X435567Y473250D01*
X436067Y473000D01*
G01X439250Y470583D02*
X439667Y470250D01*
X440250Y470000D01*
X440750D01*
X441250Y470167D01*
X441583Y470417D01*
X441750Y470750D01*
X441667Y471250D01*
X441333Y471500D01*
X439833Y472000D01*
X439500Y472583D01*
X439667Y473000D01*
X440000Y473250D01*
X440500Y473333D01*
X441000Y473250D01*
X441500Y473000D01*
G01X446517Y468333D02*
X447350Y469167D01*
X447767Y470000D01*
Y473333D01*
X447350Y474167D01*
X446517Y475000D01*
G01X270833Y485000D02*
Y490000D01*
X272833D01*
X273500Y489750D01*
X274000Y489167D01*
X274167Y488500D01*
X274000Y487833D01*
X273583Y487333D01*
X272833Y487083D01*
X270833D01*
G01X278100Y490000D02*
Y485000D01*
G01X276183Y490000D02*
X280017D01*
G01X281950Y485000D02*
Y490000D01*
G01X285450D02*
Y485000D01*
G01Y487500D02*
X281950D01*
G01X287800Y484833D02*
X290800Y490000D01*
G01X292983Y485000D02*
Y490000D01*
X296817Y485000D01*
Y490000D01*
G01X298833Y485000D02*
Y490000D01*
X300833D01*
X301500Y489750D01*
X302000Y489167D01*
X302167Y488500D01*
X302000Y487833D01*
X301583Y487333D01*
X300833Y487083D01*
X298833D01*
G01X306100Y490000D02*
Y485000D01*
G01X304183Y490000D02*
X308017D01*
G01X309950Y485000D02*
Y490000D01*
G01X313450D02*
Y485000D01*
G01Y487500D02*
X309950D01*
G01X321233Y485000D02*
X324567Y486667D01*
X321233Y488333D01*
G01X327417Y485917D02*
X329583D01*
G01Y487417D02*
X327417D01*
G01X332267Y485750D02*
X332767Y485333D01*
X333350Y485083D01*
X334100Y485000D01*
X334850Y485167D01*
X335433Y485500D01*
X335850Y486083D01*
X335933Y486750D01*
X335767Y487417D01*
X335350Y487833D01*
X334767Y488167D01*
X334183Y488250D01*
X333600Y488167D01*
X332850Y487833D01*
X333100Y490000D01*
X335350D01*
G01X342800Y485000D02*
Y488333D01*
G01Y487417D02*
X343050Y487833D01*
X343467Y488167D01*
X344050Y488333D01*
X344633Y488167D01*
X345050Y487833D01*
X345300Y487417D01*
Y485000D01*
G01Y487417D02*
X345550Y487833D01*
X345967Y488167D01*
X346550Y488333D01*
X347133Y488167D01*
X347550Y487833D01*
X347800Y487333D01*
Y485000D01*
G01X348400D02*
Y488333D01*
G01Y487417D02*
X348650Y487833D01*
X349067Y488167D01*
X349650Y488333D01*
X350233Y488167D01*
X350650Y487833D01*
X350900Y487417D01*
Y485000D01*
G01Y487417D02*
X351150Y487833D01*
X351567Y488167D01*
X352150Y488333D01*
X352733Y488167D01*
X353150Y487833D01*
X353400Y487333D01*
Y485000D01*
G01X270583Y498500D02*
Y503500D01*
X274417Y498500D01*
Y503500D01*
G01X276433Y498500D02*
Y503500D01*
X278433D01*
X279100Y503250D01*
X279600Y502667D01*
X279767Y502000D01*
X279600Y501333D01*
X279183Y500833D01*
X278433Y500583D01*
X276433D01*
G01X283700Y503500D02*
Y498500D01*
G01X281783Y503500D02*
X285617D01*
G01X287550Y498500D02*
Y503500D01*
G01X291050D02*
Y498500D01*
G01Y501000D02*
X287550D01*
G01X298750Y499167D02*
X299417Y498750D01*
X300167Y498500D01*
X300833D01*
X301500Y498750D01*
X302000Y499167D01*
X302250Y499750D01*
X302083Y500333D01*
X301667Y500833D01*
X300917Y501167D01*
X299917Y501333D01*
X299333Y501667D01*
X299083Y502250D01*
X299250Y502833D01*
X299667Y503250D01*
X300250Y503500D01*
X300833D01*
X301417Y503333D01*
X301917Y502917D01*
G01X306100Y501833D02*
Y498500D01*
G01Y503167D02*
X305933Y503250D01*
Y503417D01*
X306100Y503500D01*
X306267Y503417D01*
Y503250D01*
X306100Y503167D01*
G01X310450Y501833D02*
X312950D01*
X310450Y498500D01*
X312950D01*
G01X316050Y500750D02*
X318717D01*
X318467Y501333D01*
X318050Y501667D01*
X317467Y501833D01*
X316883Y501750D01*
X316383Y501500D01*
X316050Y500917D01*
X315883Y500417D01*
Y499917D01*
X316050Y499417D01*
X316467Y498917D01*
X316967Y498583D01*
X317550Y498500D01*
X318133Y498667D01*
X318717Y499167D01*
G01X326667Y499500D02*
X327167Y498917D01*
X327833Y498583D01*
X328583Y498500D01*
X329250Y498583D01*
X329917Y499000D01*
X330333Y499500D01*
X330417Y500000D01*
X330250Y500583D01*
X329667Y501000D01*
X329083Y501167D01*
X328333D01*
G01X329083D02*
X329583Y501417D01*
X330000Y501833D01*
X330167Y502333D01*
X330000Y502833D01*
X329583Y503250D01*
X328833Y503500D01*
X328083Y503417D01*
X327333Y503083D01*
G01X334100Y498333D02*
X333933Y498417D01*
Y498583D01*
X334100Y498667D01*
X334267Y498583D01*
Y498417D01*
X334100Y498333D01*
G01X337867Y499250D02*
X338367Y498833D01*
X338950Y498583D01*
X339700Y498500D01*
X340450Y498667D01*
X341033Y499000D01*
X341450Y499583D01*
X341533Y500250D01*
X341367Y500917D01*
X340950Y501333D01*
X340367Y501667D01*
X339783Y501750D01*
X339200Y501667D01*
X338450Y501333D01*
X338700Y503500D01*
X340950D01*
G01X343467Y499250D02*
X343967Y498833D01*
X344550Y498583D01*
X345300Y498500D01*
X346050Y498667D01*
X346633Y499000D01*
X347050Y499583D01*
X347133Y500250D01*
X346967Y500917D01*
X346550Y501333D01*
X345967Y501667D01*
X345383Y501750D01*
X344800Y501667D01*
X344050Y501333D01*
X344300Y503500D01*
X346550D01*
G01X348400Y498500D02*
Y501833D01*
G01Y500917D02*
X348650Y501333D01*
X349067Y501667D01*
X349650Y501833D01*
X350233Y501667D01*
X350650Y501333D01*
X350900Y500917D01*
Y498500D01*
G01Y500917D02*
X351150Y501333D01*
X351567Y501667D01*
X352150Y501833D01*
X352733Y501667D01*
X353150Y501333D01*
X353400Y500833D01*
Y498500D01*
G01X354000D02*
Y501833D01*
G01Y500917D02*
X354250Y501333D01*
X354667Y501667D01*
X355250Y501833D01*
X355833Y501667D01*
X356250Y501333D01*
X356500Y500917D01*
Y498500D01*
G01Y500917D02*
X356750Y501333D01*
X357167Y501667D01*
X357750Y501833D01*
X358333Y501667D01*
X358750Y501333D01*
X359000Y500833D01*
Y498500D01*
G01X270583Y513500D02*
Y518500D01*
X274417Y513500D01*
Y518500D01*
G01X276433Y513500D02*
Y518500D01*
X278433D01*
X279100Y518250D01*
X279600Y517667D01*
X279767Y517000D01*
X279600Y516333D01*
X279183Y515833D01*
X278433Y515583D01*
X276433D01*
G01X283700Y518500D02*
Y513500D01*
G01X281783Y518500D02*
X285617D01*
G01X287550Y513500D02*
Y518500D01*
G01X291050D02*
Y513500D01*
G01Y516000D02*
X287550D01*
G01X298750Y514167D02*
X299417Y513750D01*
X300167Y513500D01*
X300833D01*
X301500Y513750D01*
X302000Y514167D01*
X302250Y514750D01*
X302083Y515333D01*
X301667Y515833D01*
X300917Y516167D01*
X299917Y516333D01*
X299333Y516667D01*
X299083Y517250D01*
X299250Y517833D01*
X299667Y518250D01*
X300250Y518500D01*
X300833D01*
X301417Y518333D01*
X301917Y517917D01*
G01X306100Y516833D02*
Y513500D01*
G01Y518167D02*
X305933Y518250D01*
Y518417D01*
X306100Y518500D01*
X306267Y518417D01*
Y518250D01*
X306100Y518167D01*
G01X310450Y516833D02*
X312950D01*
X310450Y513500D01*
X312950D01*
G01X316050Y515750D02*
X318717D01*
X318467Y516333D01*
X318050Y516667D01*
X317467Y516833D01*
X316883Y516750D01*
X316383Y516500D01*
X316050Y515917D01*
X315883Y515417D01*
Y514917D01*
X316050Y514417D01*
X316467Y513917D01*
X316967Y513583D01*
X317550Y513500D01*
X318133Y513667D01*
X318717Y514167D01*
G01X324567Y513500D02*
X321233Y515167D01*
X324567Y516833D01*
G01X332267Y514250D02*
X332767Y513833D01*
X333350Y513583D01*
X334100Y513500D01*
X334850Y513667D01*
X335433Y514000D01*
X335850Y514583D01*
X335933Y515250D01*
X335767Y515917D01*
X335350Y516333D01*
X334767Y516667D01*
X334183Y516750D01*
X333600Y516667D01*
X332850Y516333D01*
X333100Y518500D01*
X335350D01*
G01X337200Y513500D02*
Y516833D01*
G01Y515917D02*
X337450Y516333D01*
X337867Y516667D01*
X338450Y516833D01*
X339033Y516667D01*
X339450Y516333D01*
X339700Y515917D01*
Y513500D01*
G01Y515917D02*
X339950Y516333D01*
X340367Y516667D01*
X340950Y516833D01*
X341533Y516667D01*
X341950Y516333D01*
X342200Y515833D01*
Y513500D01*
G01X342800D02*
Y516833D01*
G01Y515917D02*
X343050Y516333D01*
X343467Y516667D01*
X344050Y516833D01*
X344633Y516667D01*
X345050Y516333D01*
X345300Y515917D01*
Y513500D01*
G01Y515917D02*
X345550Y516333D01*
X345967Y516667D01*
X346550Y516833D01*
X347133Y516667D01*
X347550Y516333D01*
X347800Y515833D01*
Y513500D01*
G01X270667Y535000D02*
Y531417D01*
X271000Y530667D01*
X271667Y530167D01*
X272500Y530000D01*
X273333Y530167D01*
X274000Y530667D01*
X274333Y531417D01*
Y535000D01*
G01X276683Y530000D02*
Y533333D01*
G01Y532500D02*
X277017Y532917D01*
X277517Y533250D01*
X278183Y533333D01*
X278767Y533250D01*
X279267Y532917D01*
X279517Y532333D01*
Y530000D01*
G01X282617Y531667D02*
X284783D01*
G01X287800Y528333D02*
Y533333D01*
G01Y532583D02*
X288217Y533000D01*
X288633Y533250D01*
X289300Y533333D01*
X289883Y533250D01*
X290467Y532833D01*
X290717Y532250D01*
X290800Y531667D01*
X290717Y531083D01*
X290467Y530500D01*
X289967Y530167D01*
X289300Y530000D01*
X288717Y530083D01*
X288133Y530333D01*
X287800Y530667D01*
G01X294900Y530000D02*
Y535000D01*
G01X299083Y533333D02*
Y531000D01*
X299417Y530417D01*
X299917Y530083D01*
X300500Y530000D01*
X301083Y530083D01*
X301583Y530417D01*
X301917Y531000D01*
G01Y530000D02*
Y533333D01*
G01X304933Y528750D02*
X305517Y528417D01*
X306183Y528333D01*
X306767Y528417D01*
X307267Y528833D01*
X307600Y529417D01*
Y533333D01*
G01Y532667D02*
X307267Y533000D01*
X306767Y533250D01*
X306183Y533333D01*
X305517Y533167D01*
X305100Y532833D01*
X304767Y532250D01*
X304600Y531667D01*
X304683Y531167D01*
X305017Y530583D01*
X305517Y530167D01*
X306183Y530000D01*
X306683Y530083D01*
X307267Y530417D01*
X307600Y530750D01*
G01X310533Y528750D02*
X311117Y528417D01*
X311783Y528333D01*
X312367Y528417D01*
X312867Y528833D01*
X313200Y529417D01*
Y533333D01*
G01Y532667D02*
X312867Y533000D01*
X312367Y533250D01*
X311783Y533333D01*
X311117Y533167D01*
X310700Y532833D01*
X310367Y532250D01*
X310200Y531667D01*
X310283Y531167D01*
X310617Y530583D01*
X311117Y530167D01*
X311783Y530000D01*
X312283Y530083D01*
X312867Y530417D01*
X313200Y530750D01*
G01X316050Y532250D02*
X318717D01*
X318467Y532833D01*
X318050Y533167D01*
X317467Y533333D01*
X316883Y533250D01*
X316383Y533000D01*
X316050Y532417D01*
X315883Y531917D01*
Y531417D01*
X316050Y530917D01*
X316467Y530417D01*
X316967Y530083D01*
X317550Y530000D01*
X318133Y530167D01*
X318717Y530667D01*
G01X324400Y535000D02*
Y530000D01*
G01Y530750D02*
X324067Y530333D01*
X323567Y530083D01*
X322983Y530000D01*
X322317Y530167D01*
X321817Y530583D01*
X321483Y531083D01*
X321400Y531667D01*
X321483Y532250D01*
X321817Y532750D01*
X322317Y533167D01*
X322983Y533333D01*
X323567Y533250D01*
X323983Y533083D01*
X324400Y532750D01*
G01X332433Y530000D02*
Y535000D01*
X334433D01*
X335100Y534750D01*
X335600Y534167D01*
X335767Y533500D01*
X335600Y532833D01*
X335183Y532333D01*
X334433Y532083D01*
X332433D01*
G01X339700Y535000D02*
Y530000D01*
G01X337783Y535000D02*
X341617D01*
G01X343550Y530000D02*
Y535000D01*
G01X347050D02*
Y530000D01*
G01Y532500D02*
X343550D01*
G01X356083Y528333D02*
X355250Y529167D01*
X354833Y530000D01*
Y533333D01*
X355250Y534167D01*
X356083Y535000D01*
G01X360350Y530000D02*
Y535000D01*
G01X363850D02*
Y530000D01*
G01Y532500D02*
X360350D01*
G01X367700Y530000D02*
X367200Y530083D01*
X366700Y530417D01*
X366367Y531000D01*
X366200Y531667D01*
X366367Y532333D01*
X366700Y532917D01*
X367200Y533250D01*
X367700Y533333D01*
X368200Y533250D01*
X368700Y532917D01*
X369033Y532333D01*
X369117Y531667D01*
X369033Y531000D01*
X368700Y530417D01*
X368200Y530083D01*
X367700Y530000D01*
G01X373300D02*
Y535000D01*
G01X377650Y532250D02*
X380317D01*
X380067Y532833D01*
X379650Y533167D01*
X379067Y533333D01*
X378483Y533250D01*
X377983Y533000D01*
X377650Y532417D01*
X377483Y531917D01*
Y531417D01*
X377650Y530917D01*
X378067Y530417D01*
X378567Y530083D01*
X379150Y530000D01*
X379733Y530167D01*
X380317Y530667D01*
G01X388350D02*
X389017Y530250D01*
X389767Y530000D01*
X390433D01*
X391100Y530250D01*
X391600Y530667D01*
X391850Y531250D01*
X391683Y531833D01*
X391267Y532333D01*
X390517Y532667D01*
X389517Y532833D01*
X388933Y533167D01*
X388683Y533750D01*
X388850Y534333D01*
X389267Y534750D01*
X389850Y535000D01*
X390433D01*
X391017Y534833D01*
X391517Y534417D01*
G01X395700Y533333D02*
Y530000D01*
G01Y534667D02*
X395533Y534750D01*
Y534917D01*
X395700Y535000D01*
X395867Y534917D01*
Y534750D01*
X395700Y534667D01*
G01X400050Y533333D02*
X402550D01*
X400050Y530000D01*
X402550D01*
G01X405650Y532250D02*
X408317D01*
X408067Y532833D01*
X407650Y533167D01*
X407067Y533333D01*
X406483Y533250D01*
X405983Y533000D01*
X405650Y532417D01*
X405483Y531917D01*
Y531417D01*
X405650Y530917D01*
X406067Y530417D01*
X406567Y530083D01*
X407150Y530000D01*
X407733Y530167D01*
X408317Y530667D01*
G01X414167Y530000D02*
X410833Y531667D01*
X414167Y533333D01*
G01X418100Y530000D02*
Y535000D01*
X417100Y534000D01*
G01Y530000D02*
X419100D01*
G01X422283Y530583D02*
X422867Y530167D01*
X423533Y530000D01*
X424200Y530167D01*
X424783Y530667D01*
X425200Y531417D01*
X425367Y532167D01*
Y533083D01*
X425200Y533833D01*
X424783Y534500D01*
X424283Y534833D01*
X423700Y535000D01*
X423033Y534833D01*
X422533Y534500D01*
X422200Y534000D01*
X422033Y533333D01*
X422200Y532750D01*
X422617Y532167D01*
X423117Y531833D01*
X423700Y531750D01*
X424367Y531917D01*
X424867Y532333D01*
X425367Y533083D01*
G01X429133Y530000D02*
X429300Y531083D01*
X429550Y532000D01*
X429883Y532833D01*
X430300Y533750D01*
X430967Y535000D01*
X427633D01*
G01X432400Y530000D02*
Y533333D01*
G01Y532417D02*
X432650Y532833D01*
X433067Y533167D01*
X433650Y533333D01*
X434233Y533167D01*
X434650Y532833D01*
X434900Y532417D01*
Y530000D01*
G01Y532417D02*
X435150Y532833D01*
X435567Y533167D01*
X436150Y533333D01*
X436733Y533167D01*
X437150Y532833D01*
X437400Y532333D01*
Y530000D01*
G01X440500Y533333D02*
Y530000D01*
G01Y534667D02*
X440333Y534750D01*
Y534917D01*
X440500Y535000D01*
X440667Y534917D01*
Y534750D01*
X440500Y534667D01*
G01X446100Y530000D02*
Y535000D01*
G01X455217Y533333D02*
X456217Y530000D01*
X457300Y533333D01*
X458383Y530000D01*
X459383Y533333D01*
G01X462900D02*
Y530000D01*
G01Y534667D02*
X462733Y534750D01*
Y534917D01*
X462900Y535000D01*
X463067Y534917D01*
Y534750D01*
X462900Y534667D01*
G01X468500Y535000D02*
Y530000D01*
G01X467333Y533333D02*
X469667D01*
G01X472683Y530000D02*
Y535000D01*
G01Y532583D02*
X473100Y533000D01*
X473517Y533250D01*
X474183Y533333D01*
X474683Y533250D01*
X475267Y532917D01*
X475517Y532417D01*
Y530000D01*
G01X483550D02*
Y535000D01*
G01X487050D02*
Y530000D01*
G01Y532500D02*
X483550D01*
G01X488817Y530000D02*
X490900Y535000D01*
X492983Y530000D01*
G01X492233Y531750D02*
X489567D01*
G01X494750Y530667D02*
X495417Y530250D01*
X496167Y530000D01*
X496833D01*
X497500Y530250D01*
X498000Y530667D01*
X498250Y531250D01*
X498083Y531833D01*
X497667Y532333D01*
X496917Y532667D01*
X495917Y532833D01*
X495333Y533167D01*
X495083Y533750D01*
X495250Y534333D01*
X495667Y534750D01*
X496250Y535000D01*
X496833D01*
X497417Y534833D01*
X497917Y534417D01*
G01X500433Y535000D02*
Y530000D01*
X503767D01*
G01X511800Y528333D02*
Y533333D01*
G01Y532583D02*
X512217Y533000D01*
X512633Y533250D01*
X513300Y533333D01*
X513883Y533250D01*
X514467Y532833D01*
X514717Y532250D01*
X514800Y531667D01*
X514717Y531083D01*
X514467Y530500D01*
X513967Y530167D01*
X513300Y530000D01*
X512717Y530083D01*
X512133Y530333D01*
X511800Y530667D01*
G01X517733Y530000D02*
Y533333D01*
G01Y532667D02*
X518150Y533000D01*
X518567Y533250D01*
X519150Y533333D01*
X519567Y533250D01*
X520067Y533000D01*
G01X524500Y530000D02*
X524000Y530083D01*
X523500Y530417D01*
X523167Y531000D01*
X523000Y531667D01*
X523167Y532333D01*
X523500Y532917D01*
X524000Y533250D01*
X524500Y533333D01*
X525000Y533250D01*
X525500Y532917D01*
X525833Y532333D01*
X525917Y531667D01*
X525833Y531000D01*
X525500Y530417D01*
X525000Y530083D01*
X524500Y530000D01*
G01X531600Y535000D02*
Y530000D01*
G01Y530750D02*
X531267Y530333D01*
X530767Y530083D01*
X530183Y530000D01*
X529517Y530167D01*
X529017Y530583D01*
X528683Y531083D01*
X528600Y531667D01*
X528683Y532250D01*
X529017Y532750D01*
X529517Y533167D01*
X530183Y533333D01*
X530767Y533250D01*
X531183Y533083D01*
X531600Y532750D01*
G01X534283Y533333D02*
Y531000D01*
X534617Y530417D01*
X535117Y530083D01*
X535700Y530000D01*
X536283Y530083D01*
X536783Y530417D01*
X537117Y531000D01*
G01Y530000D02*
Y533333D01*
G01X542633Y532917D02*
X542050Y533250D01*
X541550Y533333D01*
X540883Y533167D01*
X540383Y532833D01*
X540050Y532250D01*
X539967Y531667D01*
X540050Y531083D01*
X540383Y530583D01*
X540883Y530167D01*
X541550Y530000D01*
X542133Y530167D01*
X542633Y530500D01*
G01X546900Y535000D02*
Y530000D01*
G01X545733Y533333D02*
X548067D01*
G01X551250Y530583D02*
X551667Y530250D01*
X552250Y530000D01*
X552750D01*
X553250Y530167D01*
X553583Y530417D01*
X553750Y530750D01*
X553667Y531250D01*
X553333Y531500D01*
X551833Y532000D01*
X551500Y532583D01*
X551667Y533000D01*
X552000Y533250D01*
X552500Y533333D01*
X553000Y533250D01*
X553500Y533000D01*
G01X558517Y528333D02*
X559350Y529167D01*
X559767Y530000D01*
Y533333D01*
X559350Y534167D01*
X558517Y535000D01*
G01X270667Y550000D02*
Y546417D01*
X271000Y545667D01*
X271667Y545167D01*
X272500Y545000D01*
X273333Y545167D01*
X274000Y545667D01*
X274333Y546417D01*
Y550000D01*
G01X276683Y545000D02*
Y548333D01*
G01Y547500D02*
X277017Y547917D01*
X277517Y548250D01*
X278183Y548333D01*
X278767Y548250D01*
X279267Y547917D01*
X279517Y547333D01*
Y545000D01*
G01X282617Y546667D02*
X284783D01*
G01X287800Y543333D02*
Y548333D01*
G01Y547583D02*
X288217Y548000D01*
X288633Y548250D01*
X289300Y548333D01*
X289883Y548250D01*
X290467Y547833D01*
X290717Y547250D01*
X290800Y546667D01*
X290717Y546083D01*
X290467Y545500D01*
X289967Y545167D01*
X289300Y545000D01*
X288717Y545083D01*
X288133Y545333D01*
X287800Y545667D01*
G01X294900Y545000D02*
Y550000D01*
G01X299083Y548333D02*
Y546000D01*
X299417Y545417D01*
X299917Y545083D01*
X300500Y545000D01*
X301083Y545083D01*
X301583Y545417D01*
X301917Y546000D01*
G01Y545000D02*
Y548333D01*
G01X304933Y543750D02*
X305517Y543417D01*
X306183Y543333D01*
X306767Y543417D01*
X307267Y543833D01*
X307600Y544417D01*
Y548333D01*
G01Y547667D02*
X307267Y548000D01*
X306767Y548250D01*
X306183Y548333D01*
X305517Y548167D01*
X305100Y547833D01*
X304767Y547250D01*
X304600Y546667D01*
X304683Y546167D01*
X305017Y545583D01*
X305517Y545167D01*
X306183Y545000D01*
X306683Y545083D01*
X307267Y545417D01*
X307600Y545750D01*
G01X310533Y543750D02*
X311117Y543417D01*
X311783Y543333D01*
X312367Y543417D01*
X312867Y543833D01*
X313200Y544417D01*
Y548333D01*
G01Y547667D02*
X312867Y548000D01*
X312367Y548250D01*
X311783Y548333D01*
X311117Y548167D01*
X310700Y547833D01*
X310367Y547250D01*
X310200Y546667D01*
X310283Y546167D01*
X310617Y545583D01*
X311117Y545167D01*
X311783Y545000D01*
X312283Y545083D01*
X312867Y545417D01*
X313200Y545750D01*
G01X316050Y547250D02*
X318717D01*
X318467Y547833D01*
X318050Y548167D01*
X317467Y548333D01*
X316883Y548250D01*
X316383Y548000D01*
X316050Y547417D01*
X315883Y546917D01*
Y546417D01*
X316050Y545917D01*
X316467Y545417D01*
X316967Y545083D01*
X317550Y545000D01*
X318133Y545167D01*
X318717Y545667D01*
G01X324400Y550000D02*
Y545000D01*
G01Y545750D02*
X324067Y545333D01*
X323567Y545083D01*
X322983Y545000D01*
X322317Y545167D01*
X321817Y545583D01*
X321483Y546083D01*
X321400Y546667D01*
X321483Y547250D01*
X321817Y547750D01*
X322317Y548167D01*
X322983Y548333D01*
X323567Y548250D01*
X323983Y548083D01*
X324400Y547750D01*
G01X332433Y545000D02*
Y550000D01*
X334433D01*
X335100Y549750D01*
X335600Y549167D01*
X335767Y548500D01*
X335600Y547833D01*
X335183Y547333D01*
X334433Y547083D01*
X332433D01*
G01X339700Y550000D02*
Y545000D01*
G01X337783Y550000D02*
X341617D01*
G01X343550Y545000D02*
Y550000D01*
G01X347050D02*
Y545000D01*
G01Y547500D02*
X343550D01*
G01X356083Y543333D02*
X355250Y544167D01*
X354833Y545000D01*
Y548333D01*
X355250Y549167D01*
X356083Y550000D01*
G01X360350Y545000D02*
Y550000D01*
G01X363850D02*
Y545000D01*
G01Y547500D02*
X360350D01*
G01X367700Y545000D02*
X367200Y545083D01*
X366700Y545417D01*
X366367Y546000D01*
X366200Y546667D01*
X366367Y547333D01*
X366700Y547917D01*
X367200Y548250D01*
X367700Y548333D01*
X368200Y548250D01*
X368700Y547917D01*
X369033Y547333D01*
X369117Y546667D01*
X369033Y546000D01*
X368700Y545417D01*
X368200Y545083D01*
X367700Y545000D01*
G01X373300D02*
Y550000D01*
G01X377650Y547250D02*
X380317D01*
X380067Y547833D01*
X379650Y548167D01*
X379067Y548333D01*
X378483Y548250D01*
X377983Y548000D01*
X377650Y547417D01*
X377483Y546917D01*
Y546417D01*
X377650Y545917D01*
X378067Y545417D01*
X378567Y545083D01*
X379150Y545000D01*
X379733Y545167D01*
X380317Y545667D01*
G01X388350D02*
X389017Y545250D01*
X389767Y545000D01*
X390433D01*
X391100Y545250D01*
X391600Y545667D01*
X391850Y546250D01*
X391683Y546833D01*
X391267Y547333D01*
X390517Y547667D01*
X389517Y547833D01*
X388933Y548167D01*
X388683Y548750D01*
X388850Y549333D01*
X389267Y549750D01*
X389850Y550000D01*
X390433D01*
X391017Y549833D01*
X391517Y549417D01*
G01X395700Y548333D02*
Y545000D01*
G01Y549667D02*
X395533Y549750D01*
Y549917D01*
X395700Y550000D01*
X395867Y549917D01*
Y549750D01*
X395700Y549667D01*
G01X400050Y548333D02*
X402550D01*
X400050Y545000D01*
X402550D01*
G01X405650Y547250D02*
X408317D01*
X408067Y547833D01*
X407650Y548167D01*
X407067Y548333D01*
X406483Y548250D01*
X405983Y548000D01*
X405650Y547417D01*
X405483Y546917D01*
Y546417D01*
X405650Y545917D01*
X406067Y545417D01*
X406567Y545083D01*
X407150Y545000D01*
X407733Y545167D01*
X408317Y545667D01*
G01X414167Y545000D02*
X410833Y546667D01*
X414167Y548333D01*
G01X418100Y545000D02*
Y550000D01*
X417100Y549000D01*
G01Y545000D02*
X419100D01*
G01X422283Y545583D02*
X422867Y545167D01*
X423533Y545000D01*
X424200Y545167D01*
X424783Y545667D01*
X425200Y546417D01*
X425367Y547167D01*
Y548083D01*
X425200Y548833D01*
X424783Y549500D01*
X424283Y549833D01*
X423700Y550000D01*
X423033Y549833D01*
X422533Y549500D01*
X422200Y549000D01*
X422033Y548333D01*
X422200Y547750D01*
X422617Y547167D01*
X423117Y546833D01*
X423700Y546750D01*
X424367Y546917D01*
X424867Y547333D01*
X425367Y548083D01*
G01X429133Y545000D02*
X429300Y546083D01*
X429550Y547000D01*
X429883Y547833D01*
X430300Y548750D01*
X430967Y550000D01*
X427633D01*
G01X432400Y545000D02*
Y548333D01*
G01Y547417D02*
X432650Y547833D01*
X433067Y548167D01*
X433650Y548333D01*
X434233Y548167D01*
X434650Y547833D01*
X434900Y547417D01*
Y545000D01*
G01Y547417D02*
X435150Y547833D01*
X435567Y548167D01*
X436150Y548333D01*
X436733Y548167D01*
X437150Y547833D01*
X437400Y547333D01*
Y545000D01*
G01X440500Y548333D02*
Y545000D01*
G01Y549667D02*
X440333Y549750D01*
Y549917D01*
X440500Y550000D01*
X440667Y549917D01*
Y549750D01*
X440500Y549667D01*
G01X446100Y545000D02*
Y550000D01*
G01X455217Y548333D02*
X456217Y545000D01*
X457300Y548333D01*
X458383Y545000D01*
X459383Y548333D01*
G01X462900D02*
Y545000D01*
G01Y549667D02*
X462733Y549750D01*
Y549917D01*
X462900Y550000D01*
X463067Y549917D01*
Y549750D01*
X462900Y549667D01*
G01X468500Y550000D02*
Y545000D01*
G01X467333Y548333D02*
X469667D01*
G01X472683Y545000D02*
Y550000D01*
G01Y547583D02*
X473100Y548000D01*
X473517Y548250D01*
X474183Y548333D01*
X474683Y548250D01*
X475267Y547917D01*
X475517Y547417D01*
Y545000D01*
G01X483883D02*
Y548333D01*
G01Y547500D02*
X484217Y547917D01*
X484717Y548250D01*
X485383Y548333D01*
X485967Y548250D01*
X486467Y547917D01*
X486717Y547333D01*
Y545000D01*
G01X490900D02*
X490400Y545083D01*
X489900Y545417D01*
X489567Y546000D01*
X489400Y546667D01*
X489567Y547333D01*
X489900Y547917D01*
X490400Y548250D01*
X490900Y548333D01*
X491400Y548250D01*
X491900Y547917D01*
X492233Y547333D01*
X492317Y546667D01*
X492233Y546000D01*
X491900Y545417D01*
X491400Y545083D01*
X490900Y545000D01*
G01X495083D02*
Y548333D01*
G01Y547500D02*
X495417Y547917D01*
X495917Y548250D01*
X496583Y548333D01*
X497167Y548250D01*
X497667Y547917D01*
X497917Y547333D01*
Y545000D01*
G01X501017Y546667D02*
X503183D01*
G01X505950Y545000D02*
Y550000D01*
G01X509450D02*
Y545000D01*
G01Y547500D02*
X505950D01*
G01X511217Y545000D02*
X513300Y550000D01*
X515383Y545000D01*
G01X514633Y546750D02*
X511967D01*
G01X517150Y545667D02*
X517817Y545250D01*
X518567Y545000D01*
X519233D01*
X519900Y545250D01*
X520400Y545667D01*
X520650Y546250D01*
X520483Y546833D01*
X520067Y547333D01*
X519317Y547667D01*
X518317Y547833D01*
X517733Y548167D01*
X517483Y548750D01*
X517650Y549333D01*
X518067Y549750D01*
X518650Y550000D01*
X519233D01*
X519817Y549833D01*
X520317Y549417D01*
G01X522833Y550000D02*
Y545000D01*
X526167D01*
G01X534200Y543333D02*
Y548333D01*
G01Y547583D02*
X534617Y548000D01*
X535033Y548250D01*
X535700Y548333D01*
X536283Y548250D01*
X536867Y547833D01*
X537117Y547250D01*
X537200Y546667D01*
X537117Y546083D01*
X536867Y545500D01*
X536367Y545167D01*
X535700Y545000D01*
X535117Y545083D01*
X534533Y545333D01*
X534200Y545667D01*
G01X540133Y545000D02*
Y548333D01*
G01Y547667D02*
X540550Y548000D01*
X540967Y548250D01*
X541550Y548333D01*
X541967Y548250D01*
X542467Y548000D01*
G01X546900Y545000D02*
X546400Y545083D01*
X545900Y545417D01*
X545567Y546000D01*
X545400Y546667D01*
X545567Y547333D01*
X545900Y547917D01*
X546400Y548250D01*
X546900Y548333D01*
X547400Y548250D01*
X547900Y547917D01*
X548233Y547333D01*
X548317Y546667D01*
X548233Y546000D01*
X547900Y545417D01*
X547400Y545083D01*
X546900Y545000D01*
G01X554000Y550000D02*
Y545000D01*
G01Y545750D02*
X553667Y545333D01*
X553167Y545083D01*
X552583Y545000D01*
X551917Y545167D01*
X551417Y545583D01*
X551083Y546083D01*
X551000Y546667D01*
X551083Y547250D01*
X551417Y547750D01*
X551917Y548167D01*
X552583Y548333D01*
X553167Y548250D01*
X553583Y548083D01*
X554000Y547750D01*
G01X556683Y548333D02*
Y546000D01*
X557017Y545417D01*
X557517Y545083D01*
X558100Y545000D01*
X558683Y545083D01*
X559183Y545417D01*
X559517Y546000D01*
G01Y545000D02*
Y548333D01*
G01X565033Y547917D02*
X564450Y548250D01*
X563950Y548333D01*
X563283Y548167D01*
X562783Y547833D01*
X562450Y547250D01*
X562367Y546667D01*
X562450Y546083D01*
X562783Y545583D01*
X563283Y545167D01*
X563950Y545000D01*
X564533Y545167D01*
X565033Y545500D01*
G01X569300Y550000D02*
Y545000D01*
G01X568133Y548333D02*
X570467D01*
G01X573650Y545583D02*
X574067Y545250D01*
X574650Y545000D01*
X575150D01*
X575650Y545167D01*
X575983Y545417D01*
X576150Y545750D01*
X576067Y546250D01*
X575733Y546500D01*
X574233Y547000D01*
X573900Y547583D01*
X574067Y548000D01*
X574400Y548250D01*
X574900Y548333D01*
X575400Y548250D01*
X575900Y548000D01*
G01X580917Y543333D02*
X581750Y544167D01*
X582167Y545000D01*
Y548333D01*
X581750Y549167D01*
X580917Y550000D01*
G01X270833Y575000D02*
Y580000D01*
X272833D01*
X273500Y579750D01*
X274000Y579167D01*
X274167Y578500D01*
X274000Y577833D01*
X273583Y577333D01*
X272833Y577083D01*
X270833D01*
G01X278100Y575000D02*
Y580000D01*
G01X282283Y578333D02*
Y576000D01*
X282617Y575417D01*
X283117Y575083D01*
X283700Y575000D01*
X284283Y575083D01*
X284783Y575417D01*
X285117Y576000D01*
G01Y575000D02*
Y578333D01*
G01X288133Y573750D02*
X288717Y573417D01*
X289383Y573333D01*
X289967Y573417D01*
X290467Y573833D01*
X290800Y574417D01*
Y578333D01*
G01Y577667D02*
X290467Y578000D01*
X289967Y578250D01*
X289383Y578333D01*
X288717Y578167D01*
X288300Y577833D01*
X287967Y577250D01*
X287800Y576667D01*
X287883Y576167D01*
X288217Y575583D01*
X288717Y575167D01*
X289383Y575000D01*
X289883Y575083D01*
X290467Y575417D01*
X290800Y575750D01*
G01X293733Y573750D02*
X294317Y573417D01*
X294983Y573333D01*
X295567Y573417D01*
X296067Y573833D01*
X296400Y574417D01*
Y578333D01*
G01Y577667D02*
X296067Y578000D01*
X295567Y578250D01*
X294983Y578333D01*
X294317Y578167D01*
X293900Y577833D01*
X293567Y577250D01*
X293400Y576667D01*
X293483Y576167D01*
X293817Y575583D01*
X294317Y575167D01*
X294983Y575000D01*
X295483Y575083D01*
X296067Y575417D01*
X296400Y575750D01*
G01X299250Y577250D02*
X301917D01*
X301667Y577833D01*
X301250Y578167D01*
X300667Y578333D01*
X300083Y578250D01*
X299583Y578000D01*
X299250Y577417D01*
X299083Y576917D01*
Y576417D01*
X299250Y575917D01*
X299667Y575417D01*
X300167Y575083D01*
X300750Y575000D01*
X301333Y575167D01*
X301917Y575667D01*
G01X307600Y580000D02*
Y575000D01*
G01Y575750D02*
X307267Y575333D01*
X306767Y575083D01*
X306183Y575000D01*
X305517Y575167D01*
X305017Y575583D01*
X304683Y576083D01*
X304600Y576667D01*
X304683Y577250D01*
X305017Y577750D01*
X305517Y578167D01*
X306183Y578333D01*
X306767Y578250D01*
X307183Y578083D01*
X307600Y577750D01*
G01X315217Y580000D02*
X317300Y575000D01*
X319383Y580000D01*
G01X322900Y578333D02*
Y575000D01*
G01Y579667D02*
X322733Y579750D01*
Y579917D01*
X322900Y580000D01*
X323067Y579917D01*
Y579750D01*
X322900Y579667D01*
G01X330000Y575000D02*
Y578333D01*
G01Y577750D02*
X329667Y578083D01*
X329167Y578250D01*
X328583Y578333D01*
X328000Y578167D01*
X327500Y577833D01*
X327167Y577333D01*
X327000Y576667D01*
X327167Y576000D01*
X327500Y575500D01*
X328000Y575167D01*
X328583Y575000D01*
X329167Y575083D01*
X329667Y575333D01*
X330000Y575667D01*
G01X333683Y573333D02*
X332850Y574167D01*
X332433Y575000D01*
Y578333D01*
X332850Y579167D01*
X333683Y580000D01*
G01X338283Y575000D02*
Y580000D01*
G01Y577583D02*
X338700Y578000D01*
X339117Y578250D01*
X339783Y578333D01*
X340283Y578250D01*
X340867Y577917D01*
X341117Y577417D01*
Y575000D01*
G01X345300D02*
X344800Y575083D01*
X344300Y575417D01*
X343967Y576000D01*
X343800Y576667D01*
X343967Y577333D01*
X344300Y577917D01*
X344800Y578250D01*
X345300Y578333D01*
X345800Y578250D01*
X346300Y577917D01*
X346633Y577333D01*
X346717Y576667D01*
X346633Y576000D01*
X346300Y575417D01*
X345800Y575083D01*
X345300Y575000D01*
G01X350900D02*
Y580000D01*
G01X355250Y577250D02*
X357917D01*
X357667Y577833D01*
X357250Y578167D01*
X356667Y578333D01*
X356083Y578250D01*
X355583Y578000D01*
X355250Y577417D01*
X355083Y576917D01*
Y576417D01*
X355250Y575917D01*
X355667Y575417D01*
X356167Y575083D01*
X356750Y575000D01*
X357333Y575167D01*
X357917Y575667D01*
G01X366450Y575583D02*
X366867Y575250D01*
X367450Y575000D01*
X367950D01*
X368450Y575167D01*
X368783Y575417D01*
X368950Y575750D01*
X368867Y576250D01*
X368533Y576500D01*
X367033Y577000D01*
X366700Y577583D01*
X366867Y578000D01*
X367200Y578250D01*
X367700Y578333D01*
X368200Y578250D01*
X368700Y578000D01*
G01X373300Y578333D02*
Y575000D01*
G01Y579667D02*
X373133Y579750D01*
Y579917D01*
X373300Y580000D01*
X373467Y579917D01*
Y579750D01*
X373300Y579667D01*
G01X377650Y578333D02*
X380150D01*
X377650Y575000D01*
X380150D01*
G01X383250Y577250D02*
X385917D01*
X385667Y577833D01*
X385250Y578167D01*
X384667Y578333D01*
X384083Y578250D01*
X383583Y578000D01*
X383250Y577417D01*
X383083Y576917D01*
Y576417D01*
X383250Y575917D01*
X383667Y575417D01*
X384167Y575083D01*
X384750Y575000D01*
X385333Y575167D01*
X385917Y575667D01*
G01X391767Y575000D02*
X388433Y576667D01*
X391767Y578333D01*
G01X395700Y575000D02*
Y580000D01*
X394700Y579000D01*
G01Y575000D02*
X396700D01*
G01X399717Y577083D02*
X400300Y577667D01*
X400800Y578000D01*
X401467Y578167D01*
X402050Y578000D01*
X402467Y577667D01*
X402800Y577167D01*
X402883Y576583D01*
X402800Y576083D01*
X402467Y575583D01*
X401967Y575167D01*
X401383Y575000D01*
X400717Y575167D01*
X400133Y575667D01*
X399800Y576417D01*
X399717Y577250D01*
X399883Y578333D01*
X400133Y578917D01*
X400550Y579500D01*
X401133Y579917D01*
X401717Y580000D01*
X402300Y579833D01*
X402717Y579417D01*
G01X410000Y575000D02*
Y578333D01*
G01Y577417D02*
X410250Y577833D01*
X410667Y578167D01*
X411250Y578333D01*
X411833Y578167D01*
X412250Y577833D01*
X412500Y577417D01*
Y575000D01*
G01Y577417D02*
X412750Y577833D01*
X413167Y578167D01*
X413750Y578333D01*
X414333Y578167D01*
X414750Y577833D01*
X415000Y577333D01*
Y575000D01*
G01X418100Y578333D02*
Y575000D01*
G01Y579667D02*
X417933Y579750D01*
Y579917D01*
X418100Y580000D01*
X418267Y579917D01*
Y579750D01*
X418100Y579667D01*
G01X423700Y575000D02*
Y580000D01*
G01X429717Y573333D02*
X430550Y574167D01*
X430967Y575000D01*
Y578333D01*
X430550Y579167D01*
X429717Y580000D01*
G01X270833Y560000D02*
Y565000D01*
X272833D01*
X273500Y564750D01*
X274000Y564167D01*
X274167Y563500D01*
X274000Y562833D01*
X273583Y562333D01*
X272833Y562083D01*
X270833D01*
G01X278100Y560000D02*
Y565000D01*
G01X282283Y563333D02*
Y561000D01*
X282617Y560417D01*
X283117Y560083D01*
X283700Y560000D01*
X284283Y560083D01*
X284783Y560417D01*
X285117Y561000D01*
G01Y560000D02*
Y563333D01*
G01X288133Y558750D02*
X288717Y558417D01*
X289383Y558333D01*
X289967Y558417D01*
X290467Y558833D01*
X290800Y559417D01*
Y563333D01*
G01Y562667D02*
X290467Y563000D01*
X289967Y563250D01*
X289383Y563333D01*
X288717Y563167D01*
X288300Y562833D01*
X287967Y562250D01*
X287800Y561667D01*
X287883Y561167D01*
X288217Y560583D01*
X288717Y560167D01*
X289383Y560000D01*
X289883Y560083D01*
X290467Y560417D01*
X290800Y560750D01*
G01X293733Y558750D02*
X294317Y558417D01*
X294983Y558333D01*
X295567Y558417D01*
X296067Y558833D01*
X296400Y559417D01*
Y563333D01*
G01Y562667D02*
X296067Y563000D01*
X295567Y563250D01*
X294983Y563333D01*
X294317Y563167D01*
X293900Y562833D01*
X293567Y562250D01*
X293400Y561667D01*
X293483Y561167D01*
X293817Y560583D01*
X294317Y560167D01*
X294983Y560000D01*
X295483Y560083D01*
X296067Y560417D01*
X296400Y560750D01*
G01X299250Y562250D02*
X301917D01*
X301667Y562833D01*
X301250Y563167D01*
X300667Y563333D01*
X300083Y563250D01*
X299583Y563000D01*
X299250Y562417D01*
X299083Y561917D01*
Y561417D01*
X299250Y560917D01*
X299667Y560417D01*
X300167Y560083D01*
X300750Y560000D01*
X301333Y560167D01*
X301917Y560667D01*
G01X307600Y565000D02*
Y560000D01*
G01Y560750D02*
X307267Y560333D01*
X306767Y560083D01*
X306183Y560000D01*
X305517Y560167D01*
X305017Y560583D01*
X304683Y561083D01*
X304600Y561667D01*
X304683Y562250D01*
X305017Y562750D01*
X305517Y563167D01*
X306183Y563333D01*
X306767Y563250D01*
X307183Y563083D01*
X307600Y562750D01*
G01X315633Y560000D02*
Y565000D01*
X317633D01*
X318300Y564750D01*
X318800Y564167D01*
X318967Y563500D01*
X318800Y562833D01*
X318383Y562333D01*
X317633Y562083D01*
X315633D01*
G01X322900Y565000D02*
Y560000D01*
G01X320983Y565000D02*
X324817D01*
G01X326750Y560000D02*
Y565000D01*
G01X330250D02*
Y560000D01*
G01Y562500D02*
X326750D01*
G01X333683Y558333D02*
X332850Y559167D01*
X332433Y560000D01*
Y563333D01*
X332850Y564167D01*
X333683Y565000D01*
G01X338283Y560000D02*
Y565000D01*
G01Y562583D02*
X338700Y563000D01*
X339117Y563250D01*
X339783Y563333D01*
X340283Y563250D01*
X340867Y562917D01*
X341117Y562417D01*
Y560000D01*
G01X345300D02*
X344800Y560083D01*
X344300Y560417D01*
X343967Y561000D01*
X343800Y561667D01*
X343967Y562333D01*
X344300Y562917D01*
X344800Y563250D01*
X345300Y563333D01*
X345800Y563250D01*
X346300Y562917D01*
X346633Y562333D01*
X346717Y561667D01*
X346633Y561000D01*
X346300Y560417D01*
X345800Y560083D01*
X345300Y560000D01*
G01X350900D02*
Y565000D01*
G01X355250Y562250D02*
X357917D01*
X357667Y562833D01*
X357250Y563167D01*
X356667Y563333D01*
X356083Y563250D01*
X355583Y563000D01*
X355250Y562417D01*
X355083Y561917D01*
Y561417D01*
X355250Y560917D01*
X355667Y560417D01*
X356167Y560083D01*
X356750Y560000D01*
X357333Y560167D01*
X357917Y560667D01*
G01X366450Y560583D02*
X366867Y560250D01*
X367450Y560000D01*
X367950D01*
X368450Y560167D01*
X368783Y560417D01*
X368950Y560750D01*
X368867Y561250D01*
X368533Y561500D01*
X367033Y562000D01*
X366700Y562583D01*
X366867Y563000D01*
X367200Y563250D01*
X367700Y563333D01*
X368200Y563250D01*
X368700Y563000D01*
G01X373300Y563333D02*
Y560000D01*
G01Y564667D02*
X373133Y564750D01*
Y564917D01*
X373300Y565000D01*
X373467Y564917D01*
Y564750D01*
X373300Y564667D01*
G01X377650Y563333D02*
X380150D01*
X377650Y560000D01*
X380150D01*
G01X383250Y562250D02*
X385917D01*
X385667Y562833D01*
X385250Y563167D01*
X384667Y563333D01*
X384083Y563250D01*
X383583Y563000D01*
X383250Y562417D01*
X383083Y561917D01*
Y561417D01*
X383250Y560917D01*
X383667Y560417D01*
X384167Y560083D01*
X384750Y560000D01*
X385333Y560167D01*
X385917Y560667D01*
G01X388433Y560000D02*
X391767Y561667D01*
X388433Y563333D01*
G01X394617Y560917D02*
X396783D01*
G01Y562417D02*
X394617D01*
G01X401300Y560000D02*
Y565000D01*
X400300Y564000D01*
G01Y560000D02*
X402300D01*
G01X405317Y562083D02*
X405900Y562667D01*
X406400Y563000D01*
X407067Y563167D01*
X407650Y563000D01*
X408067Y562667D01*
X408400Y562167D01*
X408483Y561583D01*
X408400Y561083D01*
X408067Y560583D01*
X407567Y560167D01*
X406983Y560000D01*
X406317Y560167D01*
X405733Y560667D01*
X405400Y561417D01*
X405317Y562250D01*
X405483Y563333D01*
X405733Y563917D01*
X406150Y564500D01*
X406733Y564917D01*
X407317Y565000D01*
X407900Y564833D01*
X408317Y564417D01*
G01X415600Y560000D02*
Y563333D01*
G01Y562417D02*
X415850Y562833D01*
X416267Y563167D01*
X416850Y563333D01*
X417433Y563167D01*
X417850Y562833D01*
X418100Y562417D01*
Y560000D01*
G01Y562417D02*
X418350Y562833D01*
X418767Y563167D01*
X419350Y563333D01*
X419933Y563167D01*
X420350Y562833D01*
X420600Y562333D01*
Y560000D01*
G01X423700Y563333D02*
Y560000D01*
G01Y564667D02*
X423533Y564750D01*
Y564917D01*
X423700Y565000D01*
X423867Y564917D01*
Y564750D01*
X423700Y564667D01*
G01X429300Y560000D02*
Y565000D01*
G01X435317Y558333D02*
X436150Y559167D01*
X436567Y560000D01*
Y563333D01*
X436150Y564167D01*
X435317Y565000D01*
G01X270583Y513500D02*
Y518500D01*
X274417Y513500D01*
Y518500D01*
G01X276433Y513500D02*
Y518500D01*
X278433D01*
X279100Y518250D01*
X279600Y517667D01*
X279767Y517000D01*
X279600Y516333D01*
X279183Y515833D01*
X278433Y515583D01*
X276433D01*
G01X283700Y518500D02*
Y513500D01*
G01X281783Y518500D02*
X285617D01*
G01X287550Y513500D02*
Y518500D01*
G01X291050D02*
Y513500D01*
G01Y516000D02*
X287550D01*
G01X298750Y514167D02*
X299417Y513750D01*
X300167Y513500D01*
X300833D01*
X301500Y513750D01*
X302000Y514167D01*
X302250Y514750D01*
X302083Y515333D01*
X301667Y515833D01*
X300917Y516167D01*
X299917Y516333D01*
X299333Y516667D01*
X299083Y517250D01*
X299250Y517833D01*
X299667Y518250D01*
X300250Y518500D01*
X300833D01*
X301417Y518333D01*
X301917Y517917D01*
G01X306100Y516833D02*
Y513500D01*
G01Y518167D02*
X305933Y518250D01*
Y518417D01*
X306100Y518500D01*
X306267Y518417D01*
Y518250D01*
X306100Y518167D01*
G01X310450Y516833D02*
X312950D01*
X310450Y513500D01*
X312950D01*
G01X316050Y515750D02*
X318717D01*
X318467Y516333D01*
X318050Y516667D01*
X317467Y516833D01*
X316883Y516750D01*
X316383Y516500D01*
X316050Y515917D01*
X315883Y515417D01*
Y514917D01*
X316050Y514417D01*
X316467Y513917D01*
X316967Y513583D01*
X317550Y513500D01*
X318133Y513667D01*
X318717Y514167D01*
G01X324567Y513500D02*
X321233Y515167D01*
X324567Y516833D01*
G01X332267Y514250D02*
X332767Y513833D01*
X333350Y513583D01*
X334100Y513500D01*
X334850Y513667D01*
X335433Y514000D01*
X335850Y514583D01*
X335933Y515250D01*
X335767Y515917D01*
X335350Y516333D01*
X334767Y516667D01*
X334183Y516750D01*
X333600Y516667D01*
X332850Y516333D01*
X333100Y518500D01*
X335350D01*
G01X337200Y513500D02*
Y516833D01*
G01Y515917D02*
X337450Y516333D01*
X337867Y516667D01*
X338450Y516833D01*
X339033Y516667D01*
X339450Y516333D01*
X339700Y515917D01*
Y513500D01*
G01Y515917D02*
X339950Y516333D01*
X340367Y516667D01*
X340950Y516833D01*
X341533Y516667D01*
X341950Y516333D01*
X342200Y515833D01*
Y513500D01*
G01X342800D02*
Y516833D01*
G01Y515917D02*
X343050Y516333D01*
X343467Y516667D01*
X344050Y516833D01*
X344633Y516667D01*
X345050Y516333D01*
X345300Y515917D01*
Y513500D01*
G01Y515917D02*
X345550Y516333D01*
X345967Y516667D01*
X346550Y516833D01*
X347133Y516667D01*
X347550Y516333D01*
X347800Y515833D01*
Y513500D01*
G01X270667Y535000D02*
Y531417D01*
X271000Y530667D01*
X271667Y530167D01*
X272500Y530000D01*
X273333Y530167D01*
X274000Y530667D01*
X274333Y531417D01*
Y535000D01*
G01X276683Y530000D02*
Y533333D01*
G01Y532500D02*
X277017Y532917D01*
X277517Y533250D01*
X278183Y533333D01*
X278767Y533250D01*
X279267Y532917D01*
X279517Y532333D01*
Y530000D01*
G01X282617Y531667D02*
X284783D01*
G01X287800Y528333D02*
Y533333D01*
G01Y532583D02*
X288217Y533000D01*
X288633Y533250D01*
X289300Y533333D01*
X289883Y533250D01*
X290467Y532833D01*
X290717Y532250D01*
X290800Y531667D01*
X290717Y531083D01*
X290467Y530500D01*
X289967Y530167D01*
X289300Y530000D01*
X288717Y530083D01*
X288133Y530333D01*
X287800Y530667D01*
G01X294900Y530000D02*
Y535000D01*
G01X299083Y533333D02*
Y531000D01*
X299417Y530417D01*
X299917Y530083D01*
X300500Y530000D01*
X301083Y530083D01*
X301583Y530417D01*
X301917Y531000D01*
G01Y530000D02*
Y533333D01*
G01X304933Y528750D02*
X305517Y528417D01*
X306183Y528333D01*
X306767Y528417D01*
X307267Y528833D01*
X307600Y529417D01*
Y533333D01*
G01Y532667D02*
X307267Y533000D01*
X306767Y533250D01*
X306183Y533333D01*
X305517Y533167D01*
X305100Y532833D01*
X304767Y532250D01*
X304600Y531667D01*
X304683Y531167D01*
X305017Y530583D01*
X305517Y530167D01*
X306183Y530000D01*
X306683Y530083D01*
X307267Y530417D01*
X307600Y530750D01*
G01X310533Y528750D02*
X311117Y528417D01*
X311783Y528333D01*
X312367Y528417D01*
X312867Y528833D01*
X313200Y529417D01*
Y533333D01*
G01Y532667D02*
X312867Y533000D01*
X312367Y533250D01*
X311783Y533333D01*
X311117Y533167D01*
X310700Y532833D01*
X310367Y532250D01*
X310200Y531667D01*
X310283Y531167D01*
X310617Y530583D01*
X311117Y530167D01*
X311783Y530000D01*
X312283Y530083D01*
X312867Y530417D01*
X313200Y530750D01*
G01X316050Y532250D02*
X318717D01*
X318467Y532833D01*
X318050Y533167D01*
X317467Y533333D01*
X316883Y533250D01*
X316383Y533000D01*
X316050Y532417D01*
X315883Y531917D01*
Y531417D01*
X316050Y530917D01*
X316467Y530417D01*
X316967Y530083D01*
X317550Y530000D01*
X318133Y530167D01*
X318717Y530667D01*
G01X324400Y535000D02*
Y530000D01*
G01Y530750D02*
X324067Y530333D01*
X323567Y530083D01*
X322983Y530000D01*
X322317Y530167D01*
X321817Y530583D01*
X321483Y531083D01*
X321400Y531667D01*
X321483Y532250D01*
X321817Y532750D01*
X322317Y533167D01*
X322983Y533333D01*
X323567Y533250D01*
X323983Y533083D01*
X324400Y532750D01*
G01X332433Y530000D02*
Y535000D01*
X334433D01*
X335100Y534750D01*
X335600Y534167D01*
X335767Y533500D01*
X335600Y532833D01*
X335183Y532333D01*
X334433Y532083D01*
X332433D01*
G01X339700Y535000D02*
Y530000D01*
G01X337783Y535000D02*
X341617D01*
G01X343550Y530000D02*
Y535000D01*
G01X347050D02*
Y530000D01*
G01Y532500D02*
X343550D01*
G01X356083Y528333D02*
X355250Y529167D01*
X354833Y530000D01*
Y533333D01*
X355250Y534167D01*
X356083Y535000D01*
G01X360350Y530000D02*
Y535000D01*
G01X363850D02*
Y530000D01*
G01Y532500D02*
X360350D01*
G01X367700Y530000D02*
X367200Y530083D01*
X366700Y530417D01*
X366367Y531000D01*
X366200Y531667D01*
X366367Y532333D01*
X366700Y532917D01*
X367200Y533250D01*
X367700Y533333D01*
X368200Y533250D01*
X368700Y532917D01*
X369033Y532333D01*
X369117Y531667D01*
X369033Y531000D01*
X368700Y530417D01*
X368200Y530083D01*
X367700Y530000D01*
G01X373300D02*
Y535000D01*
G01X377650Y532250D02*
X380317D01*
X380067Y532833D01*
X379650Y533167D01*
X379067Y533333D01*
X378483Y533250D01*
X377983Y533000D01*
X377650Y532417D01*
X377483Y531917D01*
Y531417D01*
X377650Y530917D01*
X378067Y530417D01*
X378567Y530083D01*
X379150Y530000D01*
X379733Y530167D01*
X380317Y530667D01*
G01X388350D02*
X389017Y530250D01*
X389767Y530000D01*
X390433D01*
X391100Y530250D01*
X391600Y530667D01*
X391850Y531250D01*
X391683Y531833D01*
X391267Y532333D01*
X390517Y532667D01*
X389517Y532833D01*
X388933Y533167D01*
X388683Y533750D01*
X388850Y534333D01*
X389267Y534750D01*
X389850Y535000D01*
X390433D01*
X391017Y534833D01*
X391517Y534417D01*
G01X395700Y533333D02*
Y530000D01*
G01Y534667D02*
X395533Y534750D01*
Y534917D01*
X395700Y535000D01*
X395867Y534917D01*
Y534750D01*
X395700Y534667D01*
G01X400050Y533333D02*
X402550D01*
X400050Y530000D01*
X402550D01*
G01X405650Y532250D02*
X408317D01*
X408067Y532833D01*
X407650Y533167D01*
X407067Y533333D01*
X406483Y533250D01*
X405983Y533000D01*
X405650Y532417D01*
X405483Y531917D01*
Y531417D01*
X405650Y530917D01*
X406067Y530417D01*
X406567Y530083D01*
X407150Y530000D01*
X407733Y530167D01*
X408317Y530667D01*
G01X414167Y530000D02*
X410833Y531667D01*
X414167Y533333D01*
G01X418100Y530000D02*
Y535000D01*
X417100Y534000D01*
G01Y530000D02*
X419100D01*
G01X422283Y530583D02*
X422867Y530167D01*
X423533Y530000D01*
X424200Y530167D01*
X424783Y530667D01*
X425200Y531417D01*
X425367Y532167D01*
Y533083D01*
X425200Y533833D01*
X424783Y534500D01*
X424283Y534833D01*
X423700Y535000D01*
X423033Y534833D01*
X422533Y534500D01*
X422200Y534000D01*
X422033Y533333D01*
X422200Y532750D01*
X422617Y532167D01*
X423117Y531833D01*
X423700Y531750D01*
X424367Y531917D01*
X424867Y532333D01*
X425367Y533083D01*
G01X429133Y530000D02*
X429300Y531083D01*
X429550Y532000D01*
X429883Y532833D01*
X430300Y533750D01*
X430967Y535000D01*
X427633D01*
G01X432400Y530000D02*
Y533333D01*
G01Y532417D02*
X432650Y532833D01*
X433067Y533167D01*
X433650Y533333D01*
X434233Y533167D01*
X434650Y532833D01*
X434900Y532417D01*
Y530000D01*
G01Y532417D02*
X435150Y532833D01*
X435567Y533167D01*
X436150Y533333D01*
X436733Y533167D01*
X437150Y532833D01*
X437400Y532333D01*
Y530000D01*
G01X440500Y533333D02*
Y530000D01*
G01Y534667D02*
X440333Y534750D01*
Y534917D01*
X440500Y535000D01*
X440667Y534917D01*
Y534750D01*
X440500Y534667D01*
G01X446100Y530000D02*
Y535000D01*
G01X455217Y533333D02*
X456217Y530000D01*
X457300Y533333D01*
X458383Y530000D01*
X459383Y533333D01*
G01X462900D02*
Y530000D01*
G01Y534667D02*
X462733Y534750D01*
Y534917D01*
X462900Y535000D01*
X463067Y534917D01*
Y534750D01*
X462900Y534667D01*
G01X468500Y535000D02*
Y530000D01*
G01X467333Y533333D02*
X469667D01*
G01X472683Y530000D02*
Y535000D01*
G01Y532583D02*
X473100Y533000D01*
X473517Y533250D01*
X474183Y533333D01*
X474683Y533250D01*
X475267Y532917D01*
X475517Y532417D01*
Y530000D01*
G01X483550D02*
Y535000D01*
G01X487050D02*
Y530000D01*
G01Y532500D02*
X483550D01*
G01X488817Y530000D02*
X490900Y535000D01*
X492983Y530000D01*
G01X492233Y531750D02*
X489567D01*
G01X494750Y530667D02*
X495417Y530250D01*
X496167Y530000D01*
X496833D01*
X497500Y530250D01*
X498000Y530667D01*
X498250Y531250D01*
X498083Y531833D01*
X497667Y532333D01*
X496917Y532667D01*
X495917Y532833D01*
X495333Y533167D01*
X495083Y533750D01*
X495250Y534333D01*
X495667Y534750D01*
X496250Y535000D01*
X496833D01*
X497417Y534833D01*
X497917Y534417D01*
G01X500433Y535000D02*
Y530000D01*
X503767D01*
G01X511800Y528333D02*
Y533333D01*
G01Y532583D02*
X512217Y533000D01*
X512633Y533250D01*
X513300Y533333D01*
X513883Y533250D01*
X514467Y532833D01*
X514717Y532250D01*
X514800Y531667D01*
X514717Y531083D01*
X514467Y530500D01*
X513967Y530167D01*
X513300Y530000D01*
X512717Y530083D01*
X512133Y530333D01*
X511800Y530667D01*
G01X517733Y530000D02*
Y533333D01*
G01Y532667D02*
X518150Y533000D01*
X518567Y533250D01*
X519150Y533333D01*
X519567Y533250D01*
X520067Y533000D01*
G01X524500Y530000D02*
X524000Y530083D01*
X523500Y530417D01*
X523167Y531000D01*
X523000Y531667D01*
X523167Y532333D01*
X523500Y532917D01*
X524000Y533250D01*
X524500Y533333D01*
X525000Y533250D01*
X525500Y532917D01*
X525833Y532333D01*
X525917Y531667D01*
X525833Y531000D01*
X525500Y530417D01*
X525000Y530083D01*
X524500Y530000D01*
G01X531600Y535000D02*
Y530000D01*
G01Y530750D02*
X531267Y530333D01*
X530767Y530083D01*
X530183Y530000D01*
X529517Y530167D01*
X529017Y530583D01*
X528683Y531083D01*
X528600Y531667D01*
X528683Y532250D01*
X529017Y532750D01*
X529517Y533167D01*
X530183Y533333D01*
X530767Y533250D01*
X531183Y533083D01*
X531600Y532750D01*
G01X534283Y533333D02*
Y531000D01*
X534617Y530417D01*
X535117Y530083D01*
X535700Y530000D01*
X536283Y530083D01*
X536783Y530417D01*
X537117Y531000D01*
G01Y530000D02*
Y533333D01*
G01X542633Y532917D02*
X542050Y533250D01*
X541550Y533333D01*
X540883Y533167D01*
X540383Y532833D01*
X540050Y532250D01*
X539967Y531667D01*
X540050Y531083D01*
X540383Y530583D01*
X540883Y530167D01*
X541550Y530000D01*
X542133Y530167D01*
X542633Y530500D01*
G01X546900Y535000D02*
Y530000D01*
G01X545733Y533333D02*
X548067D01*
G01X551250Y530583D02*
X551667Y530250D01*
X552250Y530000D01*
X552750D01*
X553250Y530167D01*
X553583Y530417D01*
X553750Y530750D01*
X553667Y531250D01*
X553333Y531500D01*
X551833Y532000D01*
X551500Y532583D01*
X551667Y533000D01*
X552000Y533250D01*
X552500Y533333D01*
X553000Y533250D01*
X553500Y533000D01*
G01X558517Y528333D02*
X559350Y529167D01*
X559767Y530000D01*
Y533333D01*
X559350Y534167D01*
X558517Y535000D01*
G01X270667Y550000D02*
Y546417D01*
X271000Y545667D01*
X271667Y545167D01*
X272500Y545000D01*
X273333Y545167D01*
X274000Y545667D01*
X274333Y546417D01*
Y550000D01*
G01X276683Y545000D02*
Y548333D01*
G01Y547500D02*
X277017Y547917D01*
X277517Y548250D01*
X278183Y548333D01*
X278767Y548250D01*
X279267Y547917D01*
X279517Y547333D01*
Y545000D01*
G01X282617Y546667D02*
X284783D01*
G01X287800Y543333D02*
Y548333D01*
G01Y547583D02*
X288217Y548000D01*
X288633Y548250D01*
X289300Y548333D01*
X289883Y548250D01*
X290467Y547833D01*
X290717Y547250D01*
X290800Y546667D01*
X290717Y546083D01*
X290467Y545500D01*
X289967Y545167D01*
X289300Y545000D01*
X288717Y545083D01*
X288133Y545333D01*
X287800Y545667D01*
G01X294900Y545000D02*
Y550000D01*
G01X299083Y548333D02*
Y546000D01*
X299417Y545417D01*
X299917Y545083D01*
X300500Y545000D01*
X301083Y545083D01*
X301583Y545417D01*
X301917Y546000D01*
G01Y545000D02*
Y548333D01*
G01X304933Y543750D02*
X305517Y543417D01*
X306183Y543333D01*
X306767Y543417D01*
X307267Y543833D01*
X307600Y544417D01*
Y548333D01*
G01Y547667D02*
X307267Y548000D01*
X306767Y548250D01*
X306183Y548333D01*
X305517Y548167D01*
X305100Y547833D01*
X304767Y547250D01*
X304600Y546667D01*
X304683Y546167D01*
X305017Y545583D01*
X305517Y545167D01*
X306183Y545000D01*
X306683Y545083D01*
X307267Y545417D01*
X307600Y545750D01*
G01X310533Y543750D02*
X311117Y543417D01*
X311783Y543333D01*
X312367Y543417D01*
X312867Y543833D01*
X313200Y544417D01*
Y548333D01*
G01Y547667D02*
X312867Y548000D01*
X312367Y548250D01*
X311783Y548333D01*
X311117Y548167D01*
X310700Y547833D01*
X310367Y547250D01*
X310200Y546667D01*
X310283Y546167D01*
X310617Y545583D01*
X311117Y545167D01*
X311783Y545000D01*
X312283Y545083D01*
X312867Y545417D01*
X313200Y545750D01*
G01X316050Y547250D02*
X318717D01*
X318467Y547833D01*
X318050Y548167D01*
X317467Y548333D01*
X316883Y548250D01*
X316383Y548000D01*
X316050Y547417D01*
X315883Y546917D01*
Y546417D01*
X316050Y545917D01*
X316467Y545417D01*
X316967Y545083D01*
X317550Y545000D01*
X318133Y545167D01*
X318717Y545667D01*
G01X324400Y550000D02*
Y545000D01*
G01Y545750D02*
X324067Y545333D01*
X323567Y545083D01*
X322983Y545000D01*
X322317Y545167D01*
X321817Y545583D01*
X321483Y546083D01*
X321400Y546667D01*
X321483Y547250D01*
X321817Y547750D01*
X322317Y548167D01*
X322983Y548333D01*
X323567Y548250D01*
X323983Y548083D01*
X324400Y547750D01*
G01X332433Y545000D02*
Y550000D01*
X334433D01*
X335100Y549750D01*
X335600Y549167D01*
X335767Y548500D01*
X335600Y547833D01*
X335183Y547333D01*
X334433Y547083D01*
X332433D01*
G01X339700Y550000D02*
Y545000D01*
G01X337783Y550000D02*
X341617D01*
G01X343550Y545000D02*
Y550000D01*
G01X347050D02*
Y545000D01*
G01Y547500D02*
X343550D01*
G01X356083Y543333D02*
X355250Y544167D01*
X354833Y545000D01*
Y548333D01*
X355250Y549167D01*
X356083Y550000D01*
G01X360350Y545000D02*
Y550000D01*
G01X363850D02*
Y545000D01*
G01Y547500D02*
X360350D01*
G01X367700Y545000D02*
X367200Y545083D01*
X366700Y545417D01*
X366367Y546000D01*
X366200Y546667D01*
X366367Y547333D01*
X366700Y547917D01*
X367200Y548250D01*
X367700Y548333D01*
X368200Y548250D01*
X368700Y547917D01*
X369033Y547333D01*
X369117Y546667D01*
X369033Y546000D01*
X368700Y545417D01*
X368200Y545083D01*
X367700Y545000D01*
G01X373300D02*
Y550000D01*
G01X377650Y547250D02*
X380317D01*
X380067Y547833D01*
X379650Y548167D01*
X379067Y548333D01*
X378483Y548250D01*
X377983Y548000D01*
X377650Y547417D01*
X377483Y546917D01*
Y546417D01*
X377650Y545917D01*
X378067Y545417D01*
X378567Y545083D01*
X379150Y545000D01*
X379733Y545167D01*
X380317Y545667D01*
G01X388350D02*
X389017Y545250D01*
X389767Y545000D01*
X390433D01*
X391100Y545250D01*
X391600Y545667D01*
X391850Y546250D01*
X391683Y546833D01*
X391267Y547333D01*
X390517Y547667D01*
X389517Y547833D01*
X388933Y548167D01*
X388683Y548750D01*
X388850Y549333D01*
X389267Y549750D01*
X389850Y550000D01*
X390433D01*
X391017Y549833D01*
X391517Y549417D01*
G01X395700Y548333D02*
Y545000D01*
G01Y549667D02*
X395533Y549750D01*
Y549917D01*
X395700Y550000D01*
X395867Y549917D01*
Y549750D01*
X395700Y549667D01*
G01X400050Y548333D02*
X402550D01*
X400050Y545000D01*
X402550D01*
G01X405650Y547250D02*
X408317D01*
X408067Y547833D01*
X407650Y548167D01*
X407067Y548333D01*
X406483Y548250D01*
X405983Y548000D01*
X405650Y547417D01*
X405483Y546917D01*
Y546417D01*
X405650Y545917D01*
X406067Y545417D01*
X406567Y545083D01*
X407150Y545000D01*
X407733Y545167D01*
X408317Y545667D01*
G01X414167Y545000D02*
X410833Y546667D01*
X414167Y548333D01*
G01X418100Y545000D02*
Y550000D01*
X417100Y549000D01*
G01Y545000D02*
X419100D01*
G01X422283Y545583D02*
X422867Y545167D01*
X423533Y545000D01*
X424200Y545167D01*
X424783Y545667D01*
X425200Y546417D01*
X425367Y547167D01*
Y548083D01*
X425200Y548833D01*
X424783Y549500D01*
X424283Y549833D01*
X423700Y550000D01*
X423033Y549833D01*
X422533Y549500D01*
X422200Y549000D01*
X422033Y548333D01*
X422200Y547750D01*
X422617Y547167D01*
X423117Y546833D01*
X423700Y546750D01*
X424367Y546917D01*
X424867Y547333D01*
X425367Y548083D01*
G01X429133Y545000D02*
X429300Y546083D01*
X429550Y547000D01*
X429883Y547833D01*
X430300Y548750D01*
X430967Y550000D01*
X427633D01*
G01X432400Y545000D02*
Y548333D01*
G01Y547417D02*
X432650Y547833D01*
X433067Y548167D01*
X433650Y548333D01*
X434233Y548167D01*
X434650Y547833D01*
X434900Y547417D01*
Y545000D01*
G01Y547417D02*
X435150Y547833D01*
X435567Y548167D01*
X436150Y548333D01*
X436733Y548167D01*
X437150Y547833D01*
X437400Y547333D01*
Y545000D01*
G01X440500Y548333D02*
Y545000D01*
G01Y549667D02*
X440333Y549750D01*
Y549917D01*
X440500Y550000D01*
X440667Y549917D01*
Y549750D01*
X440500Y549667D01*
G01X446100Y545000D02*
Y550000D01*
G01X455217Y548333D02*
X456217Y545000D01*
X457300Y548333D01*
X458383Y545000D01*
X459383Y548333D01*
G01X462900D02*
Y545000D01*
G01Y549667D02*
X462733Y549750D01*
Y549917D01*
X462900Y550000D01*
X463067Y549917D01*
Y549750D01*
X462900Y549667D01*
G01X468500Y550000D02*
Y545000D01*
G01X467333Y548333D02*
X469667D01*
G01X472683Y545000D02*
Y550000D01*
G01Y547583D02*
X473100Y548000D01*
X473517Y548250D01*
X474183Y548333D01*
X474683Y548250D01*
X475267Y547917D01*
X475517Y547417D01*
Y545000D01*
G01X483883D02*
Y548333D01*
G01Y547500D02*
X484217Y547917D01*
X484717Y548250D01*
X485383Y548333D01*
X485967Y548250D01*
X486467Y547917D01*
X486717Y547333D01*
Y545000D01*
G01X490900D02*
X490400Y545083D01*
X489900Y545417D01*
X489567Y546000D01*
X489400Y546667D01*
X489567Y547333D01*
X489900Y547917D01*
X490400Y548250D01*
X490900Y548333D01*
X491400Y548250D01*
X491900Y547917D01*
X492233Y547333D01*
X492317Y546667D01*
X492233Y546000D01*
X491900Y545417D01*
X491400Y545083D01*
X490900Y545000D01*
G01X495083D02*
Y548333D01*
G01Y547500D02*
X495417Y547917D01*
X495917Y548250D01*
X496583Y548333D01*
X497167Y548250D01*
X497667Y547917D01*
X497917Y547333D01*
Y545000D01*
G01X501017Y546667D02*
X503183D01*
G01X505950Y545000D02*
Y550000D01*
G01X509450D02*
Y545000D01*
G01Y547500D02*
X505950D01*
G01X511217Y545000D02*
X513300Y550000D01*
X515383Y545000D01*
G01X514633Y546750D02*
X511967D01*
G01X517150Y545667D02*
X517817Y545250D01*
X518567Y545000D01*
X519233D01*
X519900Y545250D01*
X520400Y545667D01*
X520650Y546250D01*
X520483Y546833D01*
X520067Y547333D01*
X519317Y547667D01*
X518317Y547833D01*
X517733Y548167D01*
X517483Y548750D01*
X517650Y549333D01*
X518067Y549750D01*
X518650Y550000D01*
X519233D01*
X519817Y549833D01*
X520317Y549417D01*
G01X522833Y550000D02*
Y545000D01*
X526167D01*
G01X534200Y543333D02*
Y548333D01*
G01Y547583D02*
X534617Y548000D01*
X535033Y548250D01*
X535700Y548333D01*
X536283Y548250D01*
X536867Y547833D01*
X537117Y547250D01*
X537200Y546667D01*
X537117Y546083D01*
X536867Y545500D01*
X536367Y545167D01*
X535700Y545000D01*
X535117Y545083D01*
X534533Y545333D01*
X534200Y545667D01*
G01X540133Y545000D02*
Y548333D01*
G01Y547667D02*
X540550Y548000D01*
X540967Y548250D01*
X541550Y548333D01*
X541967Y548250D01*
X542467Y548000D01*
G01X546900Y545000D02*
X546400Y545083D01*
X545900Y545417D01*
X545567Y546000D01*
X545400Y546667D01*
X545567Y547333D01*
X545900Y547917D01*
X546400Y548250D01*
X546900Y548333D01*
X547400Y548250D01*
X547900Y547917D01*
X548233Y547333D01*
X548317Y546667D01*
X548233Y546000D01*
X547900Y545417D01*
X547400Y545083D01*
X546900Y545000D01*
G01X554000Y550000D02*
Y545000D01*
G01Y545750D02*
X553667Y545333D01*
X553167Y545083D01*
X552583Y545000D01*
X551917Y545167D01*
X551417Y545583D01*
X551083Y546083D01*
X551000Y546667D01*
X551083Y547250D01*
X551417Y547750D01*
X551917Y548167D01*
X552583Y548333D01*
X553167Y548250D01*
X553583Y548083D01*
X554000Y547750D01*
G01X556683Y548333D02*
Y546000D01*
X557017Y545417D01*
X557517Y545083D01*
X558100Y545000D01*
X558683Y545083D01*
X559183Y545417D01*
X559517Y546000D01*
G01Y545000D02*
Y548333D01*
G01X565033Y547917D02*
X564450Y548250D01*
X563950Y548333D01*
X563283Y548167D01*
X562783Y547833D01*
X562450Y547250D01*
X562367Y546667D01*
X562450Y546083D01*
X562783Y545583D01*
X563283Y545167D01*
X563950Y545000D01*
X564533Y545167D01*
X565033Y545500D01*
G01X569300Y550000D02*
Y545000D01*
G01X568133Y548333D02*
X570467D01*
G01X573650Y545583D02*
X574067Y545250D01*
X574650Y545000D01*
X575150D01*
X575650Y545167D01*
X575983Y545417D01*
X576150Y545750D01*
X576067Y546250D01*
X575733Y546500D01*
X574233Y547000D01*
X573900Y547583D01*
X574067Y548000D01*
X574400Y548250D01*
X574900Y548333D01*
X575400Y548250D01*
X575900Y548000D01*
G01X580917Y543333D02*
X581750Y544167D01*
X582167Y545000D01*
Y548333D01*
X581750Y549167D01*
X580917Y550000D01*
G01X270833Y575000D02*
Y580000D01*
X272833D01*
X273500Y579750D01*
X274000Y579167D01*
X274167Y578500D01*
X274000Y577833D01*
X273583Y577333D01*
X272833Y577083D01*
X270833D01*
G01X278100Y575000D02*
Y580000D01*
G01X282283Y578333D02*
Y576000D01*
X282617Y575417D01*
X283117Y575083D01*
X283700Y575000D01*
X284283Y575083D01*
X284783Y575417D01*
X285117Y576000D01*
G01Y575000D02*
Y578333D01*
G01X288133Y573750D02*
X288717Y573417D01*
X289383Y573333D01*
X289967Y573417D01*
X290467Y573833D01*
X290800Y574417D01*
Y578333D01*
G01Y577667D02*
X290467Y578000D01*
X289967Y578250D01*
X289383Y578333D01*
X288717Y578167D01*
X288300Y577833D01*
X287967Y577250D01*
X287800Y576667D01*
X287883Y576167D01*
X288217Y575583D01*
X288717Y575167D01*
X289383Y575000D01*
X289883Y575083D01*
X290467Y575417D01*
X290800Y575750D01*
G01X293733Y573750D02*
X294317Y573417D01*
X294983Y573333D01*
X295567Y573417D01*
X296067Y573833D01*
X296400Y574417D01*
Y578333D01*
G01Y577667D02*
X296067Y578000D01*
X295567Y578250D01*
X294983Y578333D01*
X294317Y578167D01*
X293900Y577833D01*
X293567Y577250D01*
X293400Y576667D01*
X293483Y576167D01*
X293817Y575583D01*
X294317Y575167D01*
X294983Y575000D01*
X295483Y575083D01*
X296067Y575417D01*
X296400Y575750D01*
G01X299250Y577250D02*
X301917D01*
X301667Y577833D01*
X301250Y578167D01*
X300667Y578333D01*
X300083Y578250D01*
X299583Y578000D01*
X299250Y577417D01*
X299083Y576917D01*
Y576417D01*
X299250Y575917D01*
X299667Y575417D01*
X300167Y575083D01*
X300750Y575000D01*
X301333Y575167D01*
X301917Y575667D01*
G01X307600Y580000D02*
Y575000D01*
G01Y575750D02*
X307267Y575333D01*
X306767Y575083D01*
X306183Y575000D01*
X305517Y575167D01*
X305017Y575583D01*
X304683Y576083D01*
X304600Y576667D01*
X304683Y577250D01*
X305017Y577750D01*
X305517Y578167D01*
X306183Y578333D01*
X306767Y578250D01*
X307183Y578083D01*
X307600Y577750D01*
G01X315217Y580000D02*
X317300Y575000D01*
X319383Y580000D01*
G01X322900Y578333D02*
Y575000D01*
G01Y579667D02*
X322733Y579750D01*
Y579917D01*
X322900Y580000D01*
X323067Y579917D01*
Y579750D01*
X322900Y579667D01*
G01X330000Y575000D02*
Y578333D01*
G01Y577750D02*
X329667Y578083D01*
X329167Y578250D01*
X328583Y578333D01*
X328000Y578167D01*
X327500Y577833D01*
X327167Y577333D01*
X327000Y576667D01*
X327167Y576000D01*
X327500Y575500D01*
X328000Y575167D01*
X328583Y575000D01*
X329167Y575083D01*
X329667Y575333D01*
X330000Y575667D01*
G01X333683Y573333D02*
X332850Y574167D01*
X332433Y575000D01*
Y578333D01*
X332850Y579167D01*
X333683Y580000D01*
G01X338283Y575000D02*
Y580000D01*
G01Y577583D02*
X338700Y578000D01*
X339117Y578250D01*
X339783Y578333D01*
X340283Y578250D01*
X340867Y577917D01*
X341117Y577417D01*
Y575000D01*
G01X345300D02*
X344800Y575083D01*
X344300Y575417D01*
X343967Y576000D01*
X343800Y576667D01*
X343967Y577333D01*
X344300Y577917D01*
X344800Y578250D01*
X345300Y578333D01*
X345800Y578250D01*
X346300Y577917D01*
X346633Y577333D01*
X346717Y576667D01*
X346633Y576000D01*
X346300Y575417D01*
X345800Y575083D01*
X345300Y575000D01*
G01X350900D02*
Y580000D01*
G01X355250Y577250D02*
X357917D01*
X357667Y577833D01*
X357250Y578167D01*
X356667Y578333D01*
X356083Y578250D01*
X355583Y578000D01*
X355250Y577417D01*
X355083Y576917D01*
Y576417D01*
X355250Y575917D01*
X355667Y575417D01*
X356167Y575083D01*
X356750Y575000D01*
X357333Y575167D01*
X357917Y575667D01*
G01X366450Y575583D02*
X366867Y575250D01*
X367450Y575000D01*
X367950D01*
X368450Y575167D01*
X368783Y575417D01*
X368950Y575750D01*
X368867Y576250D01*
X368533Y576500D01*
X367033Y577000D01*
X366700Y577583D01*
X366867Y578000D01*
X367200Y578250D01*
X367700Y578333D01*
X368200Y578250D01*
X368700Y578000D01*
G01X373300Y578333D02*
Y575000D01*
G01Y579667D02*
X373133Y579750D01*
Y579917D01*
X373300Y580000D01*
X373467Y579917D01*
Y579750D01*
X373300Y579667D01*
G01X377650Y578333D02*
X380150D01*
X377650Y575000D01*
X380150D01*
G01X383250Y577250D02*
X385917D01*
X385667Y577833D01*
X385250Y578167D01*
X384667Y578333D01*
X384083Y578250D01*
X383583Y578000D01*
X383250Y577417D01*
X383083Y576917D01*
Y576417D01*
X383250Y575917D01*
X383667Y575417D01*
X384167Y575083D01*
X384750Y575000D01*
X385333Y575167D01*
X385917Y575667D01*
G01X391767Y575000D02*
X388433Y576667D01*
X391767Y578333D01*
G01X395700Y575000D02*
Y580000D01*
X394700Y579000D01*
G01Y575000D02*
X396700D01*
G01X399717Y577083D02*
X400300Y577667D01*
X400800Y578000D01*
X401467Y578167D01*
X402050Y578000D01*
X402467Y577667D01*
X402800Y577167D01*
X402883Y576583D01*
X402800Y576083D01*
X402467Y575583D01*
X401967Y575167D01*
X401383Y575000D01*
X400717Y575167D01*
X400133Y575667D01*
X399800Y576417D01*
X399717Y577250D01*
X399883Y578333D01*
X400133Y578917D01*
X400550Y579500D01*
X401133Y579917D01*
X401717Y580000D01*
X402300Y579833D01*
X402717Y579417D01*
G01X410000Y575000D02*
Y578333D01*
G01Y577417D02*
X410250Y577833D01*
X410667Y578167D01*
X411250Y578333D01*
X411833Y578167D01*
X412250Y577833D01*
X412500Y577417D01*
Y575000D01*
G01Y577417D02*
X412750Y577833D01*
X413167Y578167D01*
X413750Y578333D01*
X414333Y578167D01*
X414750Y577833D01*
X415000Y577333D01*
Y575000D01*
G01X418100Y578333D02*
Y575000D01*
G01Y579667D02*
X417933Y579750D01*
Y579917D01*
X418100Y580000D01*
X418267Y579917D01*
Y579750D01*
X418100Y579667D01*
G01X423700Y575000D02*
Y580000D01*
G01X429717Y573333D02*
X430550Y574167D01*
X430967Y575000D01*
Y578333D01*
X430550Y579167D01*
X429717Y580000D01*
G01X270833Y560000D02*
Y565000D01*
X272833D01*
X273500Y564750D01*
X274000Y564167D01*
X274167Y563500D01*
X274000Y562833D01*
X273583Y562333D01*
X272833Y562083D01*
X270833D01*
G01X278100Y560000D02*
Y565000D01*
G01X282283Y563333D02*
Y561000D01*
X282617Y560417D01*
X283117Y560083D01*
X283700Y560000D01*
X284283Y560083D01*
X284783Y560417D01*
X285117Y561000D01*
G01Y560000D02*
Y563333D01*
G01X288133Y558750D02*
X288717Y558417D01*
X289383Y558333D01*
X289967Y558417D01*
X290467Y558833D01*
X290800Y559417D01*
Y563333D01*
G01Y562667D02*
X290467Y563000D01*
X289967Y563250D01*
X289383Y563333D01*
X288717Y563167D01*
X288300Y562833D01*
X287967Y562250D01*
X287800Y561667D01*
X287883Y561167D01*
X288217Y560583D01*
X288717Y560167D01*
X289383Y560000D01*
X289883Y560083D01*
X290467Y560417D01*
X290800Y560750D01*
G01X293733Y558750D02*
X294317Y558417D01*
X294983Y558333D01*
X295567Y558417D01*
X296067Y558833D01*
X296400Y559417D01*
Y563333D01*
G01Y562667D02*
X296067Y563000D01*
X295567Y563250D01*
X294983Y563333D01*
X294317Y563167D01*
X293900Y562833D01*
X293567Y562250D01*
X293400Y561667D01*
X293483Y561167D01*
X293817Y560583D01*
X294317Y560167D01*
X294983Y560000D01*
X295483Y560083D01*
X296067Y560417D01*
X296400Y560750D01*
G01X299250Y562250D02*
X301917D01*
X301667Y562833D01*
X301250Y563167D01*
X300667Y563333D01*
X300083Y563250D01*
X299583Y563000D01*
X299250Y562417D01*
X299083Y561917D01*
Y561417D01*
X299250Y560917D01*
X299667Y560417D01*
X300167Y560083D01*
X300750Y560000D01*
X301333Y560167D01*
X301917Y560667D01*
G01X307600Y565000D02*
Y560000D01*
G01Y560750D02*
X307267Y560333D01*
X306767Y560083D01*
X306183Y560000D01*
X305517Y560167D01*
X305017Y560583D01*
X304683Y561083D01*
X304600Y561667D01*
X304683Y562250D01*
X305017Y562750D01*
X305517Y563167D01*
X306183Y563333D01*
X306767Y563250D01*
X307183Y563083D01*
X307600Y562750D01*
G01X315633Y560000D02*
Y565000D01*
X317633D01*
X318300Y564750D01*
X318800Y564167D01*
X318967Y563500D01*
X318800Y562833D01*
X318383Y562333D01*
X317633Y562083D01*
X315633D01*
G01X322900Y565000D02*
Y560000D01*
G01X320983Y565000D02*
X324817D01*
G01X326750Y560000D02*
Y565000D01*
G01X330250D02*
Y560000D01*
G01Y562500D02*
X326750D01*
G01X333683Y558333D02*
X332850Y559167D01*
X332433Y560000D01*
Y563333D01*
X332850Y564167D01*
X333683Y565000D01*
G01X338283Y560000D02*
Y565000D01*
G01Y562583D02*
X338700Y563000D01*
X339117Y563250D01*
X339783Y563333D01*
X340283Y563250D01*
X340867Y562917D01*
X341117Y562417D01*
Y560000D01*
G01X345300D02*
X344800Y560083D01*
X344300Y560417D01*
X343967Y561000D01*
X343800Y561667D01*
X343967Y562333D01*
X344300Y562917D01*
X344800Y563250D01*
X345300Y563333D01*
X345800Y563250D01*
X346300Y562917D01*
X346633Y562333D01*
X346717Y561667D01*
X346633Y561000D01*
X346300Y560417D01*
X345800Y560083D01*
X345300Y560000D01*
G01X350900D02*
Y565000D01*
G01X355250Y562250D02*
X357917D01*
X357667Y562833D01*
X357250Y563167D01*
X356667Y563333D01*
X356083Y563250D01*
X355583Y563000D01*
X355250Y562417D01*
X355083Y561917D01*
Y561417D01*
X355250Y560917D01*
X355667Y560417D01*
X356167Y560083D01*
X356750Y560000D01*
X357333Y560167D01*
X357917Y560667D01*
G01X366450Y560583D02*
X366867Y560250D01*
X367450Y560000D01*
X367950D01*
X368450Y560167D01*
X368783Y560417D01*
X368950Y560750D01*
X368867Y561250D01*
X368533Y561500D01*
X367033Y562000D01*
X366700Y562583D01*
X366867Y563000D01*
X367200Y563250D01*
X367700Y563333D01*
X368200Y563250D01*
X368700Y563000D01*
G01X373300Y563333D02*
Y560000D01*
G01Y564667D02*
X373133Y564750D01*
Y564917D01*
X373300Y565000D01*
X373467Y564917D01*
Y564750D01*
X373300Y564667D01*
G01X377650Y563333D02*
X380150D01*
X377650Y560000D01*
X380150D01*
G01X383250Y562250D02*
X385917D01*
X385667Y562833D01*
X385250Y563167D01*
X384667Y563333D01*
X384083Y563250D01*
X383583Y563000D01*
X383250Y562417D01*
X383083Y561917D01*
Y561417D01*
X383250Y560917D01*
X383667Y560417D01*
X384167Y560083D01*
X384750Y560000D01*
X385333Y560167D01*
X385917Y560667D01*
G01X388433Y560000D02*
X391767Y561667D01*
X388433Y563333D01*
G01X394617Y560917D02*
X396783D01*
G01Y562417D02*
X394617D01*
G01X401300Y560000D02*
Y565000D01*
X400300Y564000D01*
G01Y560000D02*
X402300D01*
G01X405317Y562083D02*
X405900Y562667D01*
X406400Y563000D01*
X407067Y563167D01*
X407650Y563000D01*
X408067Y562667D01*
X408400Y562167D01*
X408483Y561583D01*
X408400Y561083D01*
X408067Y560583D01*
X407567Y560167D01*
X406983Y560000D01*
X406317Y560167D01*
X405733Y560667D01*
X405400Y561417D01*
X405317Y562250D01*
X405483Y563333D01*
X405733Y563917D01*
X406150Y564500D01*
X406733Y564917D01*
X407317Y565000D01*
X407900Y564833D01*
X408317Y564417D01*
G01X415600Y560000D02*
Y563333D01*
G01Y562417D02*
X415850Y562833D01*
X416267Y563167D01*
X416850Y563333D01*
X417433Y563167D01*
X417850Y562833D01*
X418100Y562417D01*
Y560000D01*
G01Y562417D02*
X418350Y562833D01*
X418767Y563167D01*
X419350Y563333D01*
X419933Y563167D01*
X420350Y562833D01*
X420600Y562333D01*
Y560000D01*
G01X423700Y563333D02*
Y560000D01*
G01Y564667D02*
X423533Y564750D01*
Y564917D01*
X423700Y565000D01*
X423867Y564917D01*
Y564750D01*
X423700Y564667D01*
G01X429300Y560000D02*
Y565000D01*
G01X435317Y558333D02*
X436150Y559167D01*
X436567Y560000D01*
Y563333D01*
X436150Y564167D01*
X435317Y565000D01*
G01X273000Y609000D02*
Y604000D01*
G01X271083Y609000D02*
X274917D01*
G01X277183Y604000D02*
Y609000D01*
G01Y606583D02*
X277600Y607000D01*
X278017Y607250D01*
X278683Y607333D01*
X279183Y607250D01*
X279767Y606917D01*
X280017Y606417D01*
Y604000D01*
G01X282950Y606250D02*
X285617D01*
X285367Y606833D01*
X284950Y607167D01*
X284367Y607333D01*
X283783Y607250D01*
X283283Y607000D01*
X282950Y606417D01*
X282783Y605917D01*
Y605417D01*
X282950Y604917D01*
X283367Y604417D01*
X283867Y604083D01*
X284450Y604000D01*
X285033Y604167D01*
X285617Y604667D01*
G01X288633Y604000D02*
Y607333D01*
G01Y606667D02*
X289050Y607000D01*
X289467Y607250D01*
X290050Y607333D01*
X290467Y607250D01*
X290967Y607000D01*
G01X292900Y604000D02*
Y607333D01*
G01Y606417D02*
X293150Y606833D01*
X293567Y607167D01*
X294150Y607333D01*
X294733Y607167D01*
X295150Y606833D01*
X295400Y606417D01*
Y604000D01*
G01Y606417D02*
X295650Y606833D01*
X296067Y607167D01*
X296650Y607333D01*
X297233Y607167D01*
X297650Y606833D01*
X297900Y606333D01*
Y604000D01*
G01X302500D02*
Y607333D01*
G01Y606750D02*
X302167Y607083D01*
X301667Y607250D01*
X301083Y607333D01*
X300500Y607167D01*
X300000Y606833D01*
X299667Y606333D01*
X299500Y605667D01*
X299667Y605000D01*
X300000Y604500D01*
X300500Y604167D01*
X301083Y604000D01*
X301667Y604083D01*
X302167Y604333D01*
X302500Y604667D01*
G01X306600Y604000D02*
Y609000D01*
G01X316300Y602333D02*
Y607333D01*
G01Y606583D02*
X316717Y607000D01*
X317133Y607250D01*
X317800Y607333D01*
X318383Y607250D01*
X318967Y606833D01*
X319217Y606250D01*
X319300Y605667D01*
X319217Y605083D01*
X318967Y604500D01*
X318467Y604167D01*
X317800Y604000D01*
X317217Y604083D01*
X316633Y604333D01*
X316300Y604667D01*
G01X324900Y604000D02*
Y607333D01*
G01Y606750D02*
X324567Y607083D01*
X324067Y607250D01*
X323483Y607333D01*
X322900Y607167D01*
X322400Y606833D01*
X322067Y606333D01*
X321900Y605667D01*
X322067Y605000D01*
X322400Y604500D01*
X322900Y604167D01*
X323483Y604000D01*
X324067Y604083D01*
X324567Y604333D01*
X324900Y604667D01*
G01X330500Y609000D02*
Y604000D01*
G01Y604750D02*
X330167Y604333D01*
X329667Y604083D01*
X329083Y604000D01*
X328417Y604167D01*
X327917Y604583D01*
X327583Y605083D01*
X327500Y605667D01*
X327583Y606250D01*
X327917Y606750D01*
X328417Y607167D01*
X329083Y607333D01*
X329667Y607250D01*
X330083Y607083D01*
X330500Y606750D01*
G01X341533Y606917D02*
X340950Y607250D01*
X340450Y607333D01*
X339783Y607167D01*
X339283Y606833D01*
X338950Y606250D01*
X338867Y605667D01*
X338950Y605083D01*
X339283Y604583D01*
X339783Y604167D01*
X340450Y604000D01*
X341033Y604167D01*
X341533Y604500D01*
G01X347300Y604000D02*
Y607333D01*
G01Y606750D02*
X346967Y607083D01*
X346467Y607250D01*
X345883Y607333D01*
X345300Y607167D01*
X344800Y606833D01*
X344467Y606333D01*
X344300Y605667D01*
X344467Y605000D01*
X344800Y604500D01*
X345300Y604167D01*
X345883Y604000D01*
X346467Y604083D01*
X346967Y604333D01*
X347300Y604667D01*
G01X349983Y604000D02*
Y607333D01*
G01Y606500D02*
X350317Y606917D01*
X350817Y607250D01*
X351483Y607333D01*
X352067Y607250D01*
X352567Y606917D01*
X352817Y606333D01*
Y604000D01*
G01X363933Y606917D02*
X363350Y607250D01*
X362850Y607333D01*
X362183Y607167D01*
X361683Y606833D01*
X361350Y606250D01*
X361267Y605667D01*
X361350Y605083D01*
X361683Y604583D01*
X362183Y604167D01*
X362850Y604000D01*
X363433Y604167D01*
X363933Y604500D01*
G01X366783Y604000D02*
Y609000D01*
G01Y606583D02*
X367200Y607000D01*
X367617Y607250D01*
X368283Y607333D01*
X368783Y607250D01*
X369367Y606917D01*
X369617Y606417D01*
Y604000D01*
G01X375300D02*
Y607333D01*
G01Y606750D02*
X374967Y607083D01*
X374467Y607250D01*
X373883Y607333D01*
X373300Y607167D01*
X372800Y606833D01*
X372467Y606333D01*
X372300Y605667D01*
X372467Y605000D01*
X372800Y604500D01*
X373300Y604167D01*
X373883Y604000D01*
X374467Y604083D01*
X374967Y604333D01*
X375300Y604667D01*
G01X377983Y604000D02*
Y607333D01*
G01Y606500D02*
X378317Y606917D01*
X378817Y607250D01*
X379483Y607333D01*
X380067Y607250D01*
X380567Y606917D01*
X380817Y606333D01*
Y604000D01*
G01X383833Y602750D02*
X384417Y602417D01*
X385083Y602333D01*
X385667Y602417D01*
X386167Y602833D01*
X386500Y603417D01*
Y607333D01*
G01Y606667D02*
X386167Y607000D01*
X385667Y607250D01*
X385083Y607333D01*
X384417Y607167D01*
X384000Y606833D01*
X383667Y606250D01*
X383500Y605667D01*
X383583Y605167D01*
X383917Y604583D01*
X384417Y604167D01*
X385083Y604000D01*
X385583Y604083D01*
X386167Y604417D01*
X386500Y604750D01*
G01X389350Y606250D02*
X392017D01*
X391767Y606833D01*
X391350Y607167D01*
X390767Y607333D01*
X390183Y607250D01*
X389683Y607000D01*
X389350Y606417D01*
X389183Y605917D01*
Y605417D01*
X389350Y604917D01*
X389767Y604417D01*
X390267Y604083D01*
X390850Y604000D01*
X391433Y604167D01*
X392017Y604667D01*
G01X401800Y607333D02*
Y604000D01*
G01Y608667D02*
X401633Y608750D01*
Y608917D01*
X401800Y609000D01*
X401967Y608917D01*
Y608750D01*
X401800Y608667D01*
G01X405983Y604000D02*
Y607333D01*
G01Y606500D02*
X406317Y606917D01*
X406817Y607250D01*
X407483Y607333D01*
X408067Y607250D01*
X408567Y606917D01*
X408817Y606333D01*
Y604000D01*
G01X413000Y609000D02*
Y604000D01*
G01X411833Y607333D02*
X414167D01*
G01X418600Y604000D02*
X418100Y604083D01*
X417600Y604417D01*
X417267Y605000D01*
X417100Y605667D01*
X417267Y606333D01*
X417600Y606917D01*
X418100Y607250D01*
X418600Y607333D01*
X419100Y607250D01*
X419600Y606917D01*
X419933Y606333D01*
X420017Y605667D01*
X419933Y605000D01*
X419600Y604417D01*
X419100Y604083D01*
X418600Y604000D01*
G01X429300D02*
Y608250D01*
X429467Y608667D01*
X429800Y608917D01*
X430300Y609000D01*
X430800Y608833D01*
X431050Y608417D01*
G01X430050Y607000D02*
X428383D01*
G01X433983Y607333D02*
Y605000D01*
X434317Y604417D01*
X434817Y604083D01*
X435400Y604000D01*
X435983Y604083D01*
X436483Y604417D01*
X436817Y605000D01*
G01Y604000D02*
Y607333D01*
G01X441000Y604000D02*
Y609000D01*
G01X446600Y604000D02*
Y609000D01*
G01X459133Y606917D02*
X458550Y607250D01*
X458050Y607333D01*
X457383Y607167D01*
X456883Y606833D01*
X456550Y606250D01*
X456467Y605667D01*
X456550Y605083D01*
X456883Y604583D01*
X457383Y604167D01*
X458050Y604000D01*
X458633Y604167D01*
X459133Y604500D01*
G01X463400Y604000D02*
X462900Y604083D01*
X462400Y604417D01*
X462067Y605000D01*
X461900Y605667D01*
X462067Y606333D01*
X462400Y606917D01*
X462900Y607250D01*
X463400Y607333D01*
X463900Y607250D01*
X464400Y606917D01*
X464733Y606333D01*
X464817Y605667D01*
X464733Y605000D01*
X464400Y604417D01*
X463900Y604083D01*
X463400Y604000D01*
G01X467583D02*
Y607333D01*
G01Y606500D02*
X467917Y606917D01*
X468417Y607250D01*
X469083Y607333D01*
X469667Y607250D01*
X470167Y606917D01*
X470417Y606333D01*
Y604000D01*
G01X474600Y609000D02*
Y604000D01*
G01X473433Y607333D02*
X475767D01*
G01X481700Y604000D02*
Y607333D01*
G01Y606750D02*
X481367Y607083D01*
X480867Y607250D01*
X480283Y607333D01*
X479700Y607167D01*
X479200Y606833D01*
X478867Y606333D01*
X478700Y605667D01*
X478867Y605000D01*
X479200Y604500D01*
X479700Y604167D01*
X480283Y604000D01*
X480867Y604083D01*
X481367Y604333D01*
X481700Y604667D01*
G01X487133Y606917D02*
X486550Y607250D01*
X486050Y607333D01*
X485383Y607167D01*
X484883Y606833D01*
X484550Y606250D01*
X484467Y605667D01*
X484550Y605083D01*
X484883Y604583D01*
X485383Y604167D01*
X486050Y604000D01*
X486633Y604167D01*
X487133Y604500D01*
G01X491400Y609000D02*
Y604000D01*
G01X490233Y607333D02*
X492567D01*
G01X270417Y588500D02*
X272500Y593500D01*
X274583Y588500D01*
G01X273833Y590250D02*
X271167D01*
G01X276683Y588500D02*
Y591833D01*
G01Y591000D02*
X277017Y591417D01*
X277517Y591750D01*
X278183Y591833D01*
X278767Y591750D01*
X279267Y591417D01*
X279517Y590833D01*
Y588500D01*
G01X281950Y587000D02*
X282450Y586833D01*
X283117Y587000D01*
X283533Y587333D01*
X283867Y587750D01*
X284367Y589083D01*
X285450Y591833D01*
G01X282783D02*
X284367Y589083D01*
G01X293483Y588500D02*
Y593500D01*
G01Y591083D02*
X293900Y591500D01*
X294317Y591750D01*
X294983Y591833D01*
X295483Y591750D01*
X296067Y591417D01*
X296317Y590917D01*
Y588500D01*
G01X300500D02*
X300000Y588583D01*
X299500Y588917D01*
X299167Y589500D01*
X299000Y590167D01*
X299167Y590833D01*
X299500Y591417D01*
X300000Y591750D01*
X300500Y591833D01*
X301000Y591750D01*
X301500Y591417D01*
X301833Y590833D01*
X301917Y590167D01*
X301833Y589500D01*
X301500Y588917D01*
X301000Y588583D01*
X300500Y588500D01*
G01X306100D02*
Y593500D01*
G01X310450Y590750D02*
X313117D01*
X312867Y591333D01*
X312450Y591667D01*
X311867Y591833D01*
X311283Y591750D01*
X310783Y591500D01*
X310450Y590917D01*
X310283Y590417D01*
Y589917D01*
X310450Y589417D01*
X310867Y588917D01*
X311367Y588583D01*
X311950Y588500D01*
X312533Y588667D01*
X313117Y589167D01*
G01X322900Y593500D02*
Y588500D01*
G01X321733Y591833D02*
X324067D01*
G01X328500Y588500D02*
X328000Y588583D01*
X327500Y588917D01*
X327167Y589500D01*
X327000Y590167D01*
X327167Y590833D01*
X327500Y591417D01*
X328000Y591750D01*
X328500Y591833D01*
X329000Y591750D01*
X329500Y591417D01*
X329833Y590833D01*
X329917Y590167D01*
X329833Y589500D01*
X329500Y588917D01*
X329000Y588583D01*
X328500Y588500D01*
G01X338283D02*
Y593500D01*
G01Y591083D02*
X338700Y591500D01*
X339117Y591750D01*
X339783Y591833D01*
X340283Y591750D01*
X340867Y591417D01*
X341117Y590917D01*
Y588500D01*
G01X345300D02*
X344800Y588583D01*
X344300Y588917D01*
X343967Y589500D01*
X343800Y590167D01*
X343967Y590833D01*
X344300Y591417D01*
X344800Y591750D01*
X345300Y591833D01*
X345800Y591750D01*
X346300Y591417D01*
X346633Y590833D01*
X346717Y590167D01*
X346633Y589500D01*
X346300Y588917D01*
X345800Y588583D01*
X345300Y588500D01*
G01X350900D02*
Y593500D01*
G01X355250Y590750D02*
X357917D01*
X357667Y591333D01*
X357250Y591667D01*
X356667Y591833D01*
X356083Y591750D01*
X355583Y591500D01*
X355250Y590917D01*
X355083Y590417D01*
Y589917D01*
X355250Y589417D01*
X355667Y588917D01*
X356167Y588583D01*
X356750Y588500D01*
X357333Y588667D01*
X357917Y589167D01*
G01X270917Y619000D02*
X273000Y624000D01*
X275083Y619000D01*
G01X274333Y620750D02*
X271667D01*
G01X277183Y619000D02*
Y622333D01*
G01Y621500D02*
X277517Y621917D01*
X278017Y622250D01*
X278683Y622333D01*
X279267Y622250D01*
X279767Y621917D01*
X280017Y621333D01*
Y619000D01*
G01X284200Y624000D02*
Y619000D01*
G01X283033Y622333D02*
X285367D01*
G01X289800D02*
Y619000D01*
G01Y623667D02*
X289633Y623750D01*
Y623917D01*
X289800Y624000D01*
X289967Y623917D01*
Y623750D01*
X289800Y623667D01*
G01X294317Y620667D02*
X296483D01*
G01X299500Y617333D02*
Y622333D01*
G01Y621583D02*
X299917Y622000D01*
X300333Y622250D01*
X301000Y622333D01*
X301583Y622250D01*
X302167Y621833D01*
X302417Y621250D01*
X302500Y620667D01*
X302417Y620083D01*
X302167Y619500D01*
X301667Y619167D01*
X301000Y619000D01*
X300417Y619083D01*
X299833Y619333D01*
X299500Y619667D01*
G01X308100Y619000D02*
Y622333D01*
G01Y621750D02*
X307767Y622083D01*
X307267Y622250D01*
X306683Y622333D01*
X306100Y622167D01*
X305600Y621833D01*
X305267Y621333D01*
X305100Y620667D01*
X305267Y620000D01*
X305600Y619500D01*
X306100Y619167D01*
X306683Y619000D01*
X307267Y619083D01*
X307767Y619333D01*
X308100Y619667D01*
G01X313700Y624000D02*
Y619000D01*
G01Y619750D02*
X313367Y619333D01*
X312867Y619083D01*
X312283Y619000D01*
X311617Y619167D01*
X311117Y619583D01*
X310783Y620083D01*
X310700Y620667D01*
X310783Y621250D01*
X311117Y621750D01*
X311617Y622167D01*
X312283Y622333D01*
X312867Y622250D01*
X313283Y622083D01*
X313700Y621750D01*
G01X322150Y619583D02*
X322567Y619250D01*
X323150Y619000D01*
X323650D01*
X324150Y619167D01*
X324483Y619417D01*
X324650Y619750D01*
X324567Y620250D01*
X324233Y620500D01*
X322733Y621000D01*
X322400Y621583D01*
X322567Y622000D01*
X322900Y622250D01*
X323400Y622333D01*
X323900Y622250D01*
X324400Y622000D01*
G01X329000Y622333D02*
Y619000D01*
G01Y623667D02*
X328833Y623750D01*
Y623917D01*
X329000Y624000D01*
X329167Y623917D01*
Y623750D01*
X329000Y623667D01*
G01X333350Y622333D02*
X335850D01*
X333350Y619000D01*
X335850D01*
G01X338950Y621250D02*
X341617D01*
X341367Y621833D01*
X340950Y622167D01*
X340367Y622333D01*
X339783Y622250D01*
X339283Y622000D01*
X338950Y621417D01*
X338783Y620917D01*
Y620417D01*
X338950Y619917D01*
X339367Y619417D01*
X339867Y619083D01*
X340450Y619000D01*
X341033Y619167D01*
X341617Y619667D01*
G01X269717Y637573D02*
X270717Y634240D01*
X271800Y637573D01*
X272883Y634240D01*
X273883Y637573D01*
G01X277400D02*
Y634240D01*
G01Y638907D02*
X277233Y638990D01*
Y639157D01*
X277400Y639240D01*
X277567Y639157D01*
Y638990D01*
X277400Y638907D01*
G01X283000Y639240D02*
Y634240D01*
G01X281833Y637573D02*
X284167D01*
G01X287183Y634240D02*
Y639240D01*
G01Y636823D02*
X287600Y637240D01*
X288017Y637490D01*
X288683Y637573D01*
X289183Y637490D01*
X289767Y637157D01*
X290017Y636657D01*
Y634240D01*
G01X294200D02*
X293700Y634323D01*
X293200Y634657D01*
X292867Y635240D01*
X292700Y635907D01*
X292867Y636573D01*
X293200Y637157D01*
X293700Y637490D01*
X294200Y637573D01*
X294700Y637490D01*
X295200Y637157D01*
X295533Y636573D01*
X295617Y635907D01*
X295533Y635240D01*
X295200Y634657D01*
X294700Y634323D01*
X294200Y634240D01*
G01X298383Y637573D02*
Y635240D01*
X298717Y634657D01*
X299217Y634323D01*
X299800Y634240D01*
X300383Y634323D01*
X300883Y634657D01*
X301217Y635240D01*
G01Y634240D02*
Y637573D01*
G01X305400Y639240D02*
Y634240D01*
G01X304233Y637573D02*
X306567D01*
G01X317933Y637157D02*
X317350Y637490D01*
X316850Y637573D01*
X316183Y637407D01*
X315683Y637073D01*
X315350Y636490D01*
X315267Y635907D01*
X315350Y635323D01*
X315683Y634823D01*
X316183Y634407D01*
X316850Y634240D01*
X317433Y634407D01*
X317933Y634740D01*
G01X322200Y634240D02*
X321700Y634323D01*
X321200Y634657D01*
X320867Y635240D01*
X320700Y635907D01*
X320867Y636573D01*
X321200Y637157D01*
X321700Y637490D01*
X322200Y637573D01*
X322700Y637490D01*
X323200Y637157D01*
X323533Y636573D01*
X323617Y635907D01*
X323533Y635240D01*
X323200Y634657D01*
X322700Y634323D01*
X322200Y634240D01*
G01X326383D02*
Y637573D01*
G01Y636740D02*
X326717Y637157D01*
X327217Y637490D01*
X327883Y637573D01*
X328467Y637490D01*
X328967Y637157D01*
X329217Y636573D01*
Y634240D01*
G01X331983D02*
Y637573D01*
G01Y636740D02*
X332317Y637157D01*
X332817Y637490D01*
X333483Y637573D01*
X334067Y637490D01*
X334567Y637157D01*
X334817Y636573D01*
Y634240D01*
G01X337750Y636490D02*
X340417D01*
X340167Y637073D01*
X339750Y637407D01*
X339167Y637573D01*
X338583Y637490D01*
X338083Y637240D01*
X337750Y636657D01*
X337583Y636157D01*
Y635657D01*
X337750Y635157D01*
X338167Y634657D01*
X338667Y634323D01*
X339250Y634240D01*
X339833Y634407D01*
X340417Y634907D01*
G01X345933Y637157D02*
X345350Y637490D01*
X344850Y637573D01*
X344183Y637407D01*
X343683Y637073D01*
X343350Y636490D01*
X343267Y635907D01*
X343350Y635323D01*
X343683Y634823D01*
X344183Y634407D01*
X344850Y634240D01*
X345433Y634407D01*
X345933Y634740D01*
G01X350200Y639240D02*
Y634240D01*
G01X349033Y637573D02*
X351367D01*
G01X355800D02*
Y634240D01*
G01Y638907D02*
X355633Y638990D01*
Y639157D01*
X355800Y639240D01*
X355967Y639157D01*
Y638990D01*
X355800Y638907D01*
G01X359983Y634240D02*
Y637573D01*
G01Y636740D02*
X360317Y637157D01*
X360817Y637490D01*
X361483Y637573D01*
X362067Y637490D01*
X362567Y637157D01*
X362817Y636573D01*
Y634240D01*
G01X365833Y632990D02*
X366417Y632657D01*
X367083Y632573D01*
X367667Y632657D01*
X368167Y633073D01*
X368500Y633657D01*
Y637573D01*
G01Y636907D02*
X368167Y637240D01*
X367667Y637490D01*
X367083Y637573D01*
X366417Y637407D01*
X366000Y637073D01*
X365667Y636490D01*
X365500Y635907D01*
X365583Y635407D01*
X365917Y634823D01*
X366417Y634407D01*
X367083Y634240D01*
X367583Y634323D01*
X368167Y634657D01*
X368500Y634990D01*
G01X378200Y639240D02*
Y634240D01*
G01X377033Y637573D02*
X379367D01*
G01X383800Y634240D02*
X383300Y634323D01*
X382800Y634657D01*
X382467Y635240D01*
X382300Y635907D01*
X382467Y636573D01*
X382800Y637157D01*
X383300Y637490D01*
X383800Y637573D01*
X384300Y637490D01*
X384800Y637157D01*
X385133Y636573D01*
X385217Y635907D01*
X385133Y635240D01*
X384800Y634657D01*
X384300Y634323D01*
X383800Y634240D01*
G01X395000D02*
X394500Y634323D01*
X394000Y634657D01*
X393667Y635240D01*
X393500Y635907D01*
X393667Y636573D01*
X394000Y637157D01*
X394500Y637490D01*
X395000Y637573D01*
X395500Y637490D01*
X396000Y637157D01*
X396333Y636573D01*
X396417Y635907D01*
X396333Y635240D01*
X396000Y634657D01*
X395500Y634323D01*
X395000Y634240D01*
G01X400600Y639240D02*
Y634240D01*
G01X399433Y637573D02*
X401767D01*
G01X404783Y634240D02*
Y639240D01*
G01Y636823D02*
X405200Y637240D01*
X405617Y637490D01*
X406283Y637573D01*
X406783Y637490D01*
X407367Y637157D01*
X407617Y636657D01*
Y634240D01*
G01X410550Y636490D02*
X413217D01*
X412967Y637073D01*
X412550Y637407D01*
X411967Y637573D01*
X411383Y637490D01*
X410883Y637240D01*
X410550Y636657D01*
X410383Y636157D01*
Y635657D01*
X410550Y635157D01*
X410967Y634657D01*
X411467Y634323D01*
X412050Y634240D01*
X412633Y634407D01*
X413217Y634907D01*
G01X416233Y634240D02*
Y637573D01*
G01Y636907D02*
X416650Y637240D01*
X417067Y637490D01*
X417650Y637573D01*
X418067Y637490D01*
X418567Y637240D01*
G01X428600Y634240D02*
Y639240D01*
G01X435700Y634240D02*
Y637573D01*
G01Y636990D02*
X435367Y637323D01*
X434867Y637490D01*
X434283Y637573D01*
X433700Y637407D01*
X433200Y637073D01*
X432867Y636573D01*
X432700Y635907D01*
X432867Y635240D01*
X433200Y634740D01*
X433700Y634407D01*
X434283Y634240D01*
X434867Y634323D01*
X435367Y634573D01*
X435700Y634907D01*
G01X438050Y632740D02*
X438550Y632573D01*
X439217Y632740D01*
X439633Y633073D01*
X439967Y633490D01*
X440467Y634823D01*
X441550Y637573D01*
G01X438883D02*
X440467Y634823D01*
G01X444150Y636490D02*
X446817D01*
X446567Y637073D01*
X446150Y637407D01*
X445567Y637573D01*
X444983Y637490D01*
X444483Y637240D01*
X444150Y636657D01*
X443983Y636157D01*
Y635657D01*
X444150Y635157D01*
X444567Y634657D01*
X445067Y634323D01*
X445650Y634240D01*
X446233Y634407D01*
X446817Y634907D01*
G01X449833Y634240D02*
Y637573D01*
G01Y636907D02*
X450250Y637240D01*
X450667Y637490D01*
X451250Y637573D01*
X451667Y637490D01*
X452167Y637240D01*
G01X455350Y634823D02*
X455767Y634490D01*
X456350Y634240D01*
X456850D01*
X457350Y634407D01*
X457683Y634657D01*
X457850Y634990D01*
X457767Y635490D01*
X457433Y635740D01*
X455933Y636240D01*
X455600Y636823D01*
X455767Y637240D01*
X456100Y637490D01*
X456600Y637573D01*
X457100Y637490D01*
X457600Y637240D01*
G01X462617Y632573D02*
X463450Y633407D01*
X463867Y634240D01*
Y637573D01*
X463450Y638407D01*
X462617Y639240D01*
G01X270257Y644950D02*
Y649950D01*
X271923D01*
X272590Y649700D01*
X273090Y649367D01*
X273507Y648867D01*
X273840Y648283D01*
X273923Y647450D01*
X273840Y646617D01*
X273507Y646033D01*
X273090Y645533D01*
X272590Y645200D01*
X271923Y644950D01*
X270257D01*
G01X276440Y647200D02*
X279107D01*
X278857Y647783D01*
X278440Y648117D01*
X277857Y648283D01*
X277273Y648200D01*
X276773Y647950D01*
X276440Y647367D01*
X276273Y646867D01*
Y646367D01*
X276440Y645867D01*
X276857Y645367D01*
X277357Y645033D01*
X277940Y644950D01*
X278523Y645117D01*
X279107Y645617D01*
G01X283290Y644950D02*
Y649950D01*
G01X287640Y647200D02*
X290307D01*
X290057Y647783D01*
X289640Y648117D01*
X289057Y648283D01*
X288473Y648200D01*
X287973Y647950D01*
X287640Y647367D01*
X287473Y646867D01*
Y646367D01*
X287640Y645867D01*
X288057Y645367D01*
X288557Y645033D01*
X289140Y644950D01*
X289723Y645117D01*
X290307Y645617D01*
G01X294490Y649950D02*
Y644950D01*
G01X293323Y648283D02*
X295657D01*
G01X298840Y647200D02*
X301507D01*
X301257Y647783D01*
X300840Y648117D01*
X300257Y648283D01*
X299673Y648200D01*
X299173Y647950D01*
X298840Y647367D01*
X298673Y646867D01*
Y646367D01*
X298840Y645867D01*
X299257Y645367D01*
X299757Y645033D01*
X300340Y644950D01*
X300923Y645117D01*
X301507Y645617D01*
G01X309873Y644950D02*
Y648283D01*
G01Y647450D02*
X310207Y647867D01*
X310707Y648200D01*
X311373Y648283D01*
X311957Y648200D01*
X312457Y647867D01*
X312707Y647283D01*
Y644950D01*
G01X316890D02*
X316390Y645033D01*
X315890Y645367D01*
X315557Y645950D01*
X315390Y646617D01*
X315557Y647283D01*
X315890Y647867D01*
X316390Y648200D01*
X316890Y648283D01*
X317390Y648200D01*
X317890Y647867D01*
X318223Y647283D01*
X318307Y646617D01*
X318223Y645950D01*
X317890Y645367D01*
X317390Y645033D01*
X316890Y644950D01*
G01X321073D02*
Y648283D01*
G01Y647450D02*
X321407Y647867D01*
X321907Y648200D01*
X322573Y648283D01*
X323157Y648200D01*
X323657Y647867D01*
X323907Y647283D01*
Y644950D01*
G01X327007Y646617D02*
X329173D01*
G01X333190Y644950D02*
Y649200D01*
X333357Y649617D01*
X333690Y649867D01*
X334190Y649950D01*
X334690Y649783D01*
X334940Y649367D01*
G01X333940Y647950D02*
X332273D01*
G01X337873Y648283D02*
Y645950D01*
X338207Y645367D01*
X338707Y645033D01*
X339290Y644950D01*
X339873Y645033D01*
X340373Y645367D01*
X340707Y645950D01*
G01Y644950D02*
Y648283D01*
G01X343473Y644950D02*
Y648283D01*
G01Y647450D02*
X343807Y647867D01*
X344307Y648200D01*
X344973Y648283D01*
X345557Y648200D01*
X346057Y647867D01*
X346307Y647283D01*
Y644950D01*
G01X351823Y647867D02*
X351240Y648200D01*
X350740Y648283D01*
X350073Y648117D01*
X349573Y647783D01*
X349240Y647200D01*
X349157Y646617D01*
X349240Y646033D01*
X349573Y645533D01*
X350073Y645117D01*
X350740Y644950D01*
X351323Y645117D01*
X351823Y645450D01*
G01X356090Y649950D02*
Y644950D01*
G01X354923Y648283D02*
X357257D01*
G01X361690D02*
Y644950D01*
G01Y649617D02*
X361523Y649700D01*
Y649867D01*
X361690Y649950D01*
X361857Y649867D01*
Y649700D01*
X361690Y649617D01*
G01X367290Y644950D02*
X366790Y645033D01*
X366290Y645367D01*
X365957Y645950D01*
X365790Y646617D01*
X365957Y647283D01*
X366290Y647867D01*
X366790Y648200D01*
X367290Y648283D01*
X367790Y648200D01*
X368290Y647867D01*
X368623Y647283D01*
X368707Y646617D01*
X368623Y645950D01*
X368290Y645367D01*
X367790Y645033D01*
X367290Y644950D01*
G01X371473D02*
Y648283D01*
G01Y647450D02*
X371807Y647867D01*
X372307Y648200D01*
X372973Y648283D01*
X373557Y648200D01*
X374057Y647867D01*
X374307Y647283D01*
Y644950D01*
G01X379990D02*
Y648283D01*
G01Y647700D02*
X379657Y648033D01*
X379157Y648200D01*
X378573Y648283D01*
X377990Y648117D01*
X377490Y647783D01*
X377157Y647283D01*
X376990Y646617D01*
X377157Y645950D01*
X377490Y645450D01*
X377990Y645117D01*
X378573Y644950D01*
X379157Y645033D01*
X379657Y645283D01*
X379990Y645617D01*
G01X384090Y644950D02*
Y649950D01*
G01X393790Y643283D02*
Y648283D01*
G01Y647533D02*
X394207Y647950D01*
X394623Y648200D01*
X395290Y648283D01*
X395873Y648200D01*
X396457Y647783D01*
X396707Y647200D01*
X396790Y646617D01*
X396707Y646033D01*
X396457Y645450D01*
X395957Y645117D01*
X395290Y644950D01*
X394707Y645033D01*
X394123Y645283D01*
X393790Y645617D01*
G01X402390Y644950D02*
Y648283D01*
G01Y647700D02*
X402057Y648033D01*
X401557Y648200D01*
X400973Y648283D01*
X400390Y648117D01*
X399890Y647783D01*
X399557Y647283D01*
X399390Y646617D01*
X399557Y645950D01*
X399890Y645450D01*
X400390Y645117D01*
X400973Y644950D01*
X401557Y645033D01*
X402057Y645283D01*
X402390Y645617D01*
G01X407990Y649950D02*
Y644950D01*
G01Y645700D02*
X407657Y645283D01*
X407157Y645033D01*
X406573Y644950D01*
X405907Y645117D01*
X405407Y645533D01*
X405073Y646033D01*
X404990Y646617D01*
X405073Y647200D01*
X405407Y647700D01*
X405907Y648117D01*
X406573Y648283D01*
X407157Y648200D01*
X407573Y648033D01*
X407990Y647700D01*
G01X417690Y648283D02*
Y644950D01*
G01Y649617D02*
X417523Y649700D01*
Y649867D01*
X417690Y649950D01*
X417857Y649867D01*
Y649700D01*
X417690Y649617D01*
G01X421873Y644950D02*
Y648283D01*
G01Y647450D02*
X422207Y647867D01*
X422707Y648200D01*
X423373Y648283D01*
X423957Y648200D01*
X424457Y647867D01*
X424707Y647283D01*
Y644950D01*
G01X435990D02*
Y648283D01*
G01Y647700D02*
X435657Y648033D01*
X435157Y648200D01*
X434573Y648283D01*
X433990Y648117D01*
X433490Y647783D01*
X433157Y647283D01*
X432990Y646617D01*
X433157Y645950D01*
X433490Y645450D01*
X433990Y645117D01*
X434573Y644950D01*
X435157Y645033D01*
X435657Y645283D01*
X435990Y645617D01*
G01X440090Y644950D02*
Y649950D01*
G01X445690Y644950D02*
Y649950D01*
G01X455390Y643283D02*
Y648283D01*
G01Y647533D02*
X455807Y647950D01*
X456223Y648200D01*
X456890Y648283D01*
X457473Y648200D01*
X458057Y647783D01*
X458307Y647200D01*
X458390Y646617D01*
X458307Y646033D01*
X458057Y645450D01*
X457557Y645117D01*
X456890Y644950D01*
X456307Y645033D01*
X455723Y645283D01*
X455390Y645617D01*
G01X461323Y644950D02*
Y648283D01*
G01Y647617D02*
X461740Y647950D01*
X462157Y648200D01*
X462740Y648283D01*
X463157Y648200D01*
X463657Y647950D01*
G01X468090Y644950D02*
X467590Y645033D01*
X467090Y645367D01*
X466757Y645950D01*
X466590Y646617D01*
X466757Y647283D01*
X467090Y647867D01*
X467590Y648200D01*
X468090Y648283D01*
X468590Y648200D01*
X469090Y647867D01*
X469423Y647283D01*
X469507Y646617D01*
X469423Y645950D01*
X469090Y645367D01*
X468590Y645033D01*
X468090Y644950D01*
G01X475190Y649950D02*
Y644950D01*
G01Y645700D02*
X474857Y645283D01*
X474357Y645033D01*
X473773Y644950D01*
X473107Y645117D01*
X472607Y645533D01*
X472273Y646033D01*
X472190Y646617D01*
X472273Y647200D01*
X472607Y647700D01*
X473107Y648117D01*
X473773Y648283D01*
X474357Y648200D01*
X474773Y648033D01*
X475190Y647700D01*
G01X477873Y648283D02*
Y645950D01*
X478207Y645367D01*
X478707Y645033D01*
X479290Y644950D01*
X479873Y645033D01*
X480373Y645367D01*
X480707Y645950D01*
G01Y644950D02*
Y648283D01*
G01X486223Y647867D02*
X485640Y648200D01*
X485140Y648283D01*
X484473Y648117D01*
X483973Y647783D01*
X483640Y647200D01*
X483557Y646617D01*
X483640Y646033D01*
X483973Y645533D01*
X484473Y645117D01*
X485140Y644950D01*
X485723Y645117D01*
X486223Y645450D01*
G01X490490Y649950D02*
Y644950D01*
G01X489323Y648283D02*
X491657D01*
G01X494840Y645533D02*
X495257Y645200D01*
X495840Y644950D01*
X496340D01*
X496840Y645117D01*
X497173Y645367D01*
X497340Y645700D01*
X497257Y646200D01*
X496923Y646450D01*
X495423Y646950D01*
X495090Y647533D01*
X495257Y647950D01*
X495590Y648200D01*
X496090Y648283D01*
X496590Y648200D01*
X497090Y647950D01*
G01X501690Y644783D02*
X501523Y644867D01*
Y645033D01*
X501690Y645117D01*
X501857Y645033D01*
Y644867D01*
X501690Y644783D01*
G01X506873Y643283D02*
X506040Y644117D01*
X505623Y644950D01*
Y648283D01*
X506040Y649117D01*
X506873Y649950D01*
G01X511890D02*
X513890D01*
G01X512890D02*
Y644950D01*
G01X511890D02*
X513890D01*
G01X517240Y645533D02*
X517657Y645200D01*
X518240Y644950D01*
X518740D01*
X519240Y645117D01*
X519573Y645367D01*
X519740Y645700D01*
X519657Y646200D01*
X519323Y646450D01*
X517823Y646950D01*
X517490Y647533D01*
X517657Y647950D01*
X517990Y648200D01*
X518490Y648283D01*
X518990Y648200D01*
X519490Y647950D01*
G01X524090Y644950D02*
X523590Y645033D01*
X523090Y645367D01*
X522757Y645950D01*
X522590Y646617D01*
X522757Y647283D01*
X523090Y647867D01*
X523590Y648200D01*
X524090Y648283D01*
X524590Y648200D01*
X525090Y647867D01*
X525423Y647283D01*
X525507Y646617D01*
X525423Y645950D01*
X525090Y645367D01*
X524590Y645033D01*
X524090Y644950D01*
G01X529690D02*
Y649950D01*
G01X536790Y644950D02*
Y648283D01*
G01Y647700D02*
X536457Y648033D01*
X535957Y648200D01*
X535373Y648283D01*
X534790Y648117D01*
X534290Y647783D01*
X533957Y647283D01*
X533790Y646617D01*
X533957Y645950D01*
X534290Y645450D01*
X534790Y645117D01*
X535373Y644950D01*
X535957Y645033D01*
X536457Y645283D01*
X536790Y645617D01*
G01X540890Y649950D02*
Y644950D01*
G01X539723Y648283D02*
X542057D01*
G01X545240Y647200D02*
X547907D01*
X547657Y647783D01*
X547240Y648117D01*
X546657Y648283D01*
X546073Y648200D01*
X545573Y647950D01*
X545240Y647367D01*
X545073Y646867D01*
Y646367D01*
X545240Y645867D01*
X545657Y645367D01*
X546157Y645033D01*
X546740Y644950D01*
X547323Y645117D01*
X547907Y645617D01*
G01X556190Y643283D02*
Y648283D01*
G01Y647533D02*
X556607Y647950D01*
X557023Y648200D01*
X557690Y648283D01*
X558273Y648200D01*
X558857Y647783D01*
X559107Y647200D01*
X559190Y646617D01*
X559107Y646033D01*
X558857Y645450D01*
X558357Y645117D01*
X557690Y644950D01*
X557107Y645033D01*
X556523Y645283D01*
X556190Y645617D01*
G01X564790Y644950D02*
Y648283D01*
G01Y647700D02*
X564457Y648033D01*
X563957Y648200D01*
X563373Y648283D01*
X562790Y648117D01*
X562290Y647783D01*
X561957Y647283D01*
X561790Y646617D01*
X561957Y645950D01*
X562290Y645450D01*
X562790Y645117D01*
X563373Y644950D01*
X563957Y645033D01*
X564457Y645283D01*
X564790Y645617D01*
G01X570390Y649950D02*
Y644950D01*
G01Y645700D02*
X570057Y645283D01*
X569557Y645033D01*
X568973Y644950D01*
X568307Y645117D01*
X567807Y645533D01*
X567473Y646033D01*
X567390Y646617D01*
X567473Y647200D01*
X567807Y647700D01*
X568307Y648117D01*
X568973Y648283D01*
X569557Y648200D01*
X569973Y648033D01*
X570390Y647700D01*
G01X273000Y609000D02*
Y604000D01*
G01X271083Y609000D02*
X274917D01*
G01X277183Y604000D02*
Y609000D01*
G01Y606583D02*
X277600Y607000D01*
X278017Y607250D01*
X278683Y607333D01*
X279183Y607250D01*
X279767Y606917D01*
X280017Y606417D01*
Y604000D01*
G01X282950Y606250D02*
X285617D01*
X285367Y606833D01*
X284950Y607167D01*
X284367Y607333D01*
X283783Y607250D01*
X283283Y607000D01*
X282950Y606417D01*
X282783Y605917D01*
Y605417D01*
X282950Y604917D01*
X283367Y604417D01*
X283867Y604083D01*
X284450Y604000D01*
X285033Y604167D01*
X285617Y604667D01*
G01X288633Y604000D02*
Y607333D01*
G01Y606667D02*
X289050Y607000D01*
X289467Y607250D01*
X290050Y607333D01*
X290467Y607250D01*
X290967Y607000D01*
G01X292900Y604000D02*
Y607333D01*
G01Y606417D02*
X293150Y606833D01*
X293567Y607167D01*
X294150Y607333D01*
X294733Y607167D01*
X295150Y606833D01*
X295400Y606417D01*
Y604000D01*
G01Y606417D02*
X295650Y606833D01*
X296067Y607167D01*
X296650Y607333D01*
X297233Y607167D01*
X297650Y606833D01*
X297900Y606333D01*
Y604000D01*
G01X302500D02*
Y607333D01*
G01Y606750D02*
X302167Y607083D01*
X301667Y607250D01*
X301083Y607333D01*
X300500Y607167D01*
X300000Y606833D01*
X299667Y606333D01*
X299500Y605667D01*
X299667Y605000D01*
X300000Y604500D01*
X300500Y604167D01*
X301083Y604000D01*
X301667Y604083D01*
X302167Y604333D01*
X302500Y604667D01*
G01X306600Y604000D02*
Y609000D01*
G01X316300Y602333D02*
Y607333D01*
G01Y606583D02*
X316717Y607000D01*
X317133Y607250D01*
X317800Y607333D01*
X318383Y607250D01*
X318967Y606833D01*
X319217Y606250D01*
X319300Y605667D01*
X319217Y605083D01*
X318967Y604500D01*
X318467Y604167D01*
X317800Y604000D01*
X317217Y604083D01*
X316633Y604333D01*
X316300Y604667D01*
G01X324900Y604000D02*
Y607333D01*
G01Y606750D02*
X324567Y607083D01*
X324067Y607250D01*
X323483Y607333D01*
X322900Y607167D01*
X322400Y606833D01*
X322067Y606333D01*
X321900Y605667D01*
X322067Y605000D01*
X322400Y604500D01*
X322900Y604167D01*
X323483Y604000D01*
X324067Y604083D01*
X324567Y604333D01*
X324900Y604667D01*
G01X330500Y609000D02*
Y604000D01*
G01Y604750D02*
X330167Y604333D01*
X329667Y604083D01*
X329083Y604000D01*
X328417Y604167D01*
X327917Y604583D01*
X327583Y605083D01*
X327500Y605667D01*
X327583Y606250D01*
X327917Y606750D01*
X328417Y607167D01*
X329083Y607333D01*
X329667Y607250D01*
X330083Y607083D01*
X330500Y606750D01*
G01X341533Y606917D02*
X340950Y607250D01*
X340450Y607333D01*
X339783Y607167D01*
X339283Y606833D01*
X338950Y606250D01*
X338867Y605667D01*
X338950Y605083D01*
X339283Y604583D01*
X339783Y604167D01*
X340450Y604000D01*
X341033Y604167D01*
X341533Y604500D01*
G01X347300Y604000D02*
Y607333D01*
G01Y606750D02*
X346967Y607083D01*
X346467Y607250D01*
X345883Y607333D01*
X345300Y607167D01*
X344800Y606833D01*
X344467Y606333D01*
X344300Y605667D01*
X344467Y605000D01*
X344800Y604500D01*
X345300Y604167D01*
X345883Y604000D01*
X346467Y604083D01*
X346967Y604333D01*
X347300Y604667D01*
G01X349983Y604000D02*
Y607333D01*
G01Y606500D02*
X350317Y606917D01*
X350817Y607250D01*
X351483Y607333D01*
X352067Y607250D01*
X352567Y606917D01*
X352817Y606333D01*
Y604000D01*
G01X363933Y606917D02*
X363350Y607250D01*
X362850Y607333D01*
X362183Y607167D01*
X361683Y606833D01*
X361350Y606250D01*
X361267Y605667D01*
X361350Y605083D01*
X361683Y604583D01*
X362183Y604167D01*
X362850Y604000D01*
X363433Y604167D01*
X363933Y604500D01*
G01X366783Y604000D02*
Y609000D01*
G01Y606583D02*
X367200Y607000D01*
X367617Y607250D01*
X368283Y607333D01*
X368783Y607250D01*
X369367Y606917D01*
X369617Y606417D01*
Y604000D01*
G01X375300D02*
Y607333D01*
G01Y606750D02*
X374967Y607083D01*
X374467Y607250D01*
X373883Y607333D01*
X373300Y607167D01*
X372800Y606833D01*
X372467Y606333D01*
X372300Y605667D01*
X372467Y605000D01*
X372800Y604500D01*
X373300Y604167D01*
X373883Y604000D01*
X374467Y604083D01*
X374967Y604333D01*
X375300Y604667D01*
G01X377983Y604000D02*
Y607333D01*
G01Y606500D02*
X378317Y606917D01*
X378817Y607250D01*
X379483Y607333D01*
X380067Y607250D01*
X380567Y606917D01*
X380817Y606333D01*
Y604000D01*
G01X383833Y602750D02*
X384417Y602417D01*
X385083Y602333D01*
X385667Y602417D01*
X386167Y602833D01*
X386500Y603417D01*
Y607333D01*
G01Y606667D02*
X386167Y607000D01*
X385667Y607250D01*
X385083Y607333D01*
X384417Y607167D01*
X384000Y606833D01*
X383667Y606250D01*
X383500Y605667D01*
X383583Y605167D01*
X383917Y604583D01*
X384417Y604167D01*
X385083Y604000D01*
X385583Y604083D01*
X386167Y604417D01*
X386500Y604750D01*
G01X389350Y606250D02*
X392017D01*
X391767Y606833D01*
X391350Y607167D01*
X390767Y607333D01*
X390183Y607250D01*
X389683Y607000D01*
X389350Y606417D01*
X389183Y605917D01*
Y605417D01*
X389350Y604917D01*
X389767Y604417D01*
X390267Y604083D01*
X390850Y604000D01*
X391433Y604167D01*
X392017Y604667D01*
G01X401800Y607333D02*
Y604000D01*
G01Y608667D02*
X401633Y608750D01*
Y608917D01*
X401800Y609000D01*
X401967Y608917D01*
Y608750D01*
X401800Y608667D01*
G01X405983Y604000D02*
Y607333D01*
G01Y606500D02*
X406317Y606917D01*
X406817Y607250D01*
X407483Y607333D01*
X408067Y607250D01*
X408567Y606917D01*
X408817Y606333D01*
Y604000D01*
G01X413000Y609000D02*
Y604000D01*
G01X411833Y607333D02*
X414167D01*
G01X418600Y604000D02*
X418100Y604083D01*
X417600Y604417D01*
X417267Y605000D01*
X417100Y605667D01*
X417267Y606333D01*
X417600Y606917D01*
X418100Y607250D01*
X418600Y607333D01*
X419100Y607250D01*
X419600Y606917D01*
X419933Y606333D01*
X420017Y605667D01*
X419933Y605000D01*
X419600Y604417D01*
X419100Y604083D01*
X418600Y604000D01*
G01X429300D02*
Y608250D01*
X429467Y608667D01*
X429800Y608917D01*
X430300Y609000D01*
X430800Y608833D01*
X431050Y608417D01*
G01X430050Y607000D02*
X428383D01*
G01X433983Y607333D02*
Y605000D01*
X434317Y604417D01*
X434817Y604083D01*
X435400Y604000D01*
X435983Y604083D01*
X436483Y604417D01*
X436817Y605000D01*
G01Y604000D02*
Y607333D01*
G01X441000Y604000D02*
Y609000D01*
G01X446600Y604000D02*
Y609000D01*
G01X459133Y606917D02*
X458550Y607250D01*
X458050Y607333D01*
X457383Y607167D01*
X456883Y606833D01*
X456550Y606250D01*
X456467Y605667D01*
X456550Y605083D01*
X456883Y604583D01*
X457383Y604167D01*
X458050Y604000D01*
X458633Y604167D01*
X459133Y604500D01*
G01X463400Y604000D02*
X462900Y604083D01*
X462400Y604417D01*
X462067Y605000D01*
X461900Y605667D01*
X462067Y606333D01*
X462400Y606917D01*
X462900Y607250D01*
X463400Y607333D01*
X463900Y607250D01*
X464400Y606917D01*
X464733Y606333D01*
X464817Y605667D01*
X464733Y605000D01*
X464400Y604417D01*
X463900Y604083D01*
X463400Y604000D01*
G01X467583D02*
Y607333D01*
G01Y606500D02*
X467917Y606917D01*
X468417Y607250D01*
X469083Y607333D01*
X469667Y607250D01*
X470167Y606917D01*
X470417Y606333D01*
Y604000D01*
G01X474600Y609000D02*
Y604000D01*
G01X473433Y607333D02*
X475767D01*
G01X481700Y604000D02*
Y607333D01*
G01Y606750D02*
X481367Y607083D01*
X480867Y607250D01*
X480283Y607333D01*
X479700Y607167D01*
X479200Y606833D01*
X478867Y606333D01*
X478700Y605667D01*
X478867Y605000D01*
X479200Y604500D01*
X479700Y604167D01*
X480283Y604000D01*
X480867Y604083D01*
X481367Y604333D01*
X481700Y604667D01*
G01X487133Y606917D02*
X486550Y607250D01*
X486050Y607333D01*
X485383Y607167D01*
X484883Y606833D01*
X484550Y606250D01*
X484467Y605667D01*
X484550Y605083D01*
X484883Y604583D01*
X485383Y604167D01*
X486050Y604000D01*
X486633Y604167D01*
X487133Y604500D01*
G01X491400Y609000D02*
Y604000D01*
G01X490233Y607333D02*
X492567D01*
G01X270417Y588500D02*
X272500Y593500D01*
X274583Y588500D01*
G01X273833Y590250D02*
X271167D01*
G01X276683Y588500D02*
Y591833D01*
G01Y591000D02*
X277017Y591417D01*
X277517Y591750D01*
X278183Y591833D01*
X278767Y591750D01*
X279267Y591417D01*
X279517Y590833D01*
Y588500D01*
G01X281950Y587000D02*
X282450Y586833D01*
X283117Y587000D01*
X283533Y587333D01*
X283867Y587750D01*
X284367Y589083D01*
X285450Y591833D01*
G01X282783D02*
X284367Y589083D01*
G01X293483Y588500D02*
Y593500D01*
G01Y591083D02*
X293900Y591500D01*
X294317Y591750D01*
X294983Y591833D01*
X295483Y591750D01*
X296067Y591417D01*
X296317Y590917D01*
Y588500D01*
G01X300500D02*
X300000Y588583D01*
X299500Y588917D01*
X299167Y589500D01*
X299000Y590167D01*
X299167Y590833D01*
X299500Y591417D01*
X300000Y591750D01*
X300500Y591833D01*
X301000Y591750D01*
X301500Y591417D01*
X301833Y590833D01*
X301917Y590167D01*
X301833Y589500D01*
X301500Y588917D01*
X301000Y588583D01*
X300500Y588500D01*
G01X306100D02*
Y593500D01*
G01X310450Y590750D02*
X313117D01*
X312867Y591333D01*
X312450Y591667D01*
X311867Y591833D01*
X311283Y591750D01*
X310783Y591500D01*
X310450Y590917D01*
X310283Y590417D01*
Y589917D01*
X310450Y589417D01*
X310867Y588917D01*
X311367Y588583D01*
X311950Y588500D01*
X312533Y588667D01*
X313117Y589167D01*
G01X322900Y593500D02*
Y588500D01*
G01X321733Y591833D02*
X324067D01*
G01X328500Y588500D02*
X328000Y588583D01*
X327500Y588917D01*
X327167Y589500D01*
X327000Y590167D01*
X327167Y590833D01*
X327500Y591417D01*
X328000Y591750D01*
X328500Y591833D01*
X329000Y591750D01*
X329500Y591417D01*
X329833Y590833D01*
X329917Y590167D01*
X329833Y589500D01*
X329500Y588917D01*
X329000Y588583D01*
X328500Y588500D01*
G01X338283D02*
Y593500D01*
G01Y591083D02*
X338700Y591500D01*
X339117Y591750D01*
X339783Y591833D01*
X340283Y591750D01*
X340867Y591417D01*
X341117Y590917D01*
Y588500D01*
G01X345300D02*
X344800Y588583D01*
X344300Y588917D01*
X343967Y589500D01*
X343800Y590167D01*
X343967Y590833D01*
X344300Y591417D01*
X344800Y591750D01*
X345300Y591833D01*
X345800Y591750D01*
X346300Y591417D01*
X346633Y590833D01*
X346717Y590167D01*
X346633Y589500D01*
X346300Y588917D01*
X345800Y588583D01*
X345300Y588500D01*
G01X350900D02*
Y593500D01*
G01X355250Y590750D02*
X357917D01*
X357667Y591333D01*
X357250Y591667D01*
X356667Y591833D01*
X356083Y591750D01*
X355583Y591500D01*
X355250Y590917D01*
X355083Y590417D01*
Y589917D01*
X355250Y589417D01*
X355667Y588917D01*
X356167Y588583D01*
X356750Y588500D01*
X357333Y588667D01*
X357917Y589167D01*
G01X270917Y619000D02*
X273000Y624000D01*
X275083Y619000D01*
G01X274333Y620750D02*
X271667D01*
G01X277183Y619000D02*
Y622333D01*
G01Y621500D02*
X277517Y621917D01*
X278017Y622250D01*
X278683Y622333D01*
X279267Y622250D01*
X279767Y621917D01*
X280017Y621333D01*
Y619000D01*
G01X284200Y624000D02*
Y619000D01*
G01X283033Y622333D02*
X285367D01*
G01X289800D02*
Y619000D01*
G01Y623667D02*
X289633Y623750D01*
Y623917D01*
X289800Y624000D01*
X289967Y623917D01*
Y623750D01*
X289800Y623667D01*
G01X294317Y620667D02*
X296483D01*
G01X299500Y617333D02*
Y622333D01*
G01Y621583D02*
X299917Y622000D01*
X300333Y622250D01*
X301000Y622333D01*
X301583Y622250D01*
X302167Y621833D01*
X302417Y621250D01*
X302500Y620667D01*
X302417Y620083D01*
X302167Y619500D01*
X301667Y619167D01*
X301000Y619000D01*
X300417Y619083D01*
X299833Y619333D01*
X299500Y619667D01*
G01X308100Y619000D02*
Y622333D01*
G01Y621750D02*
X307767Y622083D01*
X307267Y622250D01*
X306683Y622333D01*
X306100Y622167D01*
X305600Y621833D01*
X305267Y621333D01*
X305100Y620667D01*
X305267Y620000D01*
X305600Y619500D01*
X306100Y619167D01*
X306683Y619000D01*
X307267Y619083D01*
X307767Y619333D01*
X308100Y619667D01*
G01X313700Y624000D02*
Y619000D01*
G01Y619750D02*
X313367Y619333D01*
X312867Y619083D01*
X312283Y619000D01*
X311617Y619167D01*
X311117Y619583D01*
X310783Y620083D01*
X310700Y620667D01*
X310783Y621250D01*
X311117Y621750D01*
X311617Y622167D01*
X312283Y622333D01*
X312867Y622250D01*
X313283Y622083D01*
X313700Y621750D01*
G01X322150Y619583D02*
X322567Y619250D01*
X323150Y619000D01*
X323650D01*
X324150Y619167D01*
X324483Y619417D01*
X324650Y619750D01*
X324567Y620250D01*
X324233Y620500D01*
X322733Y621000D01*
X322400Y621583D01*
X322567Y622000D01*
X322900Y622250D01*
X323400Y622333D01*
X323900Y622250D01*
X324400Y622000D01*
G01X329000Y622333D02*
Y619000D01*
G01Y623667D02*
X328833Y623750D01*
Y623917D01*
X329000Y624000D01*
X329167Y623917D01*
Y623750D01*
X329000Y623667D01*
G01X333350Y622333D02*
X335850D01*
X333350Y619000D01*
X335850D01*
G01X338950Y621250D02*
X341617D01*
X341367Y621833D01*
X340950Y622167D01*
X340367Y622333D01*
X339783Y622250D01*
X339283Y622000D01*
X338950Y621417D01*
X338783Y620917D01*
Y620417D01*
X338950Y619917D01*
X339367Y619417D01*
X339867Y619083D01*
X340450Y619000D01*
X341033Y619167D01*
X341617Y619667D01*
G01X269717Y637573D02*
X270717Y634240D01*
X271800Y637573D01*
X272883Y634240D01*
X273883Y637573D01*
G01X277400D02*
Y634240D01*
G01Y638907D02*
X277233Y638990D01*
Y639157D01*
X277400Y639240D01*
X277567Y639157D01*
Y638990D01*
X277400Y638907D01*
G01X283000Y639240D02*
Y634240D01*
G01X281833Y637573D02*
X284167D01*
G01X287183Y634240D02*
Y639240D01*
G01Y636823D02*
X287600Y637240D01*
X288017Y637490D01*
X288683Y637573D01*
X289183Y637490D01*
X289767Y637157D01*
X290017Y636657D01*
Y634240D01*
G01X294200D02*
X293700Y634323D01*
X293200Y634657D01*
X292867Y635240D01*
X292700Y635907D01*
X292867Y636573D01*
X293200Y637157D01*
X293700Y637490D01*
X294200Y637573D01*
X294700Y637490D01*
X295200Y637157D01*
X295533Y636573D01*
X295617Y635907D01*
X295533Y635240D01*
X295200Y634657D01*
X294700Y634323D01*
X294200Y634240D01*
G01X298383Y637573D02*
Y635240D01*
X298717Y634657D01*
X299217Y634323D01*
X299800Y634240D01*
X300383Y634323D01*
X300883Y634657D01*
X301217Y635240D01*
G01Y634240D02*
Y637573D01*
G01X305400Y639240D02*
Y634240D01*
G01X304233Y637573D02*
X306567D01*
G01X317933Y637157D02*
X317350Y637490D01*
X316850Y637573D01*
X316183Y637407D01*
X315683Y637073D01*
X315350Y636490D01*
X315267Y635907D01*
X315350Y635323D01*
X315683Y634823D01*
X316183Y634407D01*
X316850Y634240D01*
X317433Y634407D01*
X317933Y634740D01*
G01X322200Y634240D02*
X321700Y634323D01*
X321200Y634657D01*
X320867Y635240D01*
X320700Y635907D01*
X320867Y636573D01*
X321200Y637157D01*
X321700Y637490D01*
X322200Y637573D01*
X322700Y637490D01*
X323200Y637157D01*
X323533Y636573D01*
X323617Y635907D01*
X323533Y635240D01*
X323200Y634657D01*
X322700Y634323D01*
X322200Y634240D01*
G01X326383D02*
Y637573D01*
G01Y636740D02*
X326717Y637157D01*
X327217Y637490D01*
X327883Y637573D01*
X328467Y637490D01*
X328967Y637157D01*
X329217Y636573D01*
Y634240D01*
G01X331983D02*
Y637573D01*
G01Y636740D02*
X332317Y637157D01*
X332817Y637490D01*
X333483Y637573D01*
X334067Y637490D01*
X334567Y637157D01*
X334817Y636573D01*
Y634240D01*
G01X337750Y636490D02*
X340417D01*
X340167Y637073D01*
X339750Y637407D01*
X339167Y637573D01*
X338583Y637490D01*
X338083Y637240D01*
X337750Y636657D01*
X337583Y636157D01*
Y635657D01*
X337750Y635157D01*
X338167Y634657D01*
X338667Y634323D01*
X339250Y634240D01*
X339833Y634407D01*
X340417Y634907D01*
G01X345933Y637157D02*
X345350Y637490D01*
X344850Y637573D01*
X344183Y637407D01*
X343683Y637073D01*
X343350Y636490D01*
X343267Y635907D01*
X343350Y635323D01*
X343683Y634823D01*
X344183Y634407D01*
X344850Y634240D01*
X345433Y634407D01*
X345933Y634740D01*
G01X350200Y639240D02*
Y634240D01*
G01X349033Y637573D02*
X351367D01*
G01X355800D02*
Y634240D01*
G01Y638907D02*
X355633Y638990D01*
Y639157D01*
X355800Y639240D01*
X355967Y639157D01*
Y638990D01*
X355800Y638907D01*
G01X359983Y634240D02*
Y637573D01*
G01Y636740D02*
X360317Y637157D01*
X360817Y637490D01*
X361483Y637573D01*
X362067Y637490D01*
X362567Y637157D01*
X362817Y636573D01*
Y634240D01*
G01X365833Y632990D02*
X366417Y632657D01*
X367083Y632573D01*
X367667Y632657D01*
X368167Y633073D01*
X368500Y633657D01*
Y637573D01*
G01Y636907D02*
X368167Y637240D01*
X367667Y637490D01*
X367083Y637573D01*
X366417Y637407D01*
X366000Y637073D01*
X365667Y636490D01*
X365500Y635907D01*
X365583Y635407D01*
X365917Y634823D01*
X366417Y634407D01*
X367083Y634240D01*
X367583Y634323D01*
X368167Y634657D01*
X368500Y634990D01*
G01X378200Y639240D02*
Y634240D01*
G01X377033Y637573D02*
X379367D01*
G01X383800Y634240D02*
X383300Y634323D01*
X382800Y634657D01*
X382467Y635240D01*
X382300Y635907D01*
X382467Y636573D01*
X382800Y637157D01*
X383300Y637490D01*
X383800Y637573D01*
X384300Y637490D01*
X384800Y637157D01*
X385133Y636573D01*
X385217Y635907D01*
X385133Y635240D01*
X384800Y634657D01*
X384300Y634323D01*
X383800Y634240D01*
G01X395000D02*
X394500Y634323D01*
X394000Y634657D01*
X393667Y635240D01*
X393500Y635907D01*
X393667Y636573D01*
X394000Y637157D01*
X394500Y637490D01*
X395000Y637573D01*
X395500Y637490D01*
X396000Y637157D01*
X396333Y636573D01*
X396417Y635907D01*
X396333Y635240D01*
X396000Y634657D01*
X395500Y634323D01*
X395000Y634240D01*
G01X400600Y639240D02*
Y634240D01*
G01X399433Y637573D02*
X401767D01*
G01X404783Y634240D02*
Y639240D01*
G01Y636823D02*
X405200Y637240D01*
X405617Y637490D01*
X406283Y637573D01*
X406783Y637490D01*
X407367Y637157D01*
X407617Y636657D01*
Y634240D01*
G01X410550Y636490D02*
X413217D01*
X412967Y637073D01*
X412550Y637407D01*
X411967Y637573D01*
X411383Y637490D01*
X410883Y637240D01*
X410550Y636657D01*
X410383Y636157D01*
Y635657D01*
X410550Y635157D01*
X410967Y634657D01*
X411467Y634323D01*
X412050Y634240D01*
X412633Y634407D01*
X413217Y634907D01*
G01X416233Y634240D02*
Y637573D01*
G01Y636907D02*
X416650Y637240D01*
X417067Y637490D01*
X417650Y637573D01*
X418067Y637490D01*
X418567Y637240D01*
G01X428600Y634240D02*
Y639240D01*
G01X435700Y634240D02*
Y637573D01*
G01Y636990D02*
X435367Y637323D01*
X434867Y637490D01*
X434283Y637573D01*
X433700Y637407D01*
X433200Y637073D01*
X432867Y636573D01*
X432700Y635907D01*
X432867Y635240D01*
X433200Y634740D01*
X433700Y634407D01*
X434283Y634240D01*
X434867Y634323D01*
X435367Y634573D01*
X435700Y634907D01*
G01X438050Y632740D02*
X438550Y632573D01*
X439217Y632740D01*
X439633Y633073D01*
X439967Y633490D01*
X440467Y634823D01*
X441550Y637573D01*
G01X438883D02*
X440467Y634823D01*
G01X444150Y636490D02*
X446817D01*
X446567Y637073D01*
X446150Y637407D01*
X445567Y637573D01*
X444983Y637490D01*
X444483Y637240D01*
X444150Y636657D01*
X443983Y636157D01*
Y635657D01*
X444150Y635157D01*
X444567Y634657D01*
X445067Y634323D01*
X445650Y634240D01*
X446233Y634407D01*
X446817Y634907D01*
G01X449833Y634240D02*
Y637573D01*
G01Y636907D02*
X450250Y637240D01*
X450667Y637490D01*
X451250Y637573D01*
X451667Y637490D01*
X452167Y637240D01*
G01X455350Y634823D02*
X455767Y634490D01*
X456350Y634240D01*
X456850D01*
X457350Y634407D01*
X457683Y634657D01*
X457850Y634990D01*
X457767Y635490D01*
X457433Y635740D01*
X455933Y636240D01*
X455600Y636823D01*
X455767Y637240D01*
X456100Y637490D01*
X456600Y637573D01*
X457100Y637490D01*
X457600Y637240D01*
G01X462617Y632573D02*
X463450Y633407D01*
X463867Y634240D01*
Y637573D01*
X463450Y638407D01*
X462617Y639240D01*
G01X270257Y644950D02*
Y649950D01*
X271923D01*
X272590Y649700D01*
X273090Y649367D01*
X273507Y648867D01*
X273840Y648283D01*
X273923Y647450D01*
X273840Y646617D01*
X273507Y646033D01*
X273090Y645533D01*
X272590Y645200D01*
X271923Y644950D01*
X270257D01*
G01X276440Y647200D02*
X279107D01*
X278857Y647783D01*
X278440Y648117D01*
X277857Y648283D01*
X277273Y648200D01*
X276773Y647950D01*
X276440Y647367D01*
X276273Y646867D01*
Y646367D01*
X276440Y645867D01*
X276857Y645367D01*
X277357Y645033D01*
X277940Y644950D01*
X278523Y645117D01*
X279107Y645617D01*
G01X283290Y644950D02*
Y649950D01*
G01X287640Y647200D02*
X290307D01*
X290057Y647783D01*
X289640Y648117D01*
X289057Y648283D01*
X288473Y648200D01*
X287973Y647950D01*
X287640Y647367D01*
X287473Y646867D01*
Y646367D01*
X287640Y645867D01*
X288057Y645367D01*
X288557Y645033D01*
X289140Y644950D01*
X289723Y645117D01*
X290307Y645617D01*
G01X294490Y649950D02*
Y644950D01*
G01X293323Y648283D02*
X295657D01*
G01X298840Y647200D02*
X301507D01*
X301257Y647783D01*
X300840Y648117D01*
X300257Y648283D01*
X299673Y648200D01*
X299173Y647950D01*
X298840Y647367D01*
X298673Y646867D01*
Y646367D01*
X298840Y645867D01*
X299257Y645367D01*
X299757Y645033D01*
X300340Y644950D01*
X300923Y645117D01*
X301507Y645617D01*
G01X309873Y644950D02*
Y648283D01*
G01Y647450D02*
X310207Y647867D01*
X310707Y648200D01*
X311373Y648283D01*
X311957Y648200D01*
X312457Y647867D01*
X312707Y647283D01*
Y644950D01*
G01X316890D02*
X316390Y645033D01*
X315890Y645367D01*
X315557Y645950D01*
X315390Y646617D01*
X315557Y647283D01*
X315890Y647867D01*
X316390Y648200D01*
X316890Y648283D01*
X317390Y648200D01*
X317890Y647867D01*
X318223Y647283D01*
X318307Y646617D01*
X318223Y645950D01*
X317890Y645367D01*
X317390Y645033D01*
X316890Y644950D01*
G01X321073D02*
Y648283D01*
G01Y647450D02*
X321407Y647867D01*
X321907Y648200D01*
X322573Y648283D01*
X323157Y648200D01*
X323657Y647867D01*
X323907Y647283D01*
Y644950D01*
G01X327007Y646617D02*
X329173D01*
G01X333190Y644950D02*
Y649200D01*
X333357Y649617D01*
X333690Y649867D01*
X334190Y649950D01*
X334690Y649783D01*
X334940Y649367D01*
G01X333940Y647950D02*
X332273D01*
G01X337873Y648283D02*
Y645950D01*
X338207Y645367D01*
X338707Y645033D01*
X339290Y644950D01*
X339873Y645033D01*
X340373Y645367D01*
X340707Y645950D01*
G01Y644950D02*
Y648283D01*
G01X343473Y644950D02*
Y648283D01*
G01Y647450D02*
X343807Y647867D01*
X344307Y648200D01*
X344973Y648283D01*
X345557Y648200D01*
X346057Y647867D01*
X346307Y647283D01*
Y644950D01*
G01X351823Y647867D02*
X351240Y648200D01*
X350740Y648283D01*
X350073Y648117D01*
X349573Y647783D01*
X349240Y647200D01*
X349157Y646617D01*
X349240Y646033D01*
X349573Y645533D01*
X350073Y645117D01*
X350740Y644950D01*
X351323Y645117D01*
X351823Y645450D01*
G01X356090Y649950D02*
Y644950D01*
G01X354923Y648283D02*
X357257D01*
G01X361690D02*
Y644950D01*
G01Y649617D02*
X361523Y649700D01*
Y649867D01*
X361690Y649950D01*
X361857Y649867D01*
Y649700D01*
X361690Y649617D01*
G01X367290Y644950D02*
X366790Y645033D01*
X366290Y645367D01*
X365957Y645950D01*
X365790Y646617D01*
X365957Y647283D01*
X366290Y647867D01*
X366790Y648200D01*
X367290Y648283D01*
X367790Y648200D01*
X368290Y647867D01*
X368623Y647283D01*
X368707Y646617D01*
X368623Y645950D01*
X368290Y645367D01*
X367790Y645033D01*
X367290Y644950D01*
G01X371473D02*
Y648283D01*
G01Y647450D02*
X371807Y647867D01*
X372307Y648200D01*
X372973Y648283D01*
X373557Y648200D01*
X374057Y647867D01*
X374307Y647283D01*
Y644950D01*
G01X379990D02*
Y648283D01*
G01Y647700D02*
X379657Y648033D01*
X379157Y648200D01*
X378573Y648283D01*
X377990Y648117D01*
X377490Y647783D01*
X377157Y647283D01*
X376990Y646617D01*
X377157Y645950D01*
X377490Y645450D01*
X377990Y645117D01*
X378573Y644950D01*
X379157Y645033D01*
X379657Y645283D01*
X379990Y645617D01*
G01X384090Y644950D02*
Y649950D01*
G01X393790Y643283D02*
Y648283D01*
G01Y647533D02*
X394207Y647950D01*
X394623Y648200D01*
X395290Y648283D01*
X395873Y648200D01*
X396457Y647783D01*
X396707Y647200D01*
X396790Y646617D01*
X396707Y646033D01*
X396457Y645450D01*
X395957Y645117D01*
X395290Y644950D01*
X394707Y645033D01*
X394123Y645283D01*
X393790Y645617D01*
G01X402390Y644950D02*
Y648283D01*
G01Y647700D02*
X402057Y648033D01*
X401557Y648200D01*
X400973Y648283D01*
X400390Y648117D01*
X399890Y647783D01*
X399557Y647283D01*
X399390Y646617D01*
X399557Y645950D01*
X399890Y645450D01*
X400390Y645117D01*
X400973Y644950D01*
X401557Y645033D01*
X402057Y645283D01*
X402390Y645617D01*
G01X407990Y649950D02*
Y644950D01*
G01Y645700D02*
X407657Y645283D01*
X407157Y645033D01*
X406573Y644950D01*
X405907Y645117D01*
X405407Y645533D01*
X405073Y646033D01*
X404990Y646617D01*
X405073Y647200D01*
X405407Y647700D01*
X405907Y648117D01*
X406573Y648283D01*
X407157Y648200D01*
X407573Y648033D01*
X407990Y647700D01*
G01X417690Y648283D02*
Y644950D01*
G01Y649617D02*
X417523Y649700D01*
Y649867D01*
X417690Y649950D01*
X417857Y649867D01*
Y649700D01*
X417690Y649617D01*
G01X421873Y644950D02*
Y648283D01*
G01Y647450D02*
X422207Y647867D01*
X422707Y648200D01*
X423373Y648283D01*
X423957Y648200D01*
X424457Y647867D01*
X424707Y647283D01*
Y644950D01*
G01X435990D02*
Y648283D01*
G01Y647700D02*
X435657Y648033D01*
X435157Y648200D01*
X434573Y648283D01*
X433990Y648117D01*
X433490Y647783D01*
X433157Y647283D01*
X432990Y646617D01*
X433157Y645950D01*
X433490Y645450D01*
X433990Y645117D01*
X434573Y644950D01*
X435157Y645033D01*
X435657Y645283D01*
X435990Y645617D01*
G01X440090Y644950D02*
Y649950D01*
G01X445690Y644950D02*
Y649950D01*
G01X455390Y643283D02*
Y648283D01*
G01Y647533D02*
X455807Y647950D01*
X456223Y648200D01*
X456890Y648283D01*
X457473Y648200D01*
X458057Y647783D01*
X458307Y647200D01*
X458390Y646617D01*
X458307Y646033D01*
X458057Y645450D01*
X457557Y645117D01*
X456890Y644950D01*
X456307Y645033D01*
X455723Y645283D01*
X455390Y645617D01*
G01X461323Y644950D02*
Y648283D01*
G01Y647617D02*
X461740Y647950D01*
X462157Y648200D01*
X462740Y648283D01*
X463157Y648200D01*
X463657Y647950D01*
G01X468090Y644950D02*
X467590Y645033D01*
X467090Y645367D01*
X466757Y645950D01*
X466590Y646617D01*
X466757Y647283D01*
X467090Y647867D01*
X467590Y648200D01*
X468090Y648283D01*
X468590Y648200D01*
X469090Y647867D01*
X469423Y647283D01*
X469507Y646617D01*
X469423Y645950D01*
X469090Y645367D01*
X468590Y645033D01*
X468090Y644950D01*
G01X475190Y649950D02*
Y644950D01*
G01Y645700D02*
X474857Y645283D01*
X474357Y645033D01*
X473773Y644950D01*
X473107Y645117D01*
X472607Y645533D01*
X472273Y646033D01*
X472190Y646617D01*
X472273Y647200D01*
X472607Y647700D01*
X473107Y648117D01*
X473773Y648283D01*
X474357Y648200D01*
X474773Y648033D01*
X475190Y647700D01*
G01X477873Y648283D02*
Y645950D01*
X478207Y645367D01*
X478707Y645033D01*
X479290Y644950D01*
X479873Y645033D01*
X480373Y645367D01*
X480707Y645950D01*
G01Y644950D02*
Y648283D01*
G01X486223Y647867D02*
X485640Y648200D01*
X485140Y648283D01*
X484473Y648117D01*
X483973Y647783D01*
X483640Y647200D01*
X483557Y646617D01*
X483640Y646033D01*
X483973Y645533D01*
X484473Y645117D01*
X485140Y644950D01*
X485723Y645117D01*
X486223Y645450D01*
G01X490490Y649950D02*
Y644950D01*
G01X489323Y648283D02*
X491657D01*
G01X494840Y645533D02*
X495257Y645200D01*
X495840Y644950D01*
X496340D01*
X496840Y645117D01*
X497173Y645367D01*
X497340Y645700D01*
X497257Y646200D01*
X496923Y646450D01*
X495423Y646950D01*
X495090Y647533D01*
X495257Y647950D01*
X495590Y648200D01*
X496090Y648283D01*
X496590Y648200D01*
X497090Y647950D01*
G01X501690Y644783D02*
X501523Y644867D01*
Y645033D01*
X501690Y645117D01*
X501857Y645033D01*
Y644867D01*
X501690Y644783D01*
G01X506873Y643283D02*
X506040Y644117D01*
X505623Y644950D01*
Y648283D01*
X506040Y649117D01*
X506873Y649950D01*
G01X511890D02*
X513890D01*
G01X512890D02*
Y644950D01*
G01X511890D02*
X513890D01*
G01X517240Y645533D02*
X517657Y645200D01*
X518240Y644950D01*
X518740D01*
X519240Y645117D01*
X519573Y645367D01*
X519740Y645700D01*
X519657Y646200D01*
X519323Y646450D01*
X517823Y646950D01*
X517490Y647533D01*
X517657Y647950D01*
X517990Y648200D01*
X518490Y648283D01*
X518990Y648200D01*
X519490Y647950D01*
G01X524090Y644950D02*
X523590Y645033D01*
X523090Y645367D01*
X522757Y645950D01*
X522590Y646617D01*
X522757Y647283D01*
X523090Y647867D01*
X523590Y648200D01*
X524090Y648283D01*
X524590Y648200D01*
X525090Y647867D01*
X525423Y647283D01*
X525507Y646617D01*
X525423Y645950D01*
X525090Y645367D01*
X524590Y645033D01*
X524090Y644950D01*
G01X529690D02*
Y649950D01*
G01X536790Y644950D02*
Y648283D01*
G01Y647700D02*
X536457Y648033D01*
X535957Y648200D01*
X535373Y648283D01*
X534790Y648117D01*
X534290Y647783D01*
X533957Y647283D01*
X533790Y646617D01*
X533957Y645950D01*
X534290Y645450D01*
X534790Y645117D01*
X535373Y644950D01*
X535957Y645033D01*
X536457Y645283D01*
X536790Y645617D01*
G01X540890Y649950D02*
Y644950D01*
G01X539723Y648283D02*
X542057D01*
G01X545240Y647200D02*
X547907D01*
X547657Y647783D01*
X547240Y648117D01*
X546657Y648283D01*
X546073Y648200D01*
X545573Y647950D01*
X545240Y647367D01*
X545073Y646867D01*
Y646367D01*
X545240Y645867D01*
X545657Y645367D01*
X546157Y645033D01*
X546740Y644950D01*
X547323Y645117D01*
X547907Y645617D01*
G01X556190Y643283D02*
Y648283D01*
G01Y647533D02*
X556607Y647950D01*
X557023Y648200D01*
X557690Y648283D01*
X558273Y648200D01*
X558857Y647783D01*
X559107Y647200D01*
X559190Y646617D01*
X559107Y646033D01*
X558857Y645450D01*
X558357Y645117D01*
X557690Y644950D01*
X557107Y645033D01*
X556523Y645283D01*
X556190Y645617D01*
G01X564790Y644950D02*
Y648283D01*
G01Y647700D02*
X564457Y648033D01*
X563957Y648200D01*
X563373Y648283D01*
X562790Y648117D01*
X562290Y647783D01*
X561957Y647283D01*
X561790Y646617D01*
X561957Y645950D01*
X562290Y645450D01*
X562790Y645117D01*
X563373Y644950D01*
X563957Y645033D01*
X564457Y645283D01*
X564790Y645617D01*
G01X570390Y649950D02*
Y644950D01*
G01Y645700D02*
X570057Y645283D01*
X569557Y645033D01*
X568973Y644950D01*
X568307Y645117D01*
X567807Y645533D01*
X567473Y646033D01*
X567390Y646617D01*
X567473Y647200D01*
X567807Y647700D01*
X568307Y648117D01*
X568973Y648283D01*
X569557Y648200D01*
X569973Y648033D01*
X570390Y647700D01*
G01X395000Y364500D02*
Y175500D01*
G01Y364500D02*
Y175500D01*
G01X402977Y229887D02*
X403310Y230137D01*
X403560Y230553D01*
X403727Y231137D01*
X403560Y231637D01*
X403227Y231970D01*
X402643Y232220D01*
X400393D01*
Y227220D01*
X403143D01*
X403727Y227553D01*
X404060Y228053D01*
X404227Y228637D01*
X404060Y229220D01*
X403560Y229720D01*
X402977Y229887D01*
X400393D01*
G01X406493Y230553D02*
Y228220D01*
X406827Y227637D01*
X407327Y227303D01*
X407910Y227220D01*
X408493Y227303D01*
X408993Y227637D01*
X409327Y228220D01*
G01Y227220D02*
Y230553D01*
G01X411010Y227220D02*
Y230553D01*
G01Y229637D02*
X411260Y230053D01*
X411677Y230387D01*
X412260Y230553D01*
X412843Y230387D01*
X413260Y230053D01*
X413510Y229637D01*
Y227220D01*
G01Y229637D02*
X413760Y230053D01*
X414177Y230387D01*
X414760Y230553D01*
X415343Y230387D01*
X415760Y230053D01*
X416010Y229553D01*
Y227220D01*
G01X417610Y225553D02*
Y230553D01*
G01Y229803D02*
X418027Y230220D01*
X418443Y230470D01*
X419110Y230553D01*
X419693Y230470D01*
X420277Y230053D01*
X420527Y229470D01*
X420610Y228887D01*
X420527Y228303D01*
X420277Y227720D01*
X419777Y227387D01*
X419110Y227220D01*
X418527Y227303D01*
X417943Y227553D01*
X417610Y227887D01*
G01X402977Y229887D02*
X403310Y230137D01*
X403560Y230553D01*
X403727Y231137D01*
X403560Y231637D01*
X403227Y231970D01*
X402643Y232220D01*
X400393D01*
Y227220D01*
X403143D01*
X403727Y227553D01*
X404060Y228053D01*
X404227Y228637D01*
X404060Y229220D01*
X403560Y229720D01*
X402977Y229887D01*
X400393D01*
G01X406493Y230553D02*
Y228220D01*
X406827Y227637D01*
X407327Y227303D01*
X407910Y227220D01*
X408493Y227303D01*
X408993Y227637D01*
X409327Y228220D01*
G01Y227220D02*
Y230553D01*
G01X411010Y227220D02*
Y230553D01*
G01Y229637D02*
X411260Y230053D01*
X411677Y230387D01*
X412260Y230553D01*
X412843Y230387D01*
X413260Y230053D01*
X413510Y229637D01*
Y227220D01*
G01Y229637D02*
X413760Y230053D01*
X414177Y230387D01*
X414760Y230553D01*
X415343Y230387D01*
X415760Y230053D01*
X416010Y229553D01*
Y227220D01*
G01X417610Y225553D02*
Y230553D01*
G01Y229803D02*
X418027Y230220D01*
X418443Y230470D01*
X419110Y230553D01*
X419693Y230470D01*
X420277Y230053D01*
X420527Y229470D01*
X420610Y228887D01*
X420527Y228303D01*
X420277Y227720D01*
X419777Y227387D01*
X419110Y227220D01*
X418527Y227303D01*
X417943Y227553D01*
X417610Y227887D01*
G01X401520Y268213D02*
X403020Y264880D01*
X404520Y268213D01*
G01X408620D02*
Y264880D01*
G01Y269547D02*
X408453Y269630D01*
Y269797D01*
X408620Y269880D01*
X408787Y269797D01*
Y269630D01*
X408620Y269547D01*
G01X415720Y264880D02*
Y268213D01*
G01Y267630D02*
X415387Y267963D01*
X414887Y268130D01*
X414303Y268213D01*
X413720Y268047D01*
X413220Y267713D01*
X412887Y267213D01*
X412720Y266547D01*
X412887Y265880D01*
X413220Y265380D01*
X413720Y265047D01*
X414303Y264880D01*
X414887Y264963D01*
X415387Y265213D01*
X415720Y265547D01*
G01X401067Y277360D02*
Y282360D01*
X402733D01*
X403400Y282110D01*
X403900Y281777D01*
X404317Y281277D01*
X404650Y280693D01*
X404733Y279860D01*
X404650Y279027D01*
X404317Y278443D01*
X403900Y277943D01*
X403400Y277610D01*
X402733Y277360D01*
X401067D01*
G01X408500Y280693D02*
Y277360D01*
G01Y282027D02*
X408333Y282110D01*
Y282277D01*
X408500Y282360D01*
X408667Y282277D01*
Y282110D01*
X408500Y282027D01*
G01X411600Y277360D02*
Y280693D01*
G01Y279777D02*
X411850Y280193D01*
X412267Y280527D01*
X412850Y280693D01*
X413433Y280527D01*
X413850Y280193D01*
X414100Y279777D01*
Y277360D01*
G01Y279777D02*
X414350Y280193D01*
X414767Y280527D01*
X415350Y280693D01*
X415933Y280527D01*
X416350Y280193D01*
X416600Y279693D01*
Y277360D01*
G01X418200Y275693D02*
Y280693D01*
G01Y279943D02*
X418617Y280360D01*
X419033Y280610D01*
X419700Y280693D01*
X420283Y280610D01*
X420867Y280193D01*
X421117Y279610D01*
X421200Y279027D01*
X421117Y278443D01*
X420867Y277860D01*
X420367Y277527D01*
X419700Y277360D01*
X419117Y277443D01*
X418533Y277693D01*
X418200Y278027D01*
G01X425300Y277360D02*
Y282360D01*
G01X429650Y279610D02*
X432317D01*
X432067Y280193D01*
X431650Y280527D01*
X431067Y280693D01*
X430483Y280610D01*
X429983Y280360D01*
X429650Y279777D01*
X429483Y279277D01*
Y278777D01*
X429650Y278277D01*
X430067Y277777D01*
X430567Y277443D01*
X431150Y277360D01*
X431733Y277527D01*
X432317Y278027D01*
G01X441600Y277360D02*
Y281610D01*
X441767Y282027D01*
X442100Y282277D01*
X442600Y282360D01*
X443100Y282193D01*
X443350Y281777D01*
G01X442350Y280360D02*
X440683D01*
G01X447700Y277360D02*
X447200Y277443D01*
X446700Y277777D01*
X446367Y278360D01*
X446200Y279027D01*
X446367Y279693D01*
X446700Y280277D01*
X447200Y280610D01*
X447700Y280693D01*
X448200Y280610D01*
X448700Y280277D01*
X449033Y279693D01*
X449117Y279027D01*
X449033Y278360D01*
X448700Y277777D01*
X448200Y277443D01*
X447700Y277360D01*
G01X452133D02*
Y280693D01*
G01Y280027D02*
X452550Y280360D01*
X452967Y280610D01*
X453550Y280693D01*
X453967Y280610D01*
X454467Y280360D01*
G01X464500Y277360D02*
X464000Y277443D01*
X463500Y277777D01*
X463167Y278360D01*
X463000Y279027D01*
X463167Y279693D01*
X463500Y280277D01*
X464000Y280610D01*
X464500Y280693D01*
X465000Y280610D01*
X465500Y280277D01*
X465833Y279693D01*
X465917Y279027D01*
X465833Y278360D01*
X465500Y277777D01*
X465000Y277443D01*
X464500Y277360D01*
G01X468683Y280693D02*
Y278360D01*
X469017Y277777D01*
X469517Y277443D01*
X470100Y277360D01*
X470683Y277443D01*
X471183Y277777D01*
X471517Y278360D01*
G01Y277360D02*
Y280693D01*
G01X475700Y282360D02*
Y277360D01*
G01X474533Y280693D02*
X476867D01*
G01X480050Y279610D02*
X482717D01*
X482467Y280193D01*
X482050Y280527D01*
X481467Y280693D01*
X480883Y280610D01*
X480383Y280360D01*
X480050Y279777D01*
X479883Y279277D01*
Y278777D01*
X480050Y278277D01*
X480467Y277777D01*
X480967Y277443D01*
X481550Y277360D01*
X482133Y277527D01*
X482717Y278027D01*
G01X485733Y277360D02*
Y280693D01*
G01Y280027D02*
X486150Y280360D01*
X486567Y280610D01*
X487150Y280693D01*
X487567Y280610D01*
X488067Y280360D01*
G01X499600Y277360D02*
Y280693D01*
G01Y280110D02*
X499267Y280443D01*
X498767Y280610D01*
X498183Y280693D01*
X497600Y280527D01*
X497100Y280193D01*
X496767Y279693D01*
X496600Y279027D01*
X496767Y278360D01*
X497100Y277860D01*
X497600Y277527D01*
X498183Y277360D01*
X498767Y277443D01*
X499267Y277693D01*
X499600Y278027D01*
G01X502283Y277360D02*
Y280693D01*
G01Y279860D02*
X502617Y280277D01*
X503117Y280610D01*
X503783Y280693D01*
X504367Y280610D01*
X504867Y280277D01*
X505117Y279693D01*
Y277360D01*
G01X510800Y282360D02*
Y277360D01*
G01Y278110D02*
X510467Y277693D01*
X509967Y277443D01*
X509383Y277360D01*
X508717Y277527D01*
X508217Y277943D01*
X507883Y278443D01*
X507800Y279027D01*
X507883Y279610D01*
X508217Y280110D01*
X508717Y280527D01*
X509383Y280693D01*
X509967Y280610D01*
X510383Y280443D01*
X510800Y280110D01*
G01X520500Y280693D02*
Y277360D01*
G01Y282027D02*
X520333Y282110D01*
Y282277D01*
X520500Y282360D01*
X520667Y282277D01*
Y282110D01*
X520500Y282027D01*
G01X524683Y277360D02*
Y280693D01*
G01Y279860D02*
X525017Y280277D01*
X525517Y280610D01*
X526183Y280693D01*
X526767Y280610D01*
X527267Y280277D01*
X527517Y279693D01*
Y277360D01*
G01X530283D02*
Y280693D01*
G01Y279860D02*
X530617Y280277D01*
X531117Y280610D01*
X531783Y280693D01*
X532367Y280610D01*
X532867Y280277D01*
X533117Y279693D01*
Y277360D01*
G01X536050Y279610D02*
X538717D01*
X538467Y280193D01*
X538050Y280527D01*
X537467Y280693D01*
X536883Y280610D01*
X536383Y280360D01*
X536050Y279777D01*
X535883Y279277D01*
Y278777D01*
X536050Y278277D01*
X536467Y277777D01*
X536967Y277443D01*
X537550Y277360D01*
X538133Y277527D01*
X538717Y278027D01*
G01X541733Y277360D02*
Y280693D01*
G01Y280027D02*
X542150Y280360D01*
X542567Y280610D01*
X543150Y280693D01*
X543567Y280610D01*
X544067Y280360D01*
G01X554100Y277360D02*
Y282360D01*
G01X561200Y277360D02*
Y280693D01*
G01Y280110D02*
X560867Y280443D01*
X560367Y280610D01*
X559783Y280693D01*
X559200Y280527D01*
X558700Y280193D01*
X558367Y279693D01*
X558200Y279027D01*
X558367Y278360D01*
X558700Y277860D01*
X559200Y277527D01*
X559783Y277360D01*
X560367Y277443D01*
X560867Y277693D01*
X561200Y278027D01*
G01X564050Y277943D02*
X564467Y277610D01*
X565050Y277360D01*
X565550D01*
X566050Y277527D01*
X566383Y277777D01*
X566550Y278110D01*
X566467Y278610D01*
X566133Y278860D01*
X564633Y279360D01*
X564300Y279943D01*
X564467Y280360D01*
X564800Y280610D01*
X565300Y280693D01*
X565800Y280610D01*
X566300Y280360D01*
G01X569650Y279610D02*
X572317D01*
X572067Y280193D01*
X571650Y280527D01*
X571067Y280693D01*
X570483Y280610D01*
X569983Y280360D01*
X569650Y279777D01*
X569483Y279277D01*
Y278777D01*
X569650Y278277D01*
X570067Y277777D01*
X570567Y277443D01*
X571150Y277360D01*
X571733Y277527D01*
X572317Y278027D01*
G01X575333Y277360D02*
Y280693D01*
G01Y280027D02*
X575750Y280360D01*
X576167Y280610D01*
X576750Y280693D01*
X577167Y280610D01*
X577667Y280360D01*
G01X361117Y328537D02*
X360717Y328737D01*
X360250Y328870D01*
X359717D01*
X359117Y328670D01*
X358650Y328337D01*
X358317Y327937D01*
X358050Y327270D01*
X357983Y326670D01*
X358117Y326070D01*
X358317Y325670D01*
X358717Y325270D01*
X359183Y325003D01*
X359650Y324870D01*
X360117D01*
X360583Y325003D01*
X360983Y325203D01*
X361317Y325470D01*
G01X401827Y295540D02*
X403910Y300540D01*
X405993Y295540D01*
G01X405243Y297290D02*
X402577D01*
G01X408093Y295540D02*
Y298873D01*
G01Y298040D02*
X408427Y298457D01*
X408927Y298790D01*
X409593Y298873D01*
X410177Y298790D01*
X410677Y298457D01*
X410927Y297873D01*
Y295540D01*
G01X413943Y294290D02*
X414527Y293957D01*
X415193Y293873D01*
X415777Y293957D01*
X416277Y294373D01*
X416610Y294957D01*
Y298873D01*
G01Y298207D02*
X416277Y298540D01*
X415777Y298790D01*
X415193Y298873D01*
X414527Y298707D01*
X414110Y298373D01*
X413777Y297790D01*
X413610Y297207D01*
X413693Y296707D01*
X414027Y296123D01*
X414527Y295707D01*
X415193Y295540D01*
X415693Y295623D01*
X416277Y295957D01*
X416610Y296290D01*
G01X420710Y295540D02*
Y300540D01*
G01X425060Y297790D02*
X427727D01*
X427477Y298373D01*
X427060Y298707D01*
X426477Y298873D01*
X425893Y298790D01*
X425393Y298540D01*
X425060Y297957D01*
X424893Y297457D01*
Y296957D01*
X425060Y296457D01*
X425477Y295957D01*
X425977Y295623D01*
X426560Y295540D01*
X427143Y295707D01*
X427727Y296207D01*
G01X431493Y293873D02*
X430660Y294707D01*
X430243Y295540D01*
Y298873D01*
X430660Y299707D01*
X431493Y300540D01*
G01X449127Y293873D02*
X449960Y294707D01*
X450377Y295540D01*
Y298873D01*
X449960Y299707D01*
X449127Y300540D01*
G01X401777Y331927D02*
X402110Y332177D01*
X402360Y332593D01*
X402527Y333177D01*
X402360Y333677D01*
X402027Y334010D01*
X401443Y334260D01*
X399193D01*
Y329260D01*
X401943D01*
X402527Y329593D01*
X402860Y330093D01*
X403027Y330677D01*
X402860Y331260D01*
X402360Y331760D01*
X401777Y331927D01*
X399193D01*
G01X405210Y329093D02*
X408210Y334260D01*
G01X410227Y329260D02*
X412310Y334260D01*
X414393Y329260D01*
G01X413643Y331010D02*
X410977D01*
G01X395000Y305500D02*
X694500D01*
G01X395000Y337500D02*
X694500D01*
G01X401520Y268213D02*
X403020Y264880D01*
X404520Y268213D01*
G01X408620D02*
Y264880D01*
G01Y269547D02*
X408453Y269630D01*
Y269797D01*
X408620Y269880D01*
X408787Y269797D01*
Y269630D01*
X408620Y269547D01*
G01X415720Y264880D02*
Y268213D01*
G01Y267630D02*
X415387Y267963D01*
X414887Y268130D01*
X414303Y268213D01*
X413720Y268047D01*
X413220Y267713D01*
X412887Y267213D01*
X412720Y266547D01*
X412887Y265880D01*
X413220Y265380D01*
X413720Y265047D01*
X414303Y264880D01*
X414887Y264963D01*
X415387Y265213D01*
X415720Y265547D01*
G01X401067Y277360D02*
Y282360D01*
X402733D01*
X403400Y282110D01*
X403900Y281777D01*
X404317Y281277D01*
X404650Y280693D01*
X404733Y279860D01*
X404650Y279027D01*
X404317Y278443D01*
X403900Y277943D01*
X403400Y277610D01*
X402733Y277360D01*
X401067D01*
G01X408500Y280693D02*
Y277360D01*
G01Y282027D02*
X408333Y282110D01*
Y282277D01*
X408500Y282360D01*
X408667Y282277D01*
Y282110D01*
X408500Y282027D01*
G01X411600Y277360D02*
Y280693D01*
G01Y279777D02*
X411850Y280193D01*
X412267Y280527D01*
X412850Y280693D01*
X413433Y280527D01*
X413850Y280193D01*
X414100Y279777D01*
Y277360D01*
G01Y279777D02*
X414350Y280193D01*
X414767Y280527D01*
X415350Y280693D01*
X415933Y280527D01*
X416350Y280193D01*
X416600Y279693D01*
Y277360D01*
G01X418200Y275693D02*
Y280693D01*
G01Y279943D02*
X418617Y280360D01*
X419033Y280610D01*
X419700Y280693D01*
X420283Y280610D01*
X420867Y280193D01*
X421117Y279610D01*
X421200Y279027D01*
X421117Y278443D01*
X420867Y277860D01*
X420367Y277527D01*
X419700Y277360D01*
X419117Y277443D01*
X418533Y277693D01*
X418200Y278027D01*
G01X425300Y277360D02*
Y282360D01*
G01X429650Y279610D02*
X432317D01*
X432067Y280193D01*
X431650Y280527D01*
X431067Y280693D01*
X430483Y280610D01*
X429983Y280360D01*
X429650Y279777D01*
X429483Y279277D01*
Y278777D01*
X429650Y278277D01*
X430067Y277777D01*
X430567Y277443D01*
X431150Y277360D01*
X431733Y277527D01*
X432317Y278027D01*
G01X441600Y277360D02*
Y281610D01*
X441767Y282027D01*
X442100Y282277D01*
X442600Y282360D01*
X443100Y282193D01*
X443350Y281777D01*
G01X442350Y280360D02*
X440683D01*
G01X447700Y277360D02*
X447200Y277443D01*
X446700Y277777D01*
X446367Y278360D01*
X446200Y279027D01*
X446367Y279693D01*
X446700Y280277D01*
X447200Y280610D01*
X447700Y280693D01*
X448200Y280610D01*
X448700Y280277D01*
X449033Y279693D01*
X449117Y279027D01*
X449033Y278360D01*
X448700Y277777D01*
X448200Y277443D01*
X447700Y277360D01*
G01X452133D02*
Y280693D01*
G01Y280027D02*
X452550Y280360D01*
X452967Y280610D01*
X453550Y280693D01*
X453967Y280610D01*
X454467Y280360D01*
G01X464500Y277360D02*
X464000Y277443D01*
X463500Y277777D01*
X463167Y278360D01*
X463000Y279027D01*
X463167Y279693D01*
X463500Y280277D01*
X464000Y280610D01*
X464500Y280693D01*
X465000Y280610D01*
X465500Y280277D01*
X465833Y279693D01*
X465917Y279027D01*
X465833Y278360D01*
X465500Y277777D01*
X465000Y277443D01*
X464500Y277360D01*
G01X468683Y280693D02*
Y278360D01*
X469017Y277777D01*
X469517Y277443D01*
X470100Y277360D01*
X470683Y277443D01*
X471183Y277777D01*
X471517Y278360D01*
G01Y277360D02*
Y280693D01*
G01X475700Y282360D02*
Y277360D01*
G01X474533Y280693D02*
X476867D01*
G01X480050Y279610D02*
X482717D01*
X482467Y280193D01*
X482050Y280527D01*
X481467Y280693D01*
X480883Y280610D01*
X480383Y280360D01*
X480050Y279777D01*
X479883Y279277D01*
Y278777D01*
X480050Y278277D01*
X480467Y277777D01*
X480967Y277443D01*
X481550Y277360D01*
X482133Y277527D01*
X482717Y278027D01*
G01X485733Y277360D02*
Y280693D01*
G01Y280027D02*
X486150Y280360D01*
X486567Y280610D01*
X487150Y280693D01*
X487567Y280610D01*
X488067Y280360D01*
G01X499600Y277360D02*
Y280693D01*
G01Y280110D02*
X499267Y280443D01*
X498767Y280610D01*
X498183Y280693D01*
X497600Y280527D01*
X497100Y280193D01*
X496767Y279693D01*
X496600Y279027D01*
X496767Y278360D01*
X497100Y277860D01*
X497600Y277527D01*
X498183Y277360D01*
X498767Y277443D01*
X499267Y277693D01*
X499600Y278027D01*
G01X502283Y277360D02*
Y280693D01*
G01Y279860D02*
X502617Y280277D01*
X503117Y280610D01*
X503783Y280693D01*
X504367Y280610D01*
X504867Y280277D01*
X505117Y279693D01*
Y277360D01*
G01X510800Y282360D02*
Y277360D01*
G01Y278110D02*
X510467Y277693D01*
X509967Y277443D01*
X509383Y277360D01*
X508717Y277527D01*
X508217Y277943D01*
X507883Y278443D01*
X507800Y279027D01*
X507883Y279610D01*
X508217Y280110D01*
X508717Y280527D01*
X509383Y280693D01*
X509967Y280610D01*
X510383Y280443D01*
X510800Y280110D01*
G01X520500Y280693D02*
Y277360D01*
G01Y282027D02*
X520333Y282110D01*
Y282277D01*
X520500Y282360D01*
X520667Y282277D01*
Y282110D01*
X520500Y282027D01*
G01X524683Y277360D02*
Y280693D01*
G01Y279860D02*
X525017Y280277D01*
X525517Y280610D01*
X526183Y280693D01*
X526767Y280610D01*
X527267Y280277D01*
X527517Y279693D01*
Y277360D01*
G01X530283D02*
Y280693D01*
G01Y279860D02*
X530617Y280277D01*
X531117Y280610D01*
X531783Y280693D01*
X532367Y280610D01*
X532867Y280277D01*
X533117Y279693D01*
Y277360D01*
G01X536050Y279610D02*
X538717D01*
X538467Y280193D01*
X538050Y280527D01*
X537467Y280693D01*
X536883Y280610D01*
X536383Y280360D01*
X536050Y279777D01*
X535883Y279277D01*
Y278777D01*
X536050Y278277D01*
X536467Y277777D01*
X536967Y277443D01*
X537550Y277360D01*
X538133Y277527D01*
X538717Y278027D01*
G01X541733Y277360D02*
Y280693D01*
G01Y280027D02*
X542150Y280360D01*
X542567Y280610D01*
X543150Y280693D01*
X543567Y280610D01*
X544067Y280360D01*
G01X554100Y277360D02*
Y282360D01*
G01X561200Y277360D02*
Y280693D01*
G01Y280110D02*
X560867Y280443D01*
X560367Y280610D01*
X559783Y280693D01*
X559200Y280527D01*
X558700Y280193D01*
X558367Y279693D01*
X558200Y279027D01*
X558367Y278360D01*
X558700Y277860D01*
X559200Y277527D01*
X559783Y277360D01*
X560367Y277443D01*
X560867Y277693D01*
X561200Y278027D01*
G01X564050Y277943D02*
X564467Y277610D01*
X565050Y277360D01*
X565550D01*
X566050Y277527D01*
X566383Y277777D01*
X566550Y278110D01*
X566467Y278610D01*
X566133Y278860D01*
X564633Y279360D01*
X564300Y279943D01*
X564467Y280360D01*
X564800Y280610D01*
X565300Y280693D01*
X565800Y280610D01*
X566300Y280360D01*
G01X569650Y279610D02*
X572317D01*
X572067Y280193D01*
X571650Y280527D01*
X571067Y280693D01*
X570483Y280610D01*
X569983Y280360D01*
X569650Y279777D01*
X569483Y279277D01*
Y278777D01*
X569650Y278277D01*
X570067Y277777D01*
X570567Y277443D01*
X571150Y277360D01*
X571733Y277527D01*
X572317Y278027D01*
G01X575333Y277360D02*
Y280693D01*
G01Y280027D02*
X575750Y280360D01*
X576167Y280610D01*
X576750Y280693D01*
X577167Y280610D01*
X577667Y280360D01*
G01X361117Y328537D02*
X360717Y328737D01*
X360250Y328870D01*
X359717D01*
X359117Y328670D01*
X358650Y328337D01*
X358317Y327937D01*
X358050Y327270D01*
X357983Y326670D01*
X358117Y326070D01*
X358317Y325670D01*
X358717Y325270D01*
X359183Y325003D01*
X359650Y324870D01*
X360117D01*
X360583Y325003D01*
X360983Y325203D01*
X361317Y325470D01*
G01X401827Y295540D02*
X403910Y300540D01*
X405993Y295540D01*
G01X405243Y297290D02*
X402577D01*
G01X408093Y295540D02*
Y298873D01*
G01Y298040D02*
X408427Y298457D01*
X408927Y298790D01*
X409593Y298873D01*
X410177Y298790D01*
X410677Y298457D01*
X410927Y297873D01*
Y295540D01*
G01X413943Y294290D02*
X414527Y293957D01*
X415193Y293873D01*
X415777Y293957D01*
X416277Y294373D01*
X416610Y294957D01*
Y298873D01*
G01Y298207D02*
X416277Y298540D01*
X415777Y298790D01*
X415193Y298873D01*
X414527Y298707D01*
X414110Y298373D01*
X413777Y297790D01*
X413610Y297207D01*
X413693Y296707D01*
X414027Y296123D01*
X414527Y295707D01*
X415193Y295540D01*
X415693Y295623D01*
X416277Y295957D01*
X416610Y296290D01*
G01X420710Y295540D02*
Y300540D01*
G01X425060Y297790D02*
X427727D01*
X427477Y298373D01*
X427060Y298707D01*
X426477Y298873D01*
X425893Y298790D01*
X425393Y298540D01*
X425060Y297957D01*
X424893Y297457D01*
Y296957D01*
X425060Y296457D01*
X425477Y295957D01*
X425977Y295623D01*
X426560Y295540D01*
X427143Y295707D01*
X427727Y296207D01*
G01X431493Y293873D02*
X430660Y294707D01*
X430243Y295540D01*
Y298873D01*
X430660Y299707D01*
X431493Y300540D01*
G01X449127Y293873D02*
X449960Y294707D01*
X450377Y295540D01*
Y298873D01*
X449960Y299707D01*
X449127Y300540D01*
G01X401777Y331927D02*
X402110Y332177D01*
X402360Y332593D01*
X402527Y333177D01*
X402360Y333677D01*
X402027Y334010D01*
X401443Y334260D01*
X399193D01*
Y329260D01*
X401943D01*
X402527Y329593D01*
X402860Y330093D01*
X403027Y330677D01*
X402860Y331260D01*
X402360Y331760D01*
X401777Y331927D01*
X399193D01*
G01X405210Y329093D02*
X408210Y334260D01*
G01X410227Y329260D02*
X412310Y334260D01*
X414393Y329260D01*
G01X413643Y331010D02*
X410977D01*
G01X395000Y305500D02*
X694500D01*
G01X395000Y337500D02*
X694500D01*
G01X400633Y358960D02*
Y353960D01*
X403967D01*
G01X409400D02*
Y357293D01*
G01Y356710D02*
X409067Y357043D01*
X408567Y357210D01*
X407983Y357293D01*
X407400Y357127D01*
X406900Y356793D01*
X406567Y356293D01*
X406400Y355627D01*
X406567Y354960D01*
X406900Y354460D01*
X407400Y354127D01*
X407983Y353960D01*
X408567Y354043D01*
X409067Y354293D01*
X409400Y354627D01*
G01X412250Y354543D02*
X412667Y354210D01*
X413250Y353960D01*
X413750D01*
X414250Y354127D01*
X414583Y354377D01*
X414750Y354710D01*
X414667Y355210D01*
X414333Y355460D01*
X412833Y355960D01*
X412500Y356543D01*
X412667Y356960D01*
X413000Y357210D01*
X413500Y357293D01*
X414000Y357210D01*
X414500Y356960D01*
G01X417850Y356210D02*
X420517D01*
X420267Y356793D01*
X419850Y357127D01*
X419267Y357293D01*
X418683Y357210D01*
X418183Y356960D01*
X417850Y356377D01*
X417683Y355877D01*
Y355377D01*
X417850Y354877D01*
X418267Y354377D01*
X418767Y354043D01*
X419350Y353960D01*
X419933Y354127D01*
X420517Y354627D01*
G01X423533Y353960D02*
Y357293D01*
G01Y356627D02*
X423950Y356960D01*
X424367Y357210D01*
X424950Y357293D01*
X425367Y357210D01*
X425867Y356960D01*
G01X434400Y357293D02*
X435900Y353960D01*
X437400Y357293D01*
G01X441500D02*
Y353960D01*
G01Y358627D02*
X441333Y358710D01*
Y358877D01*
X441500Y358960D01*
X441667Y358877D01*
Y358710D01*
X441500Y358627D01*
G01X448600Y353960D02*
Y357293D01*
G01Y356710D02*
X448267Y357043D01*
X447767Y357210D01*
X447183Y357293D01*
X446600Y357127D01*
X446100Y356793D01*
X445767Y356293D01*
X445600Y355627D01*
X445767Y354960D01*
X446100Y354460D01*
X446600Y354127D01*
X447183Y353960D01*
X447767Y354043D01*
X448267Y354293D01*
X448600Y354627D01*
G01X457050Y354543D02*
X457467Y354210D01*
X458050Y353960D01*
X458550D01*
X459050Y354127D01*
X459383Y354377D01*
X459550Y354710D01*
X459467Y355210D01*
X459133Y355460D01*
X457633Y355960D01*
X457300Y356543D01*
X457467Y356960D01*
X457800Y357210D01*
X458300Y357293D01*
X458800Y357210D01*
X459300Y356960D01*
G01X463900Y357293D02*
Y353960D01*
G01Y358627D02*
X463733Y358710D01*
Y358877D01*
X463900Y358960D01*
X464067Y358877D01*
Y358710D01*
X463900Y358627D01*
G01X468250Y357293D02*
X470750D01*
X468250Y353960D01*
X470750D01*
G01X473850Y356210D02*
X476517D01*
X476267Y356793D01*
X475850Y357127D01*
X475267Y357293D01*
X474683Y357210D01*
X474183Y356960D01*
X473850Y356377D01*
X473683Y355877D01*
Y355377D01*
X473850Y354877D01*
X474267Y354377D01*
X474767Y354043D01*
X475350Y353960D01*
X475933Y354127D01*
X476517Y354627D01*
G01X484217Y357293D02*
X485217Y353960D01*
X486300Y357293D01*
X487383Y353960D01*
X488383Y357293D01*
G01X491900D02*
Y353960D01*
G01Y358627D02*
X491733Y358710D01*
Y358877D01*
X491900Y358960D01*
X492067Y358877D01*
Y358710D01*
X491900Y358627D01*
G01X497500Y358960D02*
Y353960D01*
G01X496333Y357293D02*
X498667D01*
G01X501683Y353960D02*
Y358960D01*
G01Y356543D02*
X502100Y356960D01*
X502517Y357210D01*
X503183Y357293D01*
X503683Y357210D01*
X504267Y356877D01*
X504517Y356377D01*
Y353960D01*
G01X508700D02*
X508200Y354043D01*
X507700Y354377D01*
X507367Y354960D01*
X507200Y355627D01*
X507367Y356293D01*
X507700Y356877D01*
X508200Y357210D01*
X508700Y357293D01*
X509200Y357210D01*
X509700Y356877D01*
X510033Y356293D01*
X510117Y355627D01*
X510033Y354960D01*
X509700Y354377D01*
X509200Y354043D01*
X508700Y353960D01*
G01X512883Y357293D02*
Y354960D01*
X513217Y354377D01*
X513717Y354043D01*
X514300Y353960D01*
X514883Y354043D01*
X515383Y354377D01*
X515717Y354960D01*
G01Y353960D02*
Y357293D01*
G01X519900Y358960D02*
Y353960D01*
G01X518733Y357293D02*
X521067D01*
G01X529600Y352293D02*
Y357293D01*
G01Y356543D02*
X530017Y356960D01*
X530433Y357210D01*
X531100Y357293D01*
X531683Y357210D01*
X532267Y356793D01*
X532517Y356210D01*
X532600Y355627D01*
X532517Y355043D01*
X532267Y354460D01*
X531767Y354127D01*
X531100Y353960D01*
X530517Y354043D01*
X529933Y354293D01*
X529600Y354627D01*
G01X536700Y353960D02*
Y358960D01*
G01X543800Y353960D02*
Y357293D01*
G01Y356710D02*
X543467Y357043D01*
X542967Y357210D01*
X542383Y357293D01*
X541800Y357127D01*
X541300Y356793D01*
X540967Y356293D01*
X540800Y355627D01*
X540967Y354960D01*
X541300Y354460D01*
X541800Y354127D01*
X542383Y353960D01*
X542967Y354043D01*
X543467Y354293D01*
X543800Y354627D01*
G01X547900Y358960D02*
Y353960D01*
G01X546733Y357293D02*
X549067D01*
G01X553500D02*
Y353960D01*
G01Y358627D02*
X553333Y358710D01*
Y358877D01*
X553500Y358960D01*
X553667Y358877D01*
Y358710D01*
X553500Y358627D01*
G01X557683Y353960D02*
Y357293D01*
G01Y356460D02*
X558017Y356877D01*
X558517Y357210D01*
X559183Y357293D01*
X559767Y357210D01*
X560267Y356877D01*
X560517Y356293D01*
Y353960D01*
G01X563533Y352710D02*
X564117Y352377D01*
X564783Y352293D01*
X565367Y352377D01*
X565867Y352793D01*
X566200Y353377D01*
Y357293D01*
G01Y356627D02*
X565867Y356960D01*
X565367Y357210D01*
X564783Y357293D01*
X564117Y357127D01*
X563700Y356793D01*
X563367Y356210D01*
X563200Y355627D01*
X563283Y355127D01*
X563617Y354543D01*
X564117Y354127D01*
X564783Y353960D01*
X565283Y354043D01*
X565867Y354377D01*
X566200Y354710D01*
G01X575483Y352293D02*
X574650Y353127D01*
X574233Y353960D01*
Y357293D01*
X574650Y358127D01*
X575483Y358960D01*
G01X582167Y356627D02*
X582500Y356877D01*
X582750Y357293D01*
X582917Y357877D01*
X582750Y358377D01*
X582417Y358710D01*
X581833Y358960D01*
X579583D01*
Y353960D01*
X582333D01*
X582917Y354293D01*
X583250Y354793D01*
X583417Y355377D01*
X583250Y355960D01*
X582750Y356460D01*
X582167Y356627D01*
X579583D01*
G01X587517Y352293D02*
X588350Y353127D01*
X588767Y353960D01*
Y357293D01*
X588350Y358127D01*
X587517Y358960D01*
G01X400633D02*
Y353960D01*
X403967D01*
G01X409400D02*
Y357293D01*
G01Y356710D02*
X409067Y357043D01*
X408567Y357210D01*
X407983Y357293D01*
X407400Y357127D01*
X406900Y356793D01*
X406567Y356293D01*
X406400Y355627D01*
X406567Y354960D01*
X406900Y354460D01*
X407400Y354127D01*
X407983Y353960D01*
X408567Y354043D01*
X409067Y354293D01*
X409400Y354627D01*
G01X412250Y354543D02*
X412667Y354210D01*
X413250Y353960D01*
X413750D01*
X414250Y354127D01*
X414583Y354377D01*
X414750Y354710D01*
X414667Y355210D01*
X414333Y355460D01*
X412833Y355960D01*
X412500Y356543D01*
X412667Y356960D01*
X413000Y357210D01*
X413500Y357293D01*
X414000Y357210D01*
X414500Y356960D01*
G01X417850Y356210D02*
X420517D01*
X420267Y356793D01*
X419850Y357127D01*
X419267Y357293D01*
X418683Y357210D01*
X418183Y356960D01*
X417850Y356377D01*
X417683Y355877D01*
Y355377D01*
X417850Y354877D01*
X418267Y354377D01*
X418767Y354043D01*
X419350Y353960D01*
X419933Y354127D01*
X420517Y354627D01*
G01X423533Y353960D02*
Y357293D01*
G01Y356627D02*
X423950Y356960D01*
X424367Y357210D01*
X424950Y357293D01*
X425367Y357210D01*
X425867Y356960D01*
G01X434400Y357293D02*
X435900Y353960D01*
X437400Y357293D01*
G01X441500D02*
Y353960D01*
G01Y358627D02*
X441333Y358710D01*
Y358877D01*
X441500Y358960D01*
X441667Y358877D01*
Y358710D01*
X441500Y358627D01*
G01X448600Y353960D02*
Y357293D01*
G01Y356710D02*
X448267Y357043D01*
X447767Y357210D01*
X447183Y357293D01*
X446600Y357127D01*
X446100Y356793D01*
X445767Y356293D01*
X445600Y355627D01*
X445767Y354960D01*
X446100Y354460D01*
X446600Y354127D01*
X447183Y353960D01*
X447767Y354043D01*
X448267Y354293D01*
X448600Y354627D01*
G01X457050Y354543D02*
X457467Y354210D01*
X458050Y353960D01*
X458550D01*
X459050Y354127D01*
X459383Y354377D01*
X459550Y354710D01*
X459467Y355210D01*
X459133Y355460D01*
X457633Y355960D01*
X457300Y356543D01*
X457467Y356960D01*
X457800Y357210D01*
X458300Y357293D01*
X458800Y357210D01*
X459300Y356960D01*
G01X463900Y357293D02*
Y353960D01*
G01Y358627D02*
X463733Y358710D01*
Y358877D01*
X463900Y358960D01*
X464067Y358877D01*
Y358710D01*
X463900Y358627D01*
G01X468250Y357293D02*
X470750D01*
X468250Y353960D01*
X470750D01*
G01X473850Y356210D02*
X476517D01*
X476267Y356793D01*
X475850Y357127D01*
X475267Y357293D01*
X474683Y357210D01*
X474183Y356960D01*
X473850Y356377D01*
X473683Y355877D01*
Y355377D01*
X473850Y354877D01*
X474267Y354377D01*
X474767Y354043D01*
X475350Y353960D01*
X475933Y354127D01*
X476517Y354627D01*
G01X484217Y357293D02*
X485217Y353960D01*
X486300Y357293D01*
X487383Y353960D01*
X488383Y357293D01*
G01X491900D02*
Y353960D01*
G01Y358627D02*
X491733Y358710D01*
Y358877D01*
X491900Y358960D01*
X492067Y358877D01*
Y358710D01*
X491900Y358627D01*
G01X497500Y358960D02*
Y353960D01*
G01X496333Y357293D02*
X498667D01*
G01X501683Y353960D02*
Y358960D01*
G01Y356543D02*
X502100Y356960D01*
X502517Y357210D01*
X503183Y357293D01*
X503683Y357210D01*
X504267Y356877D01*
X504517Y356377D01*
Y353960D01*
G01X508700D02*
X508200Y354043D01*
X507700Y354377D01*
X507367Y354960D01*
X507200Y355627D01*
X507367Y356293D01*
X507700Y356877D01*
X508200Y357210D01*
X508700Y357293D01*
X509200Y357210D01*
X509700Y356877D01*
X510033Y356293D01*
X510117Y355627D01*
X510033Y354960D01*
X509700Y354377D01*
X509200Y354043D01*
X508700Y353960D01*
G01X512883Y357293D02*
Y354960D01*
X513217Y354377D01*
X513717Y354043D01*
X514300Y353960D01*
X514883Y354043D01*
X515383Y354377D01*
X515717Y354960D01*
G01Y353960D02*
Y357293D01*
G01X519900Y358960D02*
Y353960D01*
G01X518733Y357293D02*
X521067D01*
G01X529600Y352293D02*
Y357293D01*
G01Y356543D02*
X530017Y356960D01*
X530433Y357210D01*
X531100Y357293D01*
X531683Y357210D01*
X532267Y356793D01*
X532517Y356210D01*
X532600Y355627D01*
X532517Y355043D01*
X532267Y354460D01*
X531767Y354127D01*
X531100Y353960D01*
X530517Y354043D01*
X529933Y354293D01*
X529600Y354627D01*
G01X536700Y353960D02*
Y358960D01*
G01X543800Y353960D02*
Y357293D01*
G01Y356710D02*
X543467Y357043D01*
X542967Y357210D01*
X542383Y357293D01*
X541800Y357127D01*
X541300Y356793D01*
X540967Y356293D01*
X540800Y355627D01*
X540967Y354960D01*
X541300Y354460D01*
X541800Y354127D01*
X542383Y353960D01*
X542967Y354043D01*
X543467Y354293D01*
X543800Y354627D01*
G01X547900Y358960D02*
Y353960D01*
G01X546733Y357293D02*
X549067D01*
G01X553500D02*
Y353960D01*
G01Y358627D02*
X553333Y358710D01*
Y358877D01*
X553500Y358960D01*
X553667Y358877D01*
Y358710D01*
X553500Y358627D01*
G01X557683Y353960D02*
Y357293D01*
G01Y356460D02*
X558017Y356877D01*
X558517Y357210D01*
X559183Y357293D01*
X559767Y357210D01*
X560267Y356877D01*
X560517Y356293D01*
Y353960D01*
G01X563533Y352710D02*
X564117Y352377D01*
X564783Y352293D01*
X565367Y352377D01*
X565867Y352793D01*
X566200Y353377D01*
Y357293D01*
G01Y356627D02*
X565867Y356960D01*
X565367Y357210D01*
X564783Y357293D01*
X564117Y357127D01*
X563700Y356793D01*
X563367Y356210D01*
X563200Y355627D01*
X563283Y355127D01*
X563617Y354543D01*
X564117Y354127D01*
X564783Y353960D01*
X565283Y354043D01*
X565867Y354377D01*
X566200Y354710D01*
G01X575483Y352293D02*
X574650Y353127D01*
X574233Y353960D01*
Y357293D01*
X574650Y358127D01*
X575483Y358960D01*
G01X582167Y356627D02*
X582500Y356877D01*
X582750Y357293D01*
X582917Y357877D01*
X582750Y358377D01*
X582417Y358710D01*
X581833Y358960D01*
X579583D01*
Y353960D01*
X582333D01*
X582917Y354293D01*
X583250Y354793D01*
X583417Y355377D01*
X583250Y355960D01*
X582750Y356460D01*
X582167Y356627D01*
X579583D01*
G01X587517Y352293D02*
X588350Y353127D01*
X588767Y353960D01*
Y357293D01*
X588350Y358127D01*
X587517Y358960D01*
G01X404500Y666833D02*
Y663500D01*
G01Y668167D02*
X404333Y668250D01*
Y668417D01*
X404500Y668500D01*
X404667Y668417D01*
Y668250D01*
X404500Y668167D01*
G01X410100Y668500D02*
Y663500D01*
G01X408933Y666833D02*
X411267D01*
G01X414450Y665750D02*
X417117D01*
X416867Y666333D01*
X416450Y666667D01*
X415867Y666833D01*
X415283Y666750D01*
X414783Y666500D01*
X414450Y665917D01*
X414283Y665417D01*
Y664917D01*
X414450Y664417D01*
X414867Y663917D01*
X415367Y663583D01*
X415950Y663500D01*
X416533Y663667D01*
X417117Y664167D01*
G01X418800Y663500D02*
Y666833D01*
G01Y665917D02*
X419050Y666333D01*
X419467Y666667D01*
X420050Y666833D01*
X420633Y666667D01*
X421050Y666333D01*
X421300Y665917D01*
Y663500D01*
G01Y665917D02*
X421550Y666333D01*
X421967Y666667D01*
X422550Y666833D01*
X423133Y666667D01*
X423550Y666333D01*
X423800Y665833D01*
Y663500D01*
G01X404500Y666833D02*
Y663500D01*
G01Y668167D02*
X404333Y668250D01*
Y668417D01*
X404500Y668500D01*
X404667Y668417D01*
Y668250D01*
X404500Y668167D01*
G01X410100Y668500D02*
Y663500D01*
G01X408933Y666833D02*
X411267D01*
G01X414450Y665750D02*
X417117D01*
X416867Y666333D01*
X416450Y666667D01*
X415867Y666833D01*
X415283Y666750D01*
X414783Y666500D01*
X414450Y665917D01*
X414283Y665417D01*
Y664917D01*
X414450Y664417D01*
X414867Y663917D01*
X415367Y663583D01*
X415950Y663500D01*
X416533Y663667D01*
X417117Y664167D01*
G01X418800Y663500D02*
Y666833D01*
G01Y665917D02*
X419050Y666333D01*
X419467Y666667D01*
X420050Y666833D01*
X420633Y666667D01*
X421050Y666333D01*
X421300Y665917D01*
Y663500D01*
G01Y665917D02*
X421550Y666333D01*
X421967Y666667D01*
X422550Y666833D01*
X423133Y666667D01*
X423550Y666333D01*
X423800Y665833D01*
Y663500D01*
G01X444197Y299927D02*
X443797Y300127D01*
X443330Y300260D01*
X442797D01*
X442197Y300060D01*
X441730Y299727D01*
X441397Y299327D01*
X441130Y298660D01*
X441063Y298060D01*
X441197Y297460D01*
X441397Y297060D01*
X441797Y296660D01*
X442263Y296393D01*
X442730Y296260D01*
X443197D01*
X443663Y296393D01*
X444063Y296593D01*
X444397Y296860D01*
G01X444197Y299927D02*
X443797Y300127D01*
X443330Y300260D01*
X442797D01*
X442197Y300060D01*
X441730Y299727D01*
X441397Y299327D01*
X441130Y298660D01*
X441063Y298060D01*
X441197Y297460D01*
X441397Y297060D01*
X441797Y296660D01*
X442263Y296393D01*
X442730Y296260D01*
X443197D01*
X443663Y296393D01*
X444063Y296593D01*
X444397Y296860D01*
G01X605333Y-65000D02*
Y-60000D01*
X607500Y-64167D01*
X609667Y-60000D01*
Y-65000D01*
G01X611683Y-61667D02*
Y-64000D01*
X612017Y-64583D01*
X612517Y-64917D01*
X613100Y-65000D01*
X613683Y-64917D01*
X614183Y-64583D01*
X614517Y-64000D01*
G01Y-65000D02*
Y-61667D01*
G01X617450Y-64417D02*
X617867Y-64750D01*
X618450Y-65000D01*
X618950D01*
X619450Y-64833D01*
X619783Y-64583D01*
X619950Y-64250D01*
X619867Y-63750D01*
X619533Y-63500D01*
X618033Y-63000D01*
X617700Y-62417D01*
X617867Y-62000D01*
X618200Y-61750D01*
X618700Y-61667D01*
X619200Y-61750D01*
X619700Y-62000D01*
G01X624300Y-60000D02*
Y-65000D01*
G01X623133Y-61667D02*
X625467D01*
G01X635000Y-65000D02*
Y-60750D01*
X635167Y-60333D01*
X635500Y-60083D01*
X636000Y-60000D01*
X636500Y-60167D01*
X636750Y-60583D01*
G01X635750Y-62000D02*
X634083D01*
G01X641100Y-65000D02*
X640600Y-64917D01*
X640100Y-64583D01*
X639767Y-64000D01*
X639600Y-63333D01*
X639767Y-62667D01*
X640100Y-62083D01*
X640600Y-61750D01*
X641100Y-61667D01*
X641600Y-61750D01*
X642100Y-62083D01*
X642433Y-62667D01*
X642517Y-63333D01*
X642433Y-64000D01*
X642100Y-64583D01*
X641600Y-64917D01*
X641100Y-65000D01*
G01X646700D02*
Y-60000D01*
G01X652300Y-65000D02*
Y-60000D01*
G01X657900Y-65000D02*
X657400Y-64917D01*
X656900Y-64583D01*
X656567Y-64000D01*
X656400Y-63333D01*
X656567Y-62667D01*
X656900Y-62083D01*
X657400Y-61750D01*
X657900Y-61667D01*
X658400Y-61750D01*
X658900Y-62083D01*
X659233Y-62667D01*
X659317Y-63333D01*
X659233Y-64000D01*
X658900Y-64583D01*
X658400Y-64917D01*
X657900Y-65000D01*
G01X661417Y-61667D02*
X662417Y-65000D01*
X663500Y-61667D01*
X664583Y-65000D01*
X665583Y-61667D01*
G01X595500Y-69500D02*
Y438000D01*
G01X605333Y-65000D02*
Y-60000D01*
X607500Y-64167D01*
X609667Y-60000D01*
Y-65000D01*
G01X611683Y-61667D02*
Y-64000D01*
X612017Y-64583D01*
X612517Y-64917D01*
X613100Y-65000D01*
X613683Y-64917D01*
X614183Y-64583D01*
X614517Y-64000D01*
G01Y-65000D02*
Y-61667D01*
G01X617450Y-64417D02*
X617867Y-64750D01*
X618450Y-65000D01*
X618950D01*
X619450Y-64833D01*
X619783Y-64583D01*
X619950Y-64250D01*
X619867Y-63750D01*
X619533Y-63500D01*
X618033Y-63000D01*
X617700Y-62417D01*
X617867Y-62000D01*
X618200Y-61750D01*
X618700Y-61667D01*
X619200Y-61750D01*
X619700Y-62000D01*
G01X624300Y-60000D02*
Y-65000D01*
G01X623133Y-61667D02*
X625467D01*
G01X635000Y-65000D02*
Y-60750D01*
X635167Y-60333D01*
X635500Y-60083D01*
X636000Y-60000D01*
X636500Y-60167D01*
X636750Y-60583D01*
G01X635750Y-62000D02*
X634083D01*
G01X641100Y-65000D02*
X640600Y-64917D01*
X640100Y-64583D01*
X639767Y-64000D01*
X639600Y-63333D01*
X639767Y-62667D01*
X640100Y-62083D01*
X640600Y-61750D01*
X641100Y-61667D01*
X641600Y-61750D01*
X642100Y-62083D01*
X642433Y-62667D01*
X642517Y-63333D01*
X642433Y-64000D01*
X642100Y-64583D01*
X641600Y-64917D01*
X641100Y-65000D01*
G01X646700D02*
Y-60000D01*
G01X652300Y-65000D02*
Y-60000D01*
G01X657900Y-65000D02*
X657400Y-64917D01*
X656900Y-64583D01*
X656567Y-64000D01*
X656400Y-63333D01*
X656567Y-62667D01*
X656900Y-62083D01*
X657400Y-61750D01*
X657900Y-61667D01*
X658400Y-61750D01*
X658900Y-62083D01*
X659233Y-62667D01*
X659317Y-63333D01*
X659233Y-64000D01*
X658900Y-64583D01*
X658400Y-64917D01*
X657900Y-65000D01*
G01X661417Y-61667D02*
X662417Y-65000D01*
X663500Y-61667D01*
X664583Y-65000D01*
X665583Y-61667D01*
G01X595500Y-69500D02*
Y438000D01*
G01X606583Y-1833D02*
X608583D01*
G01X607500Y-750D02*
Y-2917D01*
G01X611600Y-3667D02*
X614600Y1500D01*
G01X617617Y-1833D02*
X619783D01*
G01X624300Y-3500D02*
Y1500D01*
X623300Y500D01*
G01Y-3500D02*
X625300D01*
G01X627400D02*
Y-167D01*
G01Y-1083D02*
X627650Y-667D01*
X628067Y-333D01*
X628650Y-167D01*
X629233Y-333D01*
X629650Y-667D01*
X629900Y-1083D01*
Y-3500D01*
G01Y-1083D02*
X630150Y-667D01*
X630567Y-333D01*
X631150Y-167D01*
X631733Y-333D01*
X632150Y-667D01*
X632400Y-1167D01*
Y-3500D01*
G01X635500Y-167D02*
Y-3500D01*
G01Y1167D02*
X635333Y1250D01*
Y1417D01*
X635500Y1500D01*
X635667Y1417D01*
Y1250D01*
X635500Y1167D01*
G01X641100Y-3500D02*
Y1500D01*
G01X607500Y-15000D02*
X606833Y-15167D01*
X606333Y-15583D01*
X606000Y-16083D01*
X605750Y-16750D01*
X605667Y-17500D01*
X605750Y-18250D01*
X606000Y-18917D01*
X606333Y-19417D01*
X606833Y-19833D01*
X607500Y-20000D01*
X608167Y-19833D01*
X608667Y-19417D01*
X609000Y-18917D01*
X609250Y-18250D01*
X609333Y-17500D01*
X609250Y-16750D01*
X609000Y-16083D01*
X608667Y-15583D01*
X608167Y-15167D01*
X607500Y-15000D01*
G01X613100Y-20167D02*
X612933Y-20083D01*
Y-19917D01*
X613100Y-19833D01*
X613267Y-19917D01*
Y-20083D01*
X613100Y-20167D01*
G01X616867Y-19000D02*
X617367Y-19583D01*
X618033Y-19917D01*
X618783Y-20000D01*
X619450Y-19917D01*
X620117Y-19500D01*
X620533Y-19000D01*
X620617Y-18500D01*
X620450Y-17917D01*
X619867Y-17500D01*
X619283Y-17333D01*
X618533D01*
G01X619283D02*
X619783Y-17083D01*
X620200Y-16667D01*
X620367Y-16167D01*
X620200Y-15667D01*
X619783Y-15250D01*
X619033Y-15000D01*
X618283Y-15083D01*
X617533Y-15417D01*
G01X621800Y-18333D02*
X622633Y-16667D01*
X623467D01*
X625133Y-20000D01*
X625967D01*
X626800Y-18333D01*
G01X629900Y-15000D02*
X629233Y-15167D01*
X628733Y-15583D01*
X628400Y-16083D01*
X628150Y-16750D01*
X628067Y-17500D01*
X628150Y-18250D01*
X628400Y-18917D01*
X628733Y-19417D01*
X629233Y-19833D01*
X629900Y-20000D01*
X630567Y-19833D01*
X631067Y-19417D01*
X631400Y-18917D01*
X631650Y-18250D01*
X631733Y-17500D01*
X631650Y-16750D01*
X631400Y-16083D01*
X631067Y-15583D01*
X630567Y-15167D01*
X629900Y-15000D01*
G01X635500Y-20167D02*
X635333Y-20083D01*
Y-19917D01*
X635500Y-19833D01*
X635667Y-19917D01*
Y-20083D01*
X635500Y-20167D01*
G01X640933Y-20000D02*
X641100Y-18917D01*
X641350Y-18000D01*
X641683Y-17167D01*
X642100Y-16250D01*
X642767Y-15000D01*
X639433D01*
G01X644200Y-20000D02*
Y-16667D01*
G01Y-17583D02*
X644450Y-17167D01*
X644867Y-16833D01*
X645450Y-16667D01*
X646033Y-16833D01*
X646450Y-17167D01*
X646700Y-17583D01*
Y-20000D01*
G01Y-17583D02*
X646950Y-17167D01*
X647367Y-16833D01*
X647950Y-16667D01*
X648533Y-16833D01*
X648950Y-17167D01*
X649200Y-17667D01*
Y-20000D01*
G01X652300Y-16667D02*
Y-20000D01*
G01Y-15333D02*
X652133Y-15250D01*
Y-15083D01*
X652300Y-15000D01*
X652467Y-15083D01*
Y-15250D01*
X652300Y-15333D01*
G01X657900Y-20000D02*
Y-15000D01*
G01X607500Y-28500D02*
X606833Y-28667D01*
X606333Y-29083D01*
X606000Y-29583D01*
X605750Y-30250D01*
X605667Y-31000D01*
X605750Y-31750D01*
X606000Y-32417D01*
X606333Y-32917D01*
X606833Y-33333D01*
X607500Y-33500D01*
X608167Y-33333D01*
X608667Y-32917D01*
X609000Y-32417D01*
X609250Y-31750D01*
X609333Y-31000D01*
X609250Y-30250D01*
X609000Y-29583D01*
X608667Y-29083D01*
X608167Y-28667D01*
X607500Y-28500D01*
G01X613100Y-33667D02*
X612933Y-33583D01*
Y-33417D01*
X613100Y-33333D01*
X613267Y-33417D01*
Y-33583D01*
X613100Y-33667D01*
G01X616867Y-32500D02*
X617367Y-33083D01*
X618033Y-33417D01*
X618783Y-33500D01*
X619450Y-33417D01*
X620117Y-33000D01*
X620533Y-32500D01*
X620617Y-32000D01*
X620450Y-31417D01*
X619867Y-31000D01*
X619283Y-30833D01*
X618533D01*
G01X619283D02*
X619783Y-30583D01*
X620200Y-30167D01*
X620367Y-29667D01*
X620200Y-29167D01*
X619783Y-28750D01*
X619033Y-28500D01*
X618283Y-28583D01*
X617533Y-28917D01*
G01X621800Y-31833D02*
X622633Y-30167D01*
X623467D01*
X625133Y-33500D01*
X625967D01*
X626800Y-31833D01*
G01X629900Y-28500D02*
X629233Y-28667D01*
X628733Y-29083D01*
X628400Y-29583D01*
X628150Y-30250D01*
X628067Y-31000D01*
X628150Y-31750D01*
X628400Y-32417D01*
X628733Y-32917D01*
X629233Y-33333D01*
X629900Y-33500D01*
X630567Y-33333D01*
X631067Y-32917D01*
X631400Y-32417D01*
X631650Y-31750D01*
X631733Y-31000D01*
X631650Y-30250D01*
X631400Y-29583D01*
X631067Y-29083D01*
X630567Y-28667D01*
X629900Y-28500D01*
G01X635500Y-33667D02*
X635333Y-33583D01*
Y-33417D01*
X635500Y-33333D01*
X635667Y-33417D01*
Y-33583D01*
X635500Y-33667D01*
G01X640933Y-33500D02*
X641100Y-32417D01*
X641350Y-31500D01*
X641683Y-30667D01*
X642100Y-29750D01*
X642767Y-28500D01*
X639433D01*
G01X644200Y-33500D02*
Y-30167D01*
G01Y-31083D02*
X644450Y-30667D01*
X644867Y-30333D01*
X645450Y-30167D01*
X646033Y-30333D01*
X646450Y-30667D01*
X646700Y-31083D01*
Y-33500D01*
G01Y-31083D02*
X646950Y-30667D01*
X647367Y-30333D01*
X647950Y-30167D01*
X648533Y-30333D01*
X648950Y-30667D01*
X649200Y-31167D01*
Y-33500D01*
G01X652300Y-30167D02*
Y-33500D01*
G01Y-28833D02*
X652133Y-28750D01*
Y-28583D01*
X652300Y-28500D01*
X652467Y-28583D01*
Y-28750D01*
X652300Y-28833D01*
G01X657900Y-33500D02*
Y-28500D01*
G01X609167Y-48500D02*
X605833Y-46833D01*
X609167Y-45167D01*
G01X612017Y-47583D02*
X614183D01*
G01Y-46083D02*
X612017D01*
G01X618700Y-48500D02*
Y-43500D01*
X617700Y-44500D01*
G01Y-48500D02*
X619700D01*
G01X624300Y-48667D02*
X624133Y-48583D01*
Y-48417D01*
X624300Y-48333D01*
X624467Y-48417D01*
Y-48583D01*
X624300Y-48667D01*
G01X630900Y-48500D02*
Y-43500D01*
X627817Y-47083D01*
X631983D01*
G01X633000Y-48500D02*
Y-45167D01*
G01Y-46083D02*
X633250Y-45667D01*
X633667Y-45333D01*
X634250Y-45167D01*
X634833Y-45333D01*
X635250Y-45667D01*
X635500Y-46083D01*
Y-48500D01*
G01Y-46083D02*
X635750Y-45667D01*
X636167Y-45333D01*
X636750Y-45167D01*
X637333Y-45333D01*
X637750Y-45667D01*
X638000Y-46167D01*
Y-48500D01*
G01X641100Y-45167D02*
Y-48500D01*
G01Y-43833D02*
X640933Y-43750D01*
Y-43583D01*
X641100Y-43500D01*
X641267Y-43583D01*
Y-43750D01*
X641100Y-43833D01*
G01X646700Y-48500D02*
Y-43500D01*
G01X606583Y13167D02*
X608583D01*
G01X607500Y14250D02*
Y12083D01*
G01X611600Y11333D02*
X614600Y16500D01*
G01X617617Y13167D02*
X619783D01*
G01X622717Y15667D02*
X623217Y16167D01*
X623800Y16417D01*
X624467Y16500D01*
X625300Y16333D01*
X625883Y15917D01*
X626050Y15417D01*
X625967Y14917D01*
X625633Y14500D01*
X623967Y13667D01*
X623217Y13083D01*
X622717Y12250D01*
X622550Y11500D01*
X626050D01*
G01X627400D02*
Y14833D01*
G01Y13917D02*
X627650Y14333D01*
X628067Y14667D01*
X628650Y14833D01*
X629233Y14667D01*
X629650Y14333D01*
X629900Y13917D01*
Y11500D01*
G01Y13917D02*
X630150Y14333D01*
X630567Y14667D01*
X631150Y14833D01*
X631733Y14667D01*
X632150Y14333D01*
X632400Y13833D01*
Y11500D01*
G01X635500Y14833D02*
Y11500D01*
G01Y16167D02*
X635333Y16250D01*
Y16417D01*
X635500Y16500D01*
X635667Y16417D01*
Y16250D01*
X635500Y16167D01*
G01X641100Y11500D02*
Y16500D01*
G01X606583Y-1833D02*
X608583D01*
G01X607500Y-750D02*
Y-2917D01*
G01X611600Y-3667D02*
X614600Y1500D01*
G01X617617Y-1833D02*
X619783D01*
G01X624300Y-3500D02*
Y1500D01*
X623300Y500D01*
G01Y-3500D02*
X625300D01*
G01X627400D02*
Y-167D01*
G01Y-1083D02*
X627650Y-667D01*
X628067Y-333D01*
X628650Y-167D01*
X629233Y-333D01*
X629650Y-667D01*
X629900Y-1083D01*
Y-3500D01*
G01Y-1083D02*
X630150Y-667D01*
X630567Y-333D01*
X631150Y-167D01*
X631733Y-333D01*
X632150Y-667D01*
X632400Y-1167D01*
Y-3500D01*
G01X635500Y-167D02*
Y-3500D01*
G01Y1167D02*
X635333Y1250D01*
Y1417D01*
X635500Y1500D01*
X635667Y1417D01*
Y1250D01*
X635500Y1167D01*
G01X641100Y-3500D02*
Y1500D01*
G01X607500Y-15000D02*
X606833Y-15167D01*
X606333Y-15583D01*
X606000Y-16083D01*
X605750Y-16750D01*
X605667Y-17500D01*
X605750Y-18250D01*
X606000Y-18917D01*
X606333Y-19417D01*
X606833Y-19833D01*
X607500Y-20000D01*
X608167Y-19833D01*
X608667Y-19417D01*
X609000Y-18917D01*
X609250Y-18250D01*
X609333Y-17500D01*
X609250Y-16750D01*
X609000Y-16083D01*
X608667Y-15583D01*
X608167Y-15167D01*
X607500Y-15000D01*
G01X613100Y-20167D02*
X612933Y-20083D01*
Y-19917D01*
X613100Y-19833D01*
X613267Y-19917D01*
Y-20083D01*
X613100Y-20167D01*
G01X616867Y-19000D02*
X617367Y-19583D01*
X618033Y-19917D01*
X618783Y-20000D01*
X619450Y-19917D01*
X620117Y-19500D01*
X620533Y-19000D01*
X620617Y-18500D01*
X620450Y-17917D01*
X619867Y-17500D01*
X619283Y-17333D01*
X618533D01*
G01X619283D02*
X619783Y-17083D01*
X620200Y-16667D01*
X620367Y-16167D01*
X620200Y-15667D01*
X619783Y-15250D01*
X619033Y-15000D01*
X618283Y-15083D01*
X617533Y-15417D01*
G01X621800Y-18333D02*
X622633Y-16667D01*
X623467D01*
X625133Y-20000D01*
X625967D01*
X626800Y-18333D01*
G01X629900Y-15000D02*
X629233Y-15167D01*
X628733Y-15583D01*
X628400Y-16083D01*
X628150Y-16750D01*
X628067Y-17500D01*
X628150Y-18250D01*
X628400Y-18917D01*
X628733Y-19417D01*
X629233Y-19833D01*
X629900Y-20000D01*
X630567Y-19833D01*
X631067Y-19417D01*
X631400Y-18917D01*
X631650Y-18250D01*
X631733Y-17500D01*
X631650Y-16750D01*
X631400Y-16083D01*
X631067Y-15583D01*
X630567Y-15167D01*
X629900Y-15000D01*
G01X635500Y-20167D02*
X635333Y-20083D01*
Y-19917D01*
X635500Y-19833D01*
X635667Y-19917D01*
Y-20083D01*
X635500Y-20167D01*
G01X640933Y-20000D02*
X641100Y-18917D01*
X641350Y-18000D01*
X641683Y-17167D01*
X642100Y-16250D01*
X642767Y-15000D01*
X639433D01*
G01X644200Y-20000D02*
Y-16667D01*
G01Y-17583D02*
X644450Y-17167D01*
X644867Y-16833D01*
X645450Y-16667D01*
X646033Y-16833D01*
X646450Y-17167D01*
X646700Y-17583D01*
Y-20000D01*
G01Y-17583D02*
X646950Y-17167D01*
X647367Y-16833D01*
X647950Y-16667D01*
X648533Y-16833D01*
X648950Y-17167D01*
X649200Y-17667D01*
Y-20000D01*
G01X652300Y-16667D02*
Y-20000D01*
G01Y-15333D02*
X652133Y-15250D01*
Y-15083D01*
X652300Y-15000D01*
X652467Y-15083D01*
Y-15250D01*
X652300Y-15333D01*
G01X657900Y-20000D02*
Y-15000D01*
G01X607500Y-28500D02*
X606833Y-28667D01*
X606333Y-29083D01*
X606000Y-29583D01*
X605750Y-30250D01*
X605667Y-31000D01*
X605750Y-31750D01*
X606000Y-32417D01*
X606333Y-32917D01*
X606833Y-33333D01*
X607500Y-33500D01*
X608167Y-33333D01*
X608667Y-32917D01*
X609000Y-32417D01*
X609250Y-31750D01*
X609333Y-31000D01*
X609250Y-30250D01*
X609000Y-29583D01*
X608667Y-29083D01*
X608167Y-28667D01*
X607500Y-28500D01*
G01X613100Y-33667D02*
X612933Y-33583D01*
Y-33417D01*
X613100Y-33333D01*
X613267Y-33417D01*
Y-33583D01*
X613100Y-33667D01*
G01X616867Y-32500D02*
X617367Y-33083D01*
X618033Y-33417D01*
X618783Y-33500D01*
X619450Y-33417D01*
X620117Y-33000D01*
X620533Y-32500D01*
X620617Y-32000D01*
X620450Y-31417D01*
X619867Y-31000D01*
X619283Y-30833D01*
X618533D01*
G01X619283D02*
X619783Y-30583D01*
X620200Y-30167D01*
X620367Y-29667D01*
X620200Y-29167D01*
X619783Y-28750D01*
X619033Y-28500D01*
X618283Y-28583D01*
X617533Y-28917D01*
G01X621800Y-31833D02*
X622633Y-30167D01*
X623467D01*
X625133Y-33500D01*
X625967D01*
X626800Y-31833D01*
G01X629900Y-28500D02*
X629233Y-28667D01*
X628733Y-29083D01*
X628400Y-29583D01*
X628150Y-30250D01*
X628067Y-31000D01*
X628150Y-31750D01*
X628400Y-32417D01*
X628733Y-32917D01*
X629233Y-33333D01*
X629900Y-33500D01*
X630567Y-33333D01*
X631067Y-32917D01*
X631400Y-32417D01*
X631650Y-31750D01*
X631733Y-31000D01*
X631650Y-30250D01*
X631400Y-29583D01*
X631067Y-29083D01*
X630567Y-28667D01*
X629900Y-28500D01*
G01X635500Y-33667D02*
X635333Y-33583D01*
Y-33417D01*
X635500Y-33333D01*
X635667Y-33417D01*
Y-33583D01*
X635500Y-33667D01*
G01X640933Y-33500D02*
X641100Y-32417D01*
X641350Y-31500D01*
X641683Y-30667D01*
X642100Y-29750D01*
X642767Y-28500D01*
X639433D01*
G01X644200Y-33500D02*
Y-30167D01*
G01Y-31083D02*
X644450Y-30667D01*
X644867Y-30333D01*
X645450Y-30167D01*
X646033Y-30333D01*
X646450Y-30667D01*
X646700Y-31083D01*
Y-33500D01*
G01Y-31083D02*
X646950Y-30667D01*
X647367Y-30333D01*
X647950Y-30167D01*
X648533Y-30333D01*
X648950Y-30667D01*
X649200Y-31167D01*
Y-33500D01*
G01X652300Y-30167D02*
Y-33500D01*
G01Y-28833D02*
X652133Y-28750D01*
Y-28583D01*
X652300Y-28500D01*
X652467Y-28583D01*
Y-28750D01*
X652300Y-28833D01*
G01X657900Y-33500D02*
Y-28500D01*
G01X609167Y-48500D02*
X605833Y-46833D01*
X609167Y-45167D01*
G01X612017Y-47583D02*
X614183D01*
G01Y-46083D02*
X612017D01*
G01X618700Y-48500D02*
Y-43500D01*
X617700Y-44500D01*
G01Y-48500D02*
X619700D01*
G01X624300Y-48667D02*
X624133Y-48583D01*
Y-48417D01*
X624300Y-48333D01*
X624467Y-48417D01*
Y-48583D01*
X624300Y-48667D01*
G01X630900Y-48500D02*
Y-43500D01*
X627817Y-47083D01*
X631983D01*
G01X633000Y-48500D02*
Y-45167D01*
G01Y-46083D02*
X633250Y-45667D01*
X633667Y-45333D01*
X634250Y-45167D01*
X634833Y-45333D01*
X635250Y-45667D01*
X635500Y-46083D01*
Y-48500D01*
G01Y-46083D02*
X635750Y-45667D01*
X636167Y-45333D01*
X636750Y-45167D01*
X637333Y-45333D01*
X637750Y-45667D01*
X638000Y-46167D01*
Y-48500D01*
G01X641100Y-45167D02*
Y-48500D01*
G01Y-43833D02*
X640933Y-43750D01*
Y-43583D01*
X641100Y-43500D01*
X641267Y-43583D01*
Y-43750D01*
X641100Y-43833D01*
G01X646700Y-48500D02*
Y-43500D01*
G01X606583Y13167D02*
X608583D01*
G01X607500Y14250D02*
Y12083D01*
G01X611600Y11333D02*
X614600Y16500D01*
G01X617617Y13167D02*
X619783D01*
G01X622717Y15667D02*
X623217Y16167D01*
X623800Y16417D01*
X624467Y16500D01*
X625300Y16333D01*
X625883Y15917D01*
X626050Y15417D01*
X625967Y14917D01*
X625633Y14500D01*
X623967Y13667D01*
X623217Y13083D01*
X622717Y12250D01*
X622550Y11500D01*
X626050D01*
G01X627400D02*
Y14833D01*
G01Y13917D02*
X627650Y14333D01*
X628067Y14667D01*
X628650Y14833D01*
X629233Y14667D01*
X629650Y14333D01*
X629900Y13917D01*
Y11500D01*
G01Y13917D02*
X630150Y14333D01*
X630567Y14667D01*
X631150Y14833D01*
X631733Y14667D01*
X632150Y14333D01*
X632400Y13833D01*
Y11500D01*
G01X635500Y14833D02*
Y11500D01*
G01Y16167D02*
X635333Y16250D01*
Y16417D01*
X635500Y16500D01*
X635667Y16417D01*
Y16250D01*
X635500Y16167D01*
G01X641100Y11500D02*
Y16500D01*
G01X606583Y98167D02*
X608583D01*
G01X607500Y99250D02*
Y97083D01*
G01X611600Y96333D02*
X614600Y101500D01*
G01X617617Y98167D02*
X619783D01*
G01X622717Y100667D02*
X623217Y101167D01*
X623800Y101417D01*
X624467Y101500D01*
X625300Y101333D01*
X625883Y100917D01*
X626050Y100417D01*
X625967Y99917D01*
X625633Y99500D01*
X623967Y98667D01*
X623217Y98083D01*
X622717Y97250D01*
X622550Y96500D01*
X626050D01*
G01X629900Y101500D02*
X629233Y101333D01*
X628733Y100917D01*
X628400Y100417D01*
X628150Y99750D01*
X628067Y99000D01*
X628150Y98250D01*
X628400Y97583D01*
X628733Y97083D01*
X629233Y96667D01*
X629900Y96500D01*
X630567Y96667D01*
X631067Y97083D01*
X631400Y97583D01*
X631650Y98250D01*
X631733Y99000D01*
X631650Y99750D01*
X631400Y100417D01*
X631067Y100917D01*
X630567Y101333D01*
X629900Y101500D01*
G01X634000Y96333D02*
X637000Y101500D01*
G01X634000D02*
X633500Y101333D01*
X633250Y101083D01*
X633083Y100583D01*
X633250Y100083D01*
X633500Y99833D01*
X634000Y99667D01*
X634500Y99833D01*
X634750Y100083D01*
X634917Y100583D01*
X634750Y101083D01*
X634500Y101333D01*
X634000Y101500D01*
G01X637000Y98167D02*
X636500Y98000D01*
X636250Y97750D01*
X636083Y97250D01*
X636250Y96750D01*
X636500Y96500D01*
X637000Y96333D01*
X637500Y96500D01*
X637750Y96750D01*
X637917Y97250D01*
X637750Y97750D01*
X637500Y98000D01*
X637000Y98167D01*
G01X606583Y68167D02*
X608583D01*
G01X607500Y69250D02*
Y67083D01*
G01X611600Y66333D02*
X614600Y71500D01*
G01X617617Y68167D02*
X619783D01*
G01X624300Y66500D02*
Y71500D01*
X623300Y70500D01*
G01Y66500D02*
X625300D01*
G01X628067Y67250D02*
X628567Y66833D01*
X629150Y66583D01*
X629900Y66500D01*
X630650Y66667D01*
X631233Y67000D01*
X631650Y67583D01*
X631733Y68250D01*
X631567Y68917D01*
X631150Y69333D01*
X630567Y69667D01*
X629983Y69750D01*
X629400Y69667D01*
X628650Y69333D01*
X628900Y71500D01*
X631150D01*
G01X634000Y66333D02*
X637000Y71500D01*
G01X634000D02*
X633500Y71333D01*
X633250Y71083D01*
X633083Y70583D01*
X633250Y70083D01*
X633500Y69833D01*
X634000Y69667D01*
X634500Y69833D01*
X634750Y70083D01*
X634917Y70583D01*
X634750Y71083D01*
X634500Y71333D01*
X634000Y71500D01*
G01X637000Y68167D02*
X636500Y68000D01*
X636250Y67750D01*
X636083Y67250D01*
X636250Y66750D01*
X636500Y66500D01*
X637000Y66333D01*
X637500Y66500D01*
X637750Y66750D01*
X637917Y67250D01*
X637750Y67750D01*
X637500Y68000D01*
X637000Y68167D01*
G01X606583Y83167D02*
X608583D01*
G01X607500Y84250D02*
Y82083D01*
G01X611600Y81333D02*
X614600Y86500D01*
G01X617617Y83167D02*
X619783D01*
G01X624300Y81500D02*
Y86500D01*
X623300Y85500D01*
G01Y81500D02*
X625300D01*
G01X627400D02*
Y84833D01*
G01Y83917D02*
X627650Y84333D01*
X628067Y84667D01*
X628650Y84833D01*
X629233Y84667D01*
X629650Y84333D01*
X629900Y83917D01*
Y81500D01*
G01Y83917D02*
X630150Y84333D01*
X630567Y84667D01*
X631150Y84833D01*
X631733Y84667D01*
X632150Y84333D01*
X632400Y83833D01*
Y81500D01*
G01X635500Y84833D02*
Y81500D01*
G01Y86167D02*
X635333Y86250D01*
Y86417D01*
X635500Y86500D01*
X635667Y86417D01*
Y86250D01*
X635500Y86167D01*
G01X641100Y81500D02*
Y86500D01*
G01X606583Y48667D02*
X608583D01*
G01X607500Y49750D02*
Y47583D01*
G01X611600Y46833D02*
X614600Y52000D01*
G01X617617Y48667D02*
X619783D01*
G01X622717Y51167D02*
X623217Y51667D01*
X623800Y51917D01*
X624467Y52000D01*
X625300Y51833D01*
X625883Y51417D01*
X626050Y50917D01*
X625967Y50417D01*
X625633Y50000D01*
X623967Y49167D01*
X623217Y48583D01*
X622717Y47750D01*
X622550Y47000D01*
X626050D01*
G01X627400D02*
Y50333D01*
G01Y49417D02*
X627650Y49833D01*
X628067Y50167D01*
X628650Y50333D01*
X629233Y50167D01*
X629650Y49833D01*
X629900Y49417D01*
Y47000D01*
G01Y49417D02*
X630150Y49833D01*
X630567Y50167D01*
X631150Y50333D01*
X631733Y50167D01*
X632150Y49833D01*
X632400Y49333D01*
Y47000D01*
G01X635500Y50333D02*
Y47000D01*
G01Y51667D02*
X635333Y51750D01*
Y51917D01*
X635500Y52000D01*
X635667Y51917D01*
Y51750D01*
X635500Y51667D01*
G01X641100Y47000D02*
Y52000D01*
G01X606583Y24667D02*
X608583D01*
G01X607500Y25750D02*
Y23583D01*
G01X611600Y22833D02*
X614600Y28000D01*
G01X617617Y24667D02*
X619783D01*
G01X624300Y23000D02*
Y28000D01*
X623300Y27000D01*
G01Y23000D02*
X625300D01*
G01X627400D02*
Y26333D01*
G01Y25417D02*
X627650Y25833D01*
X628067Y26167D01*
X628650Y26333D01*
X629233Y26167D01*
X629650Y25833D01*
X629900Y25417D01*
Y23000D01*
G01Y25417D02*
X630150Y25833D01*
X630567Y26167D01*
X631150Y26333D01*
X631733Y26167D01*
X632150Y25833D01*
X632400Y25333D01*
Y23000D01*
G01X635500Y26333D02*
Y23000D01*
G01Y27667D02*
X635333Y27750D01*
Y27917D01*
X635500Y28000D01*
X635667Y27917D01*
Y27750D01*
X635500Y27667D01*
G01X641100Y23000D02*
Y28000D01*
G01X606583Y98167D02*
X608583D01*
G01X607500Y99250D02*
Y97083D01*
G01X611600Y96333D02*
X614600Y101500D01*
G01X617617Y98167D02*
X619783D01*
G01X622717Y100667D02*
X623217Y101167D01*
X623800Y101417D01*
X624467Y101500D01*
X625300Y101333D01*
X625883Y100917D01*
X626050Y100417D01*
X625967Y99917D01*
X625633Y99500D01*
X623967Y98667D01*
X623217Y98083D01*
X622717Y97250D01*
X622550Y96500D01*
X626050D01*
G01X629900Y101500D02*
X629233Y101333D01*
X628733Y100917D01*
X628400Y100417D01*
X628150Y99750D01*
X628067Y99000D01*
X628150Y98250D01*
X628400Y97583D01*
X628733Y97083D01*
X629233Y96667D01*
X629900Y96500D01*
X630567Y96667D01*
X631067Y97083D01*
X631400Y97583D01*
X631650Y98250D01*
X631733Y99000D01*
X631650Y99750D01*
X631400Y100417D01*
X631067Y100917D01*
X630567Y101333D01*
X629900Y101500D01*
G01X634000Y96333D02*
X637000Y101500D01*
G01X634000D02*
X633500Y101333D01*
X633250Y101083D01*
X633083Y100583D01*
X633250Y100083D01*
X633500Y99833D01*
X634000Y99667D01*
X634500Y99833D01*
X634750Y100083D01*
X634917Y100583D01*
X634750Y101083D01*
X634500Y101333D01*
X634000Y101500D01*
G01X637000Y98167D02*
X636500Y98000D01*
X636250Y97750D01*
X636083Y97250D01*
X636250Y96750D01*
X636500Y96500D01*
X637000Y96333D01*
X637500Y96500D01*
X637750Y96750D01*
X637917Y97250D01*
X637750Y97750D01*
X637500Y98000D01*
X637000Y98167D01*
G01X606583Y68167D02*
X608583D01*
G01X607500Y69250D02*
Y67083D01*
G01X611600Y66333D02*
X614600Y71500D01*
G01X617617Y68167D02*
X619783D01*
G01X624300Y66500D02*
Y71500D01*
X623300Y70500D01*
G01Y66500D02*
X625300D01*
G01X628067Y67250D02*
X628567Y66833D01*
X629150Y66583D01*
X629900Y66500D01*
X630650Y66667D01*
X631233Y67000D01*
X631650Y67583D01*
X631733Y68250D01*
X631567Y68917D01*
X631150Y69333D01*
X630567Y69667D01*
X629983Y69750D01*
X629400Y69667D01*
X628650Y69333D01*
X628900Y71500D01*
X631150D01*
G01X634000Y66333D02*
X637000Y71500D01*
G01X634000D02*
X633500Y71333D01*
X633250Y71083D01*
X633083Y70583D01*
X633250Y70083D01*
X633500Y69833D01*
X634000Y69667D01*
X634500Y69833D01*
X634750Y70083D01*
X634917Y70583D01*
X634750Y71083D01*
X634500Y71333D01*
X634000Y71500D01*
G01X637000Y68167D02*
X636500Y68000D01*
X636250Y67750D01*
X636083Y67250D01*
X636250Y66750D01*
X636500Y66500D01*
X637000Y66333D01*
X637500Y66500D01*
X637750Y66750D01*
X637917Y67250D01*
X637750Y67750D01*
X637500Y68000D01*
X637000Y68167D01*
G01X606583Y83167D02*
X608583D01*
G01X607500Y84250D02*
Y82083D01*
G01X611600Y81333D02*
X614600Y86500D01*
G01X617617Y83167D02*
X619783D01*
G01X624300Y81500D02*
Y86500D01*
X623300Y85500D01*
G01Y81500D02*
X625300D01*
G01X627400D02*
Y84833D01*
G01Y83917D02*
X627650Y84333D01*
X628067Y84667D01*
X628650Y84833D01*
X629233Y84667D01*
X629650Y84333D01*
X629900Y83917D01*
Y81500D01*
G01Y83917D02*
X630150Y84333D01*
X630567Y84667D01*
X631150Y84833D01*
X631733Y84667D01*
X632150Y84333D01*
X632400Y83833D01*
Y81500D01*
G01X635500Y84833D02*
Y81500D01*
G01Y86167D02*
X635333Y86250D01*
Y86417D01*
X635500Y86500D01*
X635667Y86417D01*
Y86250D01*
X635500Y86167D01*
G01X641100Y81500D02*
Y86500D01*
G01X606583Y48667D02*
X608583D01*
G01X607500Y49750D02*
Y47583D01*
G01X611600Y46833D02*
X614600Y52000D01*
G01X617617Y48667D02*
X619783D01*
G01X622717Y51167D02*
X623217Y51667D01*
X623800Y51917D01*
X624467Y52000D01*
X625300Y51833D01*
X625883Y51417D01*
X626050Y50917D01*
X625967Y50417D01*
X625633Y50000D01*
X623967Y49167D01*
X623217Y48583D01*
X622717Y47750D01*
X622550Y47000D01*
X626050D01*
G01X627400D02*
Y50333D01*
G01Y49417D02*
X627650Y49833D01*
X628067Y50167D01*
X628650Y50333D01*
X629233Y50167D01*
X629650Y49833D01*
X629900Y49417D01*
Y47000D01*
G01Y49417D02*
X630150Y49833D01*
X630567Y50167D01*
X631150Y50333D01*
X631733Y50167D01*
X632150Y49833D01*
X632400Y49333D01*
Y47000D01*
G01X635500Y50333D02*
Y47000D01*
G01Y51667D02*
X635333Y51750D01*
Y51917D01*
X635500Y52000D01*
X635667Y51917D01*
Y51750D01*
X635500Y51667D01*
G01X641100Y47000D02*
Y52000D01*
G01X606583Y24667D02*
X608583D01*
G01X607500Y25750D02*
Y23583D01*
G01X611600Y22833D02*
X614600Y28000D01*
G01X617617Y24667D02*
X619783D01*
G01X624300Y23000D02*
Y28000D01*
X623300Y27000D01*
G01Y23000D02*
X625300D01*
G01X627400D02*
Y26333D01*
G01Y25417D02*
X627650Y25833D01*
X628067Y26167D01*
X628650Y26333D01*
X629233Y26167D01*
X629650Y25833D01*
X629900Y25417D01*
Y23000D01*
G01Y25417D02*
X630150Y25833D01*
X630567Y26167D01*
X631150Y26333D01*
X631733Y26167D01*
X632150Y25833D01*
X632400Y25333D01*
Y23000D01*
G01X635500Y26333D02*
Y23000D01*
G01Y27667D02*
X635333Y27750D01*
Y27917D01*
X635500Y28000D01*
X635667Y27917D01*
Y27750D01*
X635500Y27667D01*
G01X641100Y23000D02*
Y28000D01*
G01X605833Y166500D02*
X609167Y168167D01*
X605833Y169833D01*
G01X612017Y167417D02*
X614183D01*
G01Y168917D02*
X612017D01*
G01X618700Y166500D02*
Y171500D01*
X617700Y170500D01*
G01Y166500D02*
X619700D01*
G01X624300Y166333D02*
X624133Y166417D01*
Y166583D01*
X624300Y166667D01*
X624467Y166583D01*
Y166417D01*
X624300Y166333D01*
G01X628067Y167500D02*
X628567Y166917D01*
X629233Y166583D01*
X629983Y166500D01*
X630650Y166583D01*
X631317Y167000D01*
X631733Y167500D01*
X631817Y168000D01*
X631650Y168583D01*
X631067Y169000D01*
X630483Y169167D01*
X629733D01*
G01X630483D02*
X630983Y169417D01*
X631400Y169833D01*
X631567Y170333D01*
X631400Y170833D01*
X630983Y171250D01*
X630233Y171500D01*
X629483Y171417D01*
X628733Y171083D01*
G01X633000Y166500D02*
Y169833D01*
G01Y168917D02*
X633250Y169333D01*
X633667Y169667D01*
X634250Y169833D01*
X634833Y169667D01*
X635250Y169333D01*
X635500Y168917D01*
Y166500D01*
G01Y168917D02*
X635750Y169333D01*
X636167Y169667D01*
X636750Y169833D01*
X637333Y169667D01*
X637750Y169333D01*
X638000Y168833D01*
Y166500D01*
G01X641100Y169833D02*
Y166500D01*
G01Y171167D02*
X640933Y171250D01*
Y171417D01*
X641100Y171500D01*
X641267Y171417D01*
Y171250D01*
X641100Y171167D01*
G01X646700Y166500D02*
Y171500D01*
G01X605833Y144000D02*
X609167Y145667D01*
X605833Y147333D01*
G01X612017Y144917D02*
X614183D01*
G01Y146417D02*
X612017D01*
G01X618700Y144000D02*
Y149000D01*
X617700Y148000D01*
G01Y144000D02*
X619700D01*
G01X624300Y143833D02*
X624133Y143917D01*
Y144083D01*
X624300Y144167D01*
X624467Y144083D01*
Y143917D01*
X624300Y143833D01*
G01X628067Y144750D02*
X628567Y144333D01*
X629150Y144083D01*
X629900Y144000D01*
X630650Y144167D01*
X631233Y144500D01*
X631650Y145083D01*
X631733Y145750D01*
X631567Y146417D01*
X631150Y146833D01*
X630567Y147167D01*
X629983Y147250D01*
X629400Y147167D01*
X628650Y146833D01*
X628900Y149000D01*
X631150D01*
G01X633000Y144000D02*
Y147333D01*
G01Y146417D02*
X633250Y146833D01*
X633667Y147167D01*
X634250Y147333D01*
X634833Y147167D01*
X635250Y146833D01*
X635500Y146417D01*
Y144000D01*
G01Y146417D02*
X635750Y146833D01*
X636167Y147167D01*
X636750Y147333D01*
X637333Y147167D01*
X637750Y146833D01*
X638000Y146333D01*
Y144000D01*
G01X641100Y147333D02*
Y144000D01*
G01Y148667D02*
X640933Y148750D01*
Y148917D01*
X641100Y149000D01*
X641267Y148917D01*
Y148750D01*
X641100Y148667D01*
G01X646700Y144000D02*
Y149000D01*
G01X605833Y126500D02*
X609167Y128167D01*
X605833Y129833D01*
G01X612017Y127417D02*
X614183D01*
G01Y128917D02*
X612017D01*
G01X618700Y126500D02*
Y131500D01*
X617700Y130500D01*
G01Y126500D02*
X619700D01*
G01X624300Y126333D02*
X624133Y126417D01*
Y126583D01*
X624300Y126667D01*
X624467Y126583D01*
Y126417D01*
X624300Y126333D01*
G01X629900Y131500D02*
X629233Y131333D01*
X628733Y130917D01*
X628400Y130417D01*
X628150Y129750D01*
X628067Y129000D01*
X628150Y128250D01*
X628400Y127583D01*
X628733Y127083D01*
X629233Y126667D01*
X629900Y126500D01*
X630567Y126667D01*
X631067Y127083D01*
X631400Y127583D01*
X631650Y128250D01*
X631733Y129000D01*
X631650Y129750D01*
X631400Y130417D01*
X631067Y130917D01*
X630567Y131333D01*
X629900Y131500D01*
G01X633000Y126500D02*
Y129833D01*
G01Y128917D02*
X633250Y129333D01*
X633667Y129667D01*
X634250Y129833D01*
X634833Y129667D01*
X635250Y129333D01*
X635500Y128917D01*
Y126500D01*
G01Y128917D02*
X635750Y129333D01*
X636167Y129667D01*
X636750Y129833D01*
X637333Y129667D01*
X637750Y129333D01*
X638000Y128833D01*
Y126500D01*
G01X641100Y129833D02*
Y126500D01*
G01Y131167D02*
X640933Y131250D01*
Y131417D01*
X641100Y131500D01*
X641267Y131417D01*
Y131250D01*
X641100Y131167D01*
G01X646700Y126500D02*
Y131500D01*
G01X606583Y113167D02*
X608583D01*
G01X607500Y114250D02*
Y112083D01*
G01X611600Y111333D02*
X614600Y116500D01*
G01X617617Y113167D02*
X619783D01*
G01X622467Y112500D02*
X622967Y111917D01*
X623633Y111583D01*
X624383Y111500D01*
X625050Y111583D01*
X625717Y112000D01*
X626133Y112500D01*
X626217Y113000D01*
X626050Y113583D01*
X625467Y114000D01*
X624883Y114167D01*
X624133D01*
G01X624883D02*
X625383Y114417D01*
X625800Y114833D01*
X625967Y115333D01*
X625800Y115833D01*
X625383Y116250D01*
X624633Y116500D01*
X623883Y116417D01*
X623133Y116083D01*
G01X627400Y111500D02*
Y114833D01*
G01Y113917D02*
X627650Y114333D01*
X628067Y114667D01*
X628650Y114833D01*
X629233Y114667D01*
X629650Y114333D01*
X629900Y113917D01*
Y111500D01*
G01Y113917D02*
X630150Y114333D01*
X630567Y114667D01*
X631150Y114833D01*
X631733Y114667D01*
X632150Y114333D01*
X632400Y113833D01*
Y111500D01*
G01X635500Y114833D02*
Y111500D01*
G01Y116167D02*
X635333Y116250D01*
Y116417D01*
X635500Y116500D01*
X635667Y116417D01*
Y116250D01*
X635500Y116167D01*
G01X641100Y111500D02*
Y116500D01*
G01X605833Y166500D02*
X609167Y168167D01*
X605833Y169833D01*
G01X612017Y167417D02*
X614183D01*
G01Y168917D02*
X612017D01*
G01X618700Y166500D02*
Y171500D01*
X617700Y170500D01*
G01Y166500D02*
X619700D01*
G01X624300Y166333D02*
X624133Y166417D01*
Y166583D01*
X624300Y166667D01*
X624467Y166583D01*
Y166417D01*
X624300Y166333D01*
G01X628067Y167500D02*
X628567Y166917D01*
X629233Y166583D01*
X629983Y166500D01*
X630650Y166583D01*
X631317Y167000D01*
X631733Y167500D01*
X631817Y168000D01*
X631650Y168583D01*
X631067Y169000D01*
X630483Y169167D01*
X629733D01*
G01X630483D02*
X630983Y169417D01*
X631400Y169833D01*
X631567Y170333D01*
X631400Y170833D01*
X630983Y171250D01*
X630233Y171500D01*
X629483Y171417D01*
X628733Y171083D01*
G01X633000Y166500D02*
Y169833D01*
G01Y168917D02*
X633250Y169333D01*
X633667Y169667D01*
X634250Y169833D01*
X634833Y169667D01*
X635250Y169333D01*
X635500Y168917D01*
Y166500D01*
G01Y168917D02*
X635750Y169333D01*
X636167Y169667D01*
X636750Y169833D01*
X637333Y169667D01*
X637750Y169333D01*
X638000Y168833D01*
Y166500D01*
G01X641100Y169833D02*
Y166500D01*
G01Y171167D02*
X640933Y171250D01*
Y171417D01*
X641100Y171500D01*
X641267Y171417D01*
Y171250D01*
X641100Y171167D01*
G01X646700Y166500D02*
Y171500D01*
G01X605833Y144000D02*
X609167Y145667D01*
X605833Y147333D01*
G01X612017Y144917D02*
X614183D01*
G01Y146417D02*
X612017D01*
G01X618700Y144000D02*
Y149000D01*
X617700Y148000D01*
G01Y144000D02*
X619700D01*
G01X624300Y143833D02*
X624133Y143917D01*
Y144083D01*
X624300Y144167D01*
X624467Y144083D01*
Y143917D01*
X624300Y143833D01*
G01X628067Y144750D02*
X628567Y144333D01*
X629150Y144083D01*
X629900Y144000D01*
X630650Y144167D01*
X631233Y144500D01*
X631650Y145083D01*
X631733Y145750D01*
X631567Y146417D01*
X631150Y146833D01*
X630567Y147167D01*
X629983Y147250D01*
X629400Y147167D01*
X628650Y146833D01*
X628900Y149000D01*
X631150D01*
G01X633000Y144000D02*
Y147333D01*
G01Y146417D02*
X633250Y146833D01*
X633667Y147167D01*
X634250Y147333D01*
X634833Y147167D01*
X635250Y146833D01*
X635500Y146417D01*
Y144000D01*
G01Y146417D02*
X635750Y146833D01*
X636167Y147167D01*
X636750Y147333D01*
X637333Y147167D01*
X637750Y146833D01*
X638000Y146333D01*
Y144000D01*
G01X641100Y147333D02*
Y144000D01*
G01Y148667D02*
X640933Y148750D01*
Y148917D01*
X641100Y149000D01*
X641267Y148917D01*
Y148750D01*
X641100Y148667D01*
G01X646700Y144000D02*
Y149000D01*
G01X605833Y126500D02*
X609167Y128167D01*
X605833Y129833D01*
G01X612017Y127417D02*
X614183D01*
G01Y128917D02*
X612017D01*
G01X618700Y126500D02*
Y131500D01*
X617700Y130500D01*
G01Y126500D02*
X619700D01*
G01X624300Y126333D02*
X624133Y126417D01*
Y126583D01*
X624300Y126667D01*
X624467Y126583D01*
Y126417D01*
X624300Y126333D01*
G01X629900Y131500D02*
X629233Y131333D01*
X628733Y130917D01*
X628400Y130417D01*
X628150Y129750D01*
X628067Y129000D01*
X628150Y128250D01*
X628400Y127583D01*
X628733Y127083D01*
X629233Y126667D01*
X629900Y126500D01*
X630567Y126667D01*
X631067Y127083D01*
X631400Y127583D01*
X631650Y128250D01*
X631733Y129000D01*
X631650Y129750D01*
X631400Y130417D01*
X631067Y130917D01*
X630567Y131333D01*
X629900Y131500D01*
G01X633000Y126500D02*
Y129833D01*
G01Y128917D02*
X633250Y129333D01*
X633667Y129667D01*
X634250Y129833D01*
X634833Y129667D01*
X635250Y129333D01*
X635500Y128917D01*
Y126500D01*
G01Y128917D02*
X635750Y129333D01*
X636167Y129667D01*
X636750Y129833D01*
X637333Y129667D01*
X637750Y129333D01*
X638000Y128833D01*
Y126500D01*
G01X641100Y129833D02*
Y126500D01*
G01Y131167D02*
X640933Y131250D01*
Y131417D01*
X641100Y131500D01*
X641267Y131417D01*
Y131250D01*
X641100Y131167D01*
G01X646700Y126500D02*
Y131500D01*
G01X606583Y113167D02*
X608583D01*
G01X607500Y114250D02*
Y112083D01*
G01X611600Y111333D02*
X614600Y116500D01*
G01X617617Y113167D02*
X619783D01*
G01X622467Y112500D02*
X622967Y111917D01*
X623633Y111583D01*
X624383Y111500D01*
X625050Y111583D01*
X625717Y112000D01*
X626133Y112500D01*
X626217Y113000D01*
X626050Y113583D01*
X625467Y114000D01*
X624883Y114167D01*
X624133D01*
G01X624883D02*
X625383Y114417D01*
X625800Y114833D01*
X625967Y115333D01*
X625800Y115833D01*
X625383Y116250D01*
X624633Y116500D01*
X623883Y116417D01*
X623133Y116083D01*
G01X627400Y111500D02*
Y114833D01*
G01Y113917D02*
X627650Y114333D01*
X628067Y114667D01*
X628650Y114833D01*
X629233Y114667D01*
X629650Y114333D01*
X629900Y113917D01*
Y111500D01*
G01Y113917D02*
X630150Y114333D01*
X630567Y114667D01*
X631150Y114833D01*
X631733Y114667D01*
X632150Y114333D01*
X632400Y113833D01*
Y111500D01*
G01X635500Y114833D02*
Y111500D01*
G01Y116167D02*
X635333Y116250D01*
Y116417D01*
X635500Y116500D01*
X635667Y116417D01*
Y116250D01*
X635500Y116167D01*
G01X641100Y111500D02*
Y116500D01*
G01X612977Y200490D02*
X609643Y202157D01*
X612977Y203823D01*
G01X616910Y205490D02*
X616243Y205323D01*
X615743Y204907D01*
X615410Y204407D01*
X615160Y203740D01*
X615077Y202990D01*
X615160Y202240D01*
X615410Y201573D01*
X615743Y201073D01*
X616243Y200657D01*
X616910Y200490D01*
X617577Y200657D01*
X618077Y201073D01*
X618410Y201573D01*
X618660Y202240D01*
X618743Y202990D01*
X618660Y203740D01*
X618410Y204407D01*
X618077Y204907D01*
X617577Y205323D01*
X616910Y205490D01*
G01X622510Y200323D02*
X622343Y200407D01*
Y200573D01*
X622510Y200657D01*
X622677Y200573D01*
Y200407D01*
X622510Y200323D01*
G01X626277Y201490D02*
X626777Y200907D01*
X627443Y200573D01*
X628193Y200490D01*
X628860Y200573D01*
X629527Y200990D01*
X629943Y201490D01*
X630027Y201990D01*
X629860Y202573D01*
X629277Y202990D01*
X628693Y203157D01*
X627943D01*
G01X628693D02*
X629193Y203407D01*
X629610Y203823D01*
X629777Y204323D01*
X629610Y204823D01*
X629193Y205240D01*
X628443Y205490D01*
X627693Y205407D01*
X626943Y205073D01*
G01X631210Y200490D02*
Y203823D01*
G01Y202907D02*
X631460Y203323D01*
X631877Y203657D01*
X632460Y203823D01*
X633043Y203657D01*
X633460Y203323D01*
X633710Y202907D01*
Y200490D01*
G01Y202907D02*
X633960Y203323D01*
X634377Y203657D01*
X634960Y203823D01*
X635543Y203657D01*
X635960Y203323D01*
X636210Y202823D01*
Y200490D01*
G01X639310Y203823D02*
Y200490D01*
G01Y205157D02*
X639143Y205240D01*
Y205407D01*
X639310Y205490D01*
X639477Y205407D01*
Y205240D01*
X639310Y205157D01*
G01X644910Y200490D02*
Y205490D01*
G01X612377Y255680D02*
X609043Y257347D01*
X612377Y259013D01*
G01X616310Y255680D02*
Y260680D01*
X615310Y259680D01*
G01Y255680D02*
X617310D01*
G01X619410D02*
Y259013D01*
G01Y258097D02*
X619660Y258513D01*
X620077Y258847D01*
X620660Y259013D01*
X621243Y258847D01*
X621660Y258513D01*
X621910Y258097D01*
Y255680D01*
G01Y258097D02*
X622160Y258513D01*
X622577Y258847D01*
X623160Y259013D01*
X623743Y258847D01*
X624160Y258513D01*
X624410Y258013D01*
Y255680D01*
G01X627510Y259013D02*
Y255680D01*
G01Y260347D02*
X627343Y260430D01*
Y260597D01*
X627510Y260680D01*
X627677Y260597D01*
Y260430D01*
X627510Y260347D01*
G01X633110Y255680D02*
Y260680D01*
G01X612977Y200490D02*
X609643Y202157D01*
X612977Y203823D01*
G01X616910Y205490D02*
X616243Y205323D01*
X615743Y204907D01*
X615410Y204407D01*
X615160Y203740D01*
X615077Y202990D01*
X615160Y202240D01*
X615410Y201573D01*
X615743Y201073D01*
X616243Y200657D01*
X616910Y200490D01*
X617577Y200657D01*
X618077Y201073D01*
X618410Y201573D01*
X618660Y202240D01*
X618743Y202990D01*
X618660Y203740D01*
X618410Y204407D01*
X618077Y204907D01*
X617577Y205323D01*
X616910Y205490D01*
G01X622510Y200323D02*
X622343Y200407D01*
Y200573D01*
X622510Y200657D01*
X622677Y200573D01*
Y200407D01*
X622510Y200323D01*
G01X626277Y201490D02*
X626777Y200907D01*
X627443Y200573D01*
X628193Y200490D01*
X628860Y200573D01*
X629527Y200990D01*
X629943Y201490D01*
X630027Y201990D01*
X629860Y202573D01*
X629277Y202990D01*
X628693Y203157D01*
X627943D01*
G01X628693D02*
X629193Y203407D01*
X629610Y203823D01*
X629777Y204323D01*
X629610Y204823D01*
X629193Y205240D01*
X628443Y205490D01*
X627693Y205407D01*
X626943Y205073D01*
G01X631210Y200490D02*
Y203823D01*
G01Y202907D02*
X631460Y203323D01*
X631877Y203657D01*
X632460Y203823D01*
X633043Y203657D01*
X633460Y203323D01*
X633710Y202907D01*
Y200490D01*
G01Y202907D02*
X633960Y203323D01*
X634377Y203657D01*
X634960Y203823D01*
X635543Y203657D01*
X635960Y203323D01*
X636210Y202823D01*
Y200490D01*
G01X639310Y203823D02*
Y200490D01*
G01Y205157D02*
X639143Y205240D01*
Y205407D01*
X639310Y205490D01*
X639477Y205407D01*
Y205240D01*
X639310Y205157D01*
G01X644910Y200490D02*
Y205490D01*
G01X612377Y255680D02*
X609043Y257347D01*
X612377Y259013D01*
G01X616310Y255680D02*
Y260680D01*
X615310Y259680D01*
G01Y255680D02*
X617310D01*
G01X619410D02*
Y259013D01*
G01Y258097D02*
X619660Y258513D01*
X620077Y258847D01*
X620660Y259013D01*
X621243Y258847D01*
X621660Y258513D01*
X621910Y258097D01*
Y255680D01*
G01Y258097D02*
X622160Y258513D01*
X622577Y258847D01*
X623160Y259013D01*
X623743Y258847D01*
X624160Y258513D01*
X624410Y258013D01*
Y255680D01*
G01X627510Y259013D02*
Y255680D01*
G01Y260347D02*
X627343Y260430D01*
Y260597D01*
X627510Y260680D01*
X627677Y260597D01*
Y260430D01*
X627510Y260347D01*
G01X633110Y255680D02*
Y260680D01*
G01X602120Y310470D02*
Y313803D01*
G01Y312887D02*
X602370Y313303D01*
X602787Y313637D01*
X603370Y313803D01*
X603953Y313637D01*
X604370Y313303D01*
X604620Y312887D01*
Y310470D01*
G01Y312887D02*
X604870Y313303D01*
X605287Y313637D01*
X605870Y313803D01*
X606453Y313637D01*
X606870Y313303D01*
X607120Y312803D01*
Y310470D01*
G01X608803Y313803D02*
Y311470D01*
X609137Y310887D01*
X609637Y310553D01*
X610220Y310470D01*
X610803Y310553D01*
X611303Y310887D01*
X611637Y311470D01*
G01Y310470D02*
Y313803D01*
G01X614570Y311053D02*
X614987Y310720D01*
X615570Y310470D01*
X616070D01*
X616570Y310637D01*
X616903Y310887D01*
X617070Y311220D01*
X616987Y311720D01*
X616653Y311970D01*
X615153Y312470D01*
X614820Y313053D01*
X614987Y313470D01*
X615320Y313720D01*
X615820Y313803D01*
X616320Y313720D01*
X616820Y313470D01*
G01X621420Y315470D02*
Y310470D01*
G01X620253Y313803D02*
X622587D01*
G01X628687Y310470D02*
X625353Y312137D01*
X628687Y313803D01*
G01X630537Y310470D02*
X632620Y315470D01*
X634703Y310470D01*
G01X633953Y312220D02*
X631287D01*
G01X645320Y315470D02*
Y310470D01*
G01Y311220D02*
X644987Y310803D01*
X644487Y310553D01*
X643903Y310470D01*
X643237Y310637D01*
X642737Y311053D01*
X642403Y311553D01*
X642320Y312137D01*
X642403Y312720D01*
X642737Y313220D01*
X643237Y313637D01*
X643903Y313803D01*
X644487Y313720D01*
X644903Y313553D01*
X645320Y313220D01*
G01X649420Y313803D02*
Y310470D01*
G01Y315137D02*
X649253Y315220D01*
Y315387D01*
X649420Y315470D01*
X649587Y315387D01*
Y315220D01*
X649420Y315137D01*
G01X656520Y310470D02*
Y313803D01*
G01Y313220D02*
X656187Y313553D01*
X655687Y313720D01*
X655103Y313803D01*
X654520Y313637D01*
X654020Y313303D01*
X653687Y312803D01*
X653520Y312137D01*
X653687Y311470D01*
X654020Y310970D01*
X654520Y310637D01*
X655103Y310470D01*
X655687Y310553D01*
X656187Y310803D01*
X656520Y311137D01*
G01X658120Y310470D02*
Y313803D01*
G01Y312887D02*
X658370Y313303D01*
X658787Y313637D01*
X659370Y313803D01*
X659953Y313637D01*
X660370Y313303D01*
X660620Y312887D01*
Y310470D01*
G01Y312887D02*
X660870Y313303D01*
X661287Y313637D01*
X661870Y313803D01*
X662453Y313637D01*
X662870Y313303D01*
X663120Y312803D01*
Y310470D01*
G01X664970Y312720D02*
X667637D01*
X667387Y313303D01*
X666970Y313637D01*
X666387Y313803D01*
X665803Y313720D01*
X665303Y313470D01*
X664970Y312887D01*
X664803Y312387D01*
Y311887D01*
X664970Y311387D01*
X665387Y310887D01*
X665887Y310553D01*
X666470Y310470D01*
X667053Y310637D01*
X667637Y311137D01*
G01X671820Y315470D02*
Y310470D01*
G01X670653Y313803D02*
X672987D01*
G01X676170Y312720D02*
X678837D01*
X678587Y313303D01*
X678170Y313637D01*
X677587Y313803D01*
X677003Y313720D01*
X676503Y313470D01*
X676170Y312887D01*
X676003Y312387D01*
Y311887D01*
X676170Y311387D01*
X676587Y310887D01*
X677087Y310553D01*
X677670Y310470D01*
X678253Y310637D01*
X678837Y311137D01*
G01X681853Y310470D02*
Y313803D01*
G01Y313137D02*
X682270Y313470D01*
X682687Y313720D01*
X683270Y313803D01*
X683687Y313720D01*
X684187Y313470D01*
G01X602700Y319240D02*
Y324240D01*
G01Y321740D02*
X603117Y322240D01*
X603617Y322490D01*
X604117Y322573D01*
X604867Y322407D01*
X605367Y322073D01*
X605700Y321490D01*
Y320823D01*
X605533Y320157D01*
X605200Y319657D01*
X604617Y319323D01*
X604117Y319240D01*
X603617Y319323D01*
X603117Y319573D01*
X602700Y319990D01*
G01X608383Y322573D02*
Y320240D01*
X608717Y319657D01*
X609217Y319323D01*
X609800Y319240D01*
X610383Y319323D01*
X610883Y319657D01*
X611217Y320240D01*
G01Y319240D02*
Y322573D01*
G01X615400Y324240D02*
Y319240D01*
G01X614233Y322573D02*
X616567D01*
G01X627267Y321907D02*
X627600Y322157D01*
X627850Y322573D01*
X628017Y323157D01*
X627850Y323657D01*
X627517Y323990D01*
X626933Y324240D01*
X624683D01*
Y319240D01*
X627433D01*
X628017Y319573D01*
X628350Y320073D01*
X628517Y320657D01*
X628350Y321240D01*
X627850Y321740D01*
X627267Y321907D01*
X624683D01*
G01X639300Y324240D02*
Y319240D01*
G01Y319990D02*
X638967Y319573D01*
X638467Y319323D01*
X637883Y319240D01*
X637217Y319407D01*
X636717Y319823D01*
X636383Y320323D01*
X636300Y320907D01*
X636383Y321490D01*
X636717Y321990D01*
X637217Y322407D01*
X637883Y322573D01*
X638467Y322490D01*
X638883Y322323D01*
X639300Y321990D01*
G01X643400Y322573D02*
Y319240D01*
G01Y323907D02*
X643233Y323990D01*
Y324157D01*
X643400Y324240D01*
X643567Y324157D01*
Y323990D01*
X643400Y323907D01*
G01X650500Y319240D02*
Y322573D01*
G01Y321990D02*
X650167Y322323D01*
X649667Y322490D01*
X649083Y322573D01*
X648500Y322407D01*
X648000Y322073D01*
X647667Y321573D01*
X647500Y320907D01*
X647667Y320240D01*
X648000Y319740D01*
X648500Y319407D01*
X649083Y319240D01*
X649667Y319323D01*
X650167Y319573D01*
X650500Y319907D01*
G01X652100Y319240D02*
Y322573D01*
G01Y321657D02*
X652350Y322073D01*
X652767Y322407D01*
X653350Y322573D01*
X653933Y322407D01*
X654350Y322073D01*
X654600Y321657D01*
Y319240D01*
G01Y321657D02*
X654850Y322073D01*
X655267Y322407D01*
X655850Y322573D01*
X656433Y322407D01*
X656850Y322073D01*
X657100Y321573D01*
Y319240D01*
G01X658950Y321490D02*
X661617D01*
X661367Y322073D01*
X660950Y322407D01*
X660367Y322573D01*
X659783Y322490D01*
X659283Y322240D01*
X658950Y321657D01*
X658783Y321157D01*
Y320657D01*
X658950Y320157D01*
X659367Y319657D01*
X659867Y319323D01*
X660450Y319240D01*
X661033Y319407D01*
X661617Y319907D01*
G01X665800Y324240D02*
Y319240D01*
G01X664633Y322573D02*
X666967D01*
G01X670150Y321490D02*
X672817D01*
X672567Y322073D01*
X672150Y322407D01*
X671567Y322573D01*
X670983Y322490D01*
X670483Y322240D01*
X670150Y321657D01*
X669983Y321157D01*
Y320657D01*
X670150Y320157D01*
X670567Y319657D01*
X671067Y319323D01*
X671650Y319240D01*
X672233Y319407D01*
X672817Y319907D01*
G01X675833Y319240D02*
Y322573D01*
G01Y321907D02*
X676250Y322240D01*
X676667Y322490D01*
X677250Y322573D01*
X677667Y322490D01*
X678167Y322240D01*
G01X608397Y295230D02*
X605063Y296897D01*
X608397Y298563D01*
G01X610913Y295813D02*
X611497Y295397D01*
X612163Y295230D01*
X612830Y295397D01*
X613413Y295897D01*
X613830Y296647D01*
X613997Y297397D01*
Y298313D01*
X613830Y299063D01*
X613413Y299730D01*
X612913Y300063D01*
X612330Y300230D01*
X611663Y300063D01*
X611163Y299730D01*
X610830Y299230D01*
X610663Y298563D01*
X610830Y297980D01*
X611247Y297397D01*
X611747Y297063D01*
X612330Y296980D01*
X612997Y297147D01*
X613497Y297563D01*
X613997Y298313D01*
G01X617930Y300230D02*
X617263Y300063D01*
X616763Y299647D01*
X616430Y299147D01*
X616180Y298480D01*
X616097Y297730D01*
X616180Y296980D01*
X616430Y296313D01*
X616763Y295813D01*
X617263Y295397D01*
X617930Y295230D01*
X618597Y295397D01*
X619097Y295813D01*
X619430Y296313D01*
X619680Y296980D01*
X619763Y297730D01*
X619680Y298480D01*
X619430Y299147D01*
X619097Y299647D01*
X618597Y300063D01*
X617930Y300230D01*
G01X630630D02*
Y295230D01*
G01Y295980D02*
X630297Y295563D01*
X629797Y295313D01*
X629213Y295230D01*
X628547Y295397D01*
X628047Y295813D01*
X627713Y296313D01*
X627630Y296897D01*
X627713Y297480D01*
X628047Y297980D01*
X628547Y298397D01*
X629213Y298563D01*
X629797Y298480D01*
X630213Y298313D01*
X630630Y297980D01*
G01X633480Y297480D02*
X636147D01*
X635897Y298063D01*
X635480Y298397D01*
X634897Y298563D01*
X634313Y298480D01*
X633813Y298230D01*
X633480Y297647D01*
X633313Y297147D01*
Y296647D01*
X633480Y296147D01*
X633897Y295647D01*
X634397Y295313D01*
X634980Y295230D01*
X635563Y295397D01*
X636147Y295897D01*
G01X639163Y293980D02*
X639747Y293647D01*
X640413Y293563D01*
X640997Y293647D01*
X641497Y294063D01*
X641830Y294647D01*
Y298563D01*
G01Y297897D02*
X641497Y298230D01*
X640997Y298480D01*
X640413Y298563D01*
X639747Y298397D01*
X639330Y298063D01*
X638997Y297480D01*
X638830Y296897D01*
X638913Y296397D01*
X639247Y295813D01*
X639747Y295397D01*
X640413Y295230D01*
X640913Y295313D01*
X641497Y295647D01*
X641830Y295980D01*
G01X644763Y295230D02*
Y298563D01*
G01Y297897D02*
X645180Y298230D01*
X645597Y298480D01*
X646180Y298563D01*
X646597Y298480D01*
X647097Y298230D01*
G01X650280Y297480D02*
X652947D01*
X652697Y298063D01*
X652280Y298397D01*
X651697Y298563D01*
X651113Y298480D01*
X650613Y298230D01*
X650280Y297647D01*
X650113Y297147D01*
Y296647D01*
X650280Y296147D01*
X650697Y295647D01*
X651197Y295313D01*
X651780Y295230D01*
X652363Y295397D01*
X652947Y295897D01*
G01X655880Y297480D02*
X658547D01*
X658297Y298063D01*
X657880Y298397D01*
X657297Y298563D01*
X656713Y298480D01*
X656213Y298230D01*
X655880Y297647D01*
X655713Y297147D01*
Y296647D01*
X655880Y296147D01*
X656297Y295647D01*
X656797Y295313D01*
X657380Y295230D01*
X657963Y295397D01*
X658547Y295897D01*
G01X603783Y329260D02*
X607117Y330927D01*
X603783Y332593D01*
G01X609967Y330177D02*
X612133D01*
G01Y331677D02*
X609967D01*
G01X616483Y329260D02*
X616650Y330343D01*
X616900Y331260D01*
X617233Y332093D01*
X617650Y333010D01*
X618317Y334260D01*
X614983D01*
G01X622250D02*
X621583Y334093D01*
X621083Y333677D01*
X620750Y333177D01*
X620500Y332510D01*
X620417Y331760D01*
X620500Y331010D01*
X620750Y330343D01*
X621083Y329843D01*
X621583Y329427D01*
X622250Y329260D01*
X622917Y329427D01*
X623417Y329843D01*
X623750Y330343D01*
X624000Y331010D01*
X624083Y331760D01*
X624000Y332510D01*
X623750Y333177D01*
X623417Y333677D01*
X622917Y334093D01*
X622250Y334260D01*
G01X626350Y329093D02*
X629350Y334260D01*
G01X626350D02*
X625850Y334093D01*
X625600Y333843D01*
X625433Y333343D01*
X625600Y332843D01*
X625850Y332593D01*
X626350Y332427D01*
X626850Y332593D01*
X627100Y332843D01*
X627267Y333343D01*
X627100Y333843D01*
X626850Y334093D01*
X626350Y334260D01*
G01X629350Y330927D02*
X628850Y330760D01*
X628600Y330510D01*
X628433Y330010D01*
X628600Y329510D01*
X628850Y329260D01*
X629350Y329093D01*
X629850Y329260D01*
X630100Y329510D01*
X630267Y330010D01*
X630100Y330510D01*
X629850Y330760D01*
X629350Y330927D01*
G01X633283Y328343D02*
X633617Y329427D01*
G01X602120Y310470D02*
Y313803D01*
G01Y312887D02*
X602370Y313303D01*
X602787Y313637D01*
X603370Y313803D01*
X603953Y313637D01*
X604370Y313303D01*
X604620Y312887D01*
Y310470D01*
G01Y312887D02*
X604870Y313303D01*
X605287Y313637D01*
X605870Y313803D01*
X606453Y313637D01*
X606870Y313303D01*
X607120Y312803D01*
Y310470D01*
G01X608803Y313803D02*
Y311470D01*
X609137Y310887D01*
X609637Y310553D01*
X610220Y310470D01*
X610803Y310553D01*
X611303Y310887D01*
X611637Y311470D01*
G01Y310470D02*
Y313803D01*
G01X614570Y311053D02*
X614987Y310720D01*
X615570Y310470D01*
X616070D01*
X616570Y310637D01*
X616903Y310887D01*
X617070Y311220D01*
X616987Y311720D01*
X616653Y311970D01*
X615153Y312470D01*
X614820Y313053D01*
X614987Y313470D01*
X615320Y313720D01*
X615820Y313803D01*
X616320Y313720D01*
X616820Y313470D01*
G01X621420Y315470D02*
Y310470D01*
G01X620253Y313803D02*
X622587D01*
G01X628687Y310470D02*
X625353Y312137D01*
X628687Y313803D01*
G01X630537Y310470D02*
X632620Y315470D01*
X634703Y310470D01*
G01X633953Y312220D02*
X631287D01*
G01X645320Y315470D02*
Y310470D01*
G01Y311220D02*
X644987Y310803D01*
X644487Y310553D01*
X643903Y310470D01*
X643237Y310637D01*
X642737Y311053D01*
X642403Y311553D01*
X642320Y312137D01*
X642403Y312720D01*
X642737Y313220D01*
X643237Y313637D01*
X643903Y313803D01*
X644487Y313720D01*
X644903Y313553D01*
X645320Y313220D01*
G01X649420Y313803D02*
Y310470D01*
G01Y315137D02*
X649253Y315220D01*
Y315387D01*
X649420Y315470D01*
X649587Y315387D01*
Y315220D01*
X649420Y315137D01*
G01X656520Y310470D02*
Y313803D01*
G01Y313220D02*
X656187Y313553D01*
X655687Y313720D01*
X655103Y313803D01*
X654520Y313637D01*
X654020Y313303D01*
X653687Y312803D01*
X653520Y312137D01*
X653687Y311470D01*
X654020Y310970D01*
X654520Y310637D01*
X655103Y310470D01*
X655687Y310553D01*
X656187Y310803D01*
X656520Y311137D01*
G01X658120Y310470D02*
Y313803D01*
G01Y312887D02*
X658370Y313303D01*
X658787Y313637D01*
X659370Y313803D01*
X659953Y313637D01*
X660370Y313303D01*
X660620Y312887D01*
Y310470D01*
G01Y312887D02*
X660870Y313303D01*
X661287Y313637D01*
X661870Y313803D01*
X662453Y313637D01*
X662870Y313303D01*
X663120Y312803D01*
Y310470D01*
G01X664970Y312720D02*
X667637D01*
X667387Y313303D01*
X666970Y313637D01*
X666387Y313803D01*
X665803Y313720D01*
X665303Y313470D01*
X664970Y312887D01*
X664803Y312387D01*
Y311887D01*
X664970Y311387D01*
X665387Y310887D01*
X665887Y310553D01*
X666470Y310470D01*
X667053Y310637D01*
X667637Y311137D01*
G01X671820Y315470D02*
Y310470D01*
G01X670653Y313803D02*
X672987D01*
G01X676170Y312720D02*
X678837D01*
X678587Y313303D01*
X678170Y313637D01*
X677587Y313803D01*
X677003Y313720D01*
X676503Y313470D01*
X676170Y312887D01*
X676003Y312387D01*
Y311887D01*
X676170Y311387D01*
X676587Y310887D01*
X677087Y310553D01*
X677670Y310470D01*
X678253Y310637D01*
X678837Y311137D01*
G01X681853Y310470D02*
Y313803D01*
G01Y313137D02*
X682270Y313470D01*
X682687Y313720D01*
X683270Y313803D01*
X683687Y313720D01*
X684187Y313470D01*
G01X602700Y319240D02*
Y324240D01*
G01Y321740D02*
X603117Y322240D01*
X603617Y322490D01*
X604117Y322573D01*
X604867Y322407D01*
X605367Y322073D01*
X605700Y321490D01*
Y320823D01*
X605533Y320157D01*
X605200Y319657D01*
X604617Y319323D01*
X604117Y319240D01*
X603617Y319323D01*
X603117Y319573D01*
X602700Y319990D01*
G01X608383Y322573D02*
Y320240D01*
X608717Y319657D01*
X609217Y319323D01*
X609800Y319240D01*
X610383Y319323D01*
X610883Y319657D01*
X611217Y320240D01*
G01Y319240D02*
Y322573D01*
G01X615400Y324240D02*
Y319240D01*
G01X614233Y322573D02*
X616567D01*
G01X627267Y321907D02*
X627600Y322157D01*
X627850Y322573D01*
X628017Y323157D01*
X627850Y323657D01*
X627517Y323990D01*
X626933Y324240D01*
X624683D01*
Y319240D01*
X627433D01*
X628017Y319573D01*
X628350Y320073D01*
X628517Y320657D01*
X628350Y321240D01*
X627850Y321740D01*
X627267Y321907D01*
X624683D01*
G01X639300Y324240D02*
Y319240D01*
G01Y319990D02*
X638967Y319573D01*
X638467Y319323D01*
X637883Y319240D01*
X637217Y319407D01*
X636717Y319823D01*
X636383Y320323D01*
X636300Y320907D01*
X636383Y321490D01*
X636717Y321990D01*
X637217Y322407D01*
X637883Y322573D01*
X638467Y322490D01*
X638883Y322323D01*
X639300Y321990D01*
G01X643400Y322573D02*
Y319240D01*
G01Y323907D02*
X643233Y323990D01*
Y324157D01*
X643400Y324240D01*
X643567Y324157D01*
Y323990D01*
X643400Y323907D01*
G01X650500Y319240D02*
Y322573D01*
G01Y321990D02*
X650167Y322323D01*
X649667Y322490D01*
X649083Y322573D01*
X648500Y322407D01*
X648000Y322073D01*
X647667Y321573D01*
X647500Y320907D01*
X647667Y320240D01*
X648000Y319740D01*
X648500Y319407D01*
X649083Y319240D01*
X649667Y319323D01*
X650167Y319573D01*
X650500Y319907D01*
G01X652100Y319240D02*
Y322573D01*
G01Y321657D02*
X652350Y322073D01*
X652767Y322407D01*
X653350Y322573D01*
X653933Y322407D01*
X654350Y322073D01*
X654600Y321657D01*
Y319240D01*
G01Y321657D02*
X654850Y322073D01*
X655267Y322407D01*
X655850Y322573D01*
X656433Y322407D01*
X656850Y322073D01*
X657100Y321573D01*
Y319240D01*
G01X658950Y321490D02*
X661617D01*
X661367Y322073D01*
X660950Y322407D01*
X660367Y322573D01*
X659783Y322490D01*
X659283Y322240D01*
X658950Y321657D01*
X658783Y321157D01*
Y320657D01*
X658950Y320157D01*
X659367Y319657D01*
X659867Y319323D01*
X660450Y319240D01*
X661033Y319407D01*
X661617Y319907D01*
G01X665800Y324240D02*
Y319240D01*
G01X664633Y322573D02*
X666967D01*
G01X670150Y321490D02*
X672817D01*
X672567Y322073D01*
X672150Y322407D01*
X671567Y322573D01*
X670983Y322490D01*
X670483Y322240D01*
X670150Y321657D01*
X669983Y321157D01*
Y320657D01*
X670150Y320157D01*
X670567Y319657D01*
X671067Y319323D01*
X671650Y319240D01*
X672233Y319407D01*
X672817Y319907D01*
G01X675833Y319240D02*
Y322573D01*
G01Y321907D02*
X676250Y322240D01*
X676667Y322490D01*
X677250Y322573D01*
X677667Y322490D01*
X678167Y322240D01*
G01X608397Y295230D02*
X605063Y296897D01*
X608397Y298563D01*
G01X610913Y295813D02*
X611497Y295397D01*
X612163Y295230D01*
X612830Y295397D01*
X613413Y295897D01*
X613830Y296647D01*
X613997Y297397D01*
Y298313D01*
X613830Y299063D01*
X613413Y299730D01*
X612913Y300063D01*
X612330Y300230D01*
X611663Y300063D01*
X611163Y299730D01*
X610830Y299230D01*
X610663Y298563D01*
X610830Y297980D01*
X611247Y297397D01*
X611747Y297063D01*
X612330Y296980D01*
X612997Y297147D01*
X613497Y297563D01*
X613997Y298313D01*
G01X617930Y300230D02*
X617263Y300063D01*
X616763Y299647D01*
X616430Y299147D01*
X616180Y298480D01*
X616097Y297730D01*
X616180Y296980D01*
X616430Y296313D01*
X616763Y295813D01*
X617263Y295397D01*
X617930Y295230D01*
X618597Y295397D01*
X619097Y295813D01*
X619430Y296313D01*
X619680Y296980D01*
X619763Y297730D01*
X619680Y298480D01*
X619430Y299147D01*
X619097Y299647D01*
X618597Y300063D01*
X617930Y300230D01*
G01X630630D02*
Y295230D01*
G01Y295980D02*
X630297Y295563D01*
X629797Y295313D01*
X629213Y295230D01*
X628547Y295397D01*
X628047Y295813D01*
X627713Y296313D01*
X627630Y296897D01*
X627713Y297480D01*
X628047Y297980D01*
X628547Y298397D01*
X629213Y298563D01*
X629797Y298480D01*
X630213Y298313D01*
X630630Y297980D01*
G01X633480Y297480D02*
X636147D01*
X635897Y298063D01*
X635480Y298397D01*
X634897Y298563D01*
X634313Y298480D01*
X633813Y298230D01*
X633480Y297647D01*
X633313Y297147D01*
Y296647D01*
X633480Y296147D01*
X633897Y295647D01*
X634397Y295313D01*
X634980Y295230D01*
X635563Y295397D01*
X636147Y295897D01*
G01X639163Y293980D02*
X639747Y293647D01*
X640413Y293563D01*
X640997Y293647D01*
X641497Y294063D01*
X641830Y294647D01*
Y298563D01*
G01Y297897D02*
X641497Y298230D01*
X640997Y298480D01*
X640413Y298563D01*
X639747Y298397D01*
X639330Y298063D01*
X638997Y297480D01*
X638830Y296897D01*
X638913Y296397D01*
X639247Y295813D01*
X639747Y295397D01*
X640413Y295230D01*
X640913Y295313D01*
X641497Y295647D01*
X641830Y295980D01*
G01X644763Y295230D02*
Y298563D01*
G01Y297897D02*
X645180Y298230D01*
X645597Y298480D01*
X646180Y298563D01*
X646597Y298480D01*
X647097Y298230D01*
G01X650280Y297480D02*
X652947D01*
X652697Y298063D01*
X652280Y298397D01*
X651697Y298563D01*
X651113Y298480D01*
X650613Y298230D01*
X650280Y297647D01*
X650113Y297147D01*
Y296647D01*
X650280Y296147D01*
X650697Y295647D01*
X651197Y295313D01*
X651780Y295230D01*
X652363Y295397D01*
X652947Y295897D01*
G01X655880Y297480D02*
X658547D01*
X658297Y298063D01*
X657880Y298397D01*
X657297Y298563D01*
X656713Y298480D01*
X656213Y298230D01*
X655880Y297647D01*
X655713Y297147D01*
Y296647D01*
X655880Y296147D01*
X656297Y295647D01*
X656797Y295313D01*
X657380Y295230D01*
X657963Y295397D01*
X658547Y295897D01*
G01X603783Y329260D02*
X607117Y330927D01*
X603783Y332593D01*
G01X609967Y330177D02*
X612133D01*
G01Y331677D02*
X609967D01*
G01X616483Y329260D02*
X616650Y330343D01*
X616900Y331260D01*
X617233Y332093D01*
X617650Y333010D01*
X618317Y334260D01*
X614983D01*
G01X622250D02*
X621583Y334093D01*
X621083Y333677D01*
X620750Y333177D01*
X620500Y332510D01*
X620417Y331760D01*
X620500Y331010D01*
X620750Y330343D01*
X621083Y329843D01*
X621583Y329427D01*
X622250Y329260D01*
X622917Y329427D01*
X623417Y329843D01*
X623750Y330343D01*
X624000Y331010D01*
X624083Y331760D01*
X624000Y332510D01*
X623750Y333177D01*
X623417Y333677D01*
X622917Y334093D01*
X622250Y334260D01*
G01X626350Y329093D02*
X629350Y334260D01*
G01X626350D02*
X625850Y334093D01*
X625600Y333843D01*
X625433Y333343D01*
X625600Y332843D01*
X625850Y332593D01*
X626350Y332427D01*
X626850Y332593D01*
X627100Y332843D01*
X627267Y333343D01*
X627100Y333843D01*
X626850Y334093D01*
X626350Y334260D01*
G01X629350Y330927D02*
X628850Y330760D01*
X628600Y330510D01*
X628433Y330010D01*
X628600Y329510D01*
X628850Y329260D01*
X629350Y329093D01*
X629850Y329260D01*
X630100Y329510D01*
X630267Y330010D01*
X630100Y330510D01*
X629850Y330760D01*
X629350Y330927D01*
G01X633283Y328343D02*
X633617Y329427D01*
G01X605763Y349687D02*
X607763D01*
G01X606680Y350770D02*
Y348603D01*
G01X610780Y347853D02*
X613780Y353020D01*
G01X616797Y349687D02*
X618963D01*
G01X623480Y348020D02*
Y353020D01*
X622480Y352020D01*
G01Y348020D02*
X624480D01*
G01X626580D02*
Y351353D01*
G01Y350437D02*
X626830Y350853D01*
X627247Y351187D01*
X627830Y351353D01*
X628413Y351187D01*
X628830Y350853D01*
X629080Y350437D01*
Y348020D01*
G01Y350437D02*
X629330Y350853D01*
X629747Y351187D01*
X630330Y351353D01*
X630913Y351187D01*
X631330Y350853D01*
X631580Y350353D01*
Y348020D01*
G01X634680Y351353D02*
Y348020D01*
G01Y352687D02*
X634513Y352770D01*
Y352937D01*
X634680Y353020D01*
X634847Y352937D01*
Y352770D01*
X634680Y352687D01*
G01X640280Y348020D02*
Y353020D01*
G01X608333Y393000D02*
Y398000D01*
X610500Y393833D01*
X612667Y398000D01*
Y393000D01*
G01X614683Y396333D02*
Y394000D01*
X615017Y393417D01*
X615517Y393083D01*
X616100Y393000D01*
X616683Y393083D01*
X617183Y393417D01*
X617517Y394000D01*
G01Y393000D02*
Y396333D01*
G01X620450Y393583D02*
X620867Y393250D01*
X621450Y393000D01*
X621950D01*
X622450Y393167D01*
X622783Y393417D01*
X622950Y393750D01*
X622867Y394250D01*
X622533Y394500D01*
X621033Y395000D01*
X620700Y395583D01*
X620867Y396000D01*
X621200Y396250D01*
X621700Y396333D01*
X622200Y396250D01*
X622700Y396000D01*
G01X627300Y398000D02*
Y393000D01*
G01X626133Y396333D02*
X628467D01*
G01X638000Y393000D02*
Y397250D01*
X638167Y397667D01*
X638500Y397917D01*
X639000Y398000D01*
X639500Y397833D01*
X639750Y397417D01*
G01X638750Y396000D02*
X637083D01*
G01X644100Y393000D02*
X643600Y393083D01*
X643100Y393417D01*
X642767Y394000D01*
X642600Y394667D01*
X642767Y395333D01*
X643100Y395917D01*
X643600Y396250D01*
X644100Y396333D01*
X644600Y396250D01*
X645100Y395917D01*
X645433Y395333D01*
X645517Y394667D01*
X645433Y394000D01*
X645100Y393417D01*
X644600Y393083D01*
X644100Y393000D01*
G01X649700D02*
Y398000D01*
G01X655300Y393000D02*
Y398000D01*
G01X660900Y393000D02*
X660400Y393083D01*
X659900Y393417D01*
X659567Y394000D01*
X659400Y394667D01*
X659567Y395333D01*
X659900Y395917D01*
X660400Y396250D01*
X660900Y396333D01*
X661400Y396250D01*
X661900Y395917D01*
X662233Y395333D01*
X662317Y394667D01*
X662233Y394000D01*
X661900Y393417D01*
X661400Y393083D01*
X660900Y393000D01*
G01X664417Y396333D02*
X665417Y393000D01*
X666500Y396333D01*
X667583Y393000D01*
X668583Y396333D01*
G01X595500Y679000D02*
Y396000D01*
G01X605763Y349687D02*
X607763D01*
G01X606680Y350770D02*
Y348603D01*
G01X610780Y347853D02*
X613780Y353020D01*
G01X616797Y349687D02*
X618963D01*
G01X623480Y348020D02*
Y353020D01*
X622480Y352020D01*
G01Y348020D02*
X624480D01*
G01X626580D02*
Y351353D01*
G01Y350437D02*
X626830Y350853D01*
X627247Y351187D01*
X627830Y351353D01*
X628413Y351187D01*
X628830Y350853D01*
X629080Y350437D01*
Y348020D01*
G01Y350437D02*
X629330Y350853D01*
X629747Y351187D01*
X630330Y351353D01*
X630913Y351187D01*
X631330Y350853D01*
X631580Y350353D01*
Y348020D01*
G01X634680Y351353D02*
Y348020D01*
G01Y352687D02*
X634513Y352770D01*
Y352937D01*
X634680Y353020D01*
X634847Y352937D01*
Y352770D01*
X634680Y352687D01*
G01X640280Y348020D02*
Y353020D01*
G01X608333Y393000D02*
Y398000D01*
X610500Y393833D01*
X612667Y398000D01*
Y393000D01*
G01X614683Y396333D02*
Y394000D01*
X615017Y393417D01*
X615517Y393083D01*
X616100Y393000D01*
X616683Y393083D01*
X617183Y393417D01*
X617517Y394000D01*
G01Y393000D02*
Y396333D01*
G01X620450Y393583D02*
X620867Y393250D01*
X621450Y393000D01*
X621950D01*
X622450Y393167D01*
X622783Y393417D01*
X622950Y393750D01*
X622867Y394250D01*
X622533Y394500D01*
X621033Y395000D01*
X620700Y395583D01*
X620867Y396000D01*
X621200Y396250D01*
X621700Y396333D01*
X622200Y396250D01*
X622700Y396000D01*
G01X627300Y398000D02*
Y393000D01*
G01X626133Y396333D02*
X628467D01*
G01X638000Y393000D02*
Y397250D01*
X638167Y397667D01*
X638500Y397917D01*
X639000Y398000D01*
X639500Y397833D01*
X639750Y397417D01*
G01X638750Y396000D02*
X637083D01*
G01X644100Y393000D02*
X643600Y393083D01*
X643100Y393417D01*
X642767Y394000D01*
X642600Y394667D01*
X642767Y395333D01*
X643100Y395917D01*
X643600Y396250D01*
X644100Y396333D01*
X644600Y396250D01*
X645100Y395917D01*
X645433Y395333D01*
X645517Y394667D01*
X645433Y394000D01*
X645100Y393417D01*
X644600Y393083D01*
X644100Y393000D01*
G01X649700D02*
Y398000D01*
G01X655300Y393000D02*
Y398000D01*
G01X660900Y393000D02*
X660400Y393083D01*
X659900Y393417D01*
X659567Y394000D01*
X659400Y394667D01*
X659567Y395333D01*
X659900Y395917D01*
X660400Y396250D01*
X660900Y396333D01*
X661400Y396250D01*
X661900Y395917D01*
X662233Y395333D01*
X662317Y394667D01*
X662233Y394000D01*
X661900Y393417D01*
X661400Y393083D01*
X660900Y393000D01*
G01X664417Y396333D02*
X665417Y393000D01*
X666500Y396333D01*
X667583Y393000D01*
X668583Y396333D01*
G01X595500Y679000D02*
Y396000D01*
G01X605810Y429990D02*
Y434240D01*
X605977Y434657D01*
X606310Y434907D01*
X606810Y434990D01*
X607310Y434823D01*
X607560Y434407D01*
G01X606560Y432990D02*
X604893D01*
G01X611910Y429990D02*
X611410Y430073D01*
X610910Y430407D01*
X610577Y430990D01*
X610410Y431657D01*
X610577Y432323D01*
X610910Y432907D01*
X611410Y433240D01*
X611910Y433323D01*
X612410Y433240D01*
X612910Y432907D01*
X613243Y432323D01*
X613327Y431657D01*
X613243Y430990D01*
X612910Y430407D01*
X612410Y430073D01*
X611910Y429990D01*
G01X617510D02*
Y434990D01*
G01X623110Y429990D02*
Y434990D01*
G01X628710Y429990D02*
X628210Y430073D01*
X627710Y430407D01*
X627377Y430990D01*
X627210Y431657D01*
X627377Y432323D01*
X627710Y432907D01*
X628210Y433240D01*
X628710Y433323D01*
X629210Y433240D01*
X629710Y432907D01*
X630043Y432323D01*
X630127Y431657D01*
X630043Y430990D01*
X629710Y430407D01*
X629210Y430073D01*
X628710Y429990D01*
G01X632227Y433323D02*
X633227Y429990D01*
X634310Y433323D01*
X635393Y429990D01*
X636393Y433323D01*
G01X647010Y434990D02*
Y429990D01*
G01Y430740D02*
X646677Y430323D01*
X646177Y430073D01*
X645593Y429990D01*
X644927Y430157D01*
X644427Y430573D01*
X644093Y431073D01*
X644010Y431657D01*
X644093Y432240D01*
X644427Y432740D01*
X644927Y433157D01*
X645593Y433323D01*
X646177Y433240D01*
X646593Y433073D01*
X647010Y432740D01*
G01X649943Y429990D02*
Y433323D01*
G01Y432657D02*
X650360Y432990D01*
X650777Y433240D01*
X651360Y433323D01*
X651777Y433240D01*
X652277Y432990D01*
G01X658210Y429990D02*
Y433323D01*
G01Y432740D02*
X657877Y433073D01*
X657377Y433240D01*
X656793Y433323D01*
X656210Y433157D01*
X655710Y432823D01*
X655377Y432323D01*
X655210Y431657D01*
X655377Y430990D01*
X655710Y430490D01*
X656210Y430157D01*
X656793Y429990D01*
X657377Y430073D01*
X657877Y430323D01*
X658210Y430657D01*
G01X660227Y433323D02*
X661227Y429990D01*
X662310Y433323D01*
X663393Y429990D01*
X664393Y433323D01*
G01X667910D02*
Y429990D01*
G01Y434657D02*
X667743Y434740D01*
Y434907D01*
X667910Y434990D01*
X668077Y434907D01*
Y434740D01*
X667910Y434657D01*
G01X672093Y429990D02*
Y433323D01*
G01Y432490D02*
X672427Y432907D01*
X672927Y433240D01*
X673593Y433323D01*
X674177Y433240D01*
X674677Y432907D01*
X674927Y432323D01*
Y429990D01*
G01X677943Y428740D02*
X678527Y428407D01*
X679193Y428323D01*
X679777Y428407D01*
X680277Y428823D01*
X680610Y429407D01*
Y433323D01*
G01Y432657D02*
X680277Y432990D01*
X679777Y433240D01*
X679193Y433323D01*
X678527Y433157D01*
X678110Y432823D01*
X677777Y432240D01*
X677610Y431657D01*
X677693Y431157D01*
X678027Y430573D01*
X678527Y430157D01*
X679193Y429990D01*
X679693Y430073D01*
X680277Y430407D01*
X680610Y430740D01*
G01X685127Y428323D02*
X685960Y429157D01*
X686377Y429990D01*
Y433323D01*
X685960Y434157D01*
X685127Y434990D01*
G01X650853Y438153D02*
X650020Y438987D01*
X649603Y439820D01*
Y443153D01*
X650020Y443987D01*
X650853Y444820D01*
G01X656870Y439820D02*
X656370Y439903D01*
X655870Y440237D01*
X655537Y440820D01*
X655370Y441487D01*
X655537Y442153D01*
X655870Y442737D01*
X656370Y443070D01*
X656870Y443153D01*
X657370Y443070D01*
X657870Y442737D01*
X658203Y442153D01*
X658287Y441487D01*
X658203Y440820D01*
X657870Y440237D01*
X657370Y439903D01*
X656870Y439820D01*
G01X661303D02*
Y443153D01*
G01Y442487D02*
X661720Y442820D01*
X662137Y443070D01*
X662720Y443153D01*
X663137Y443070D01*
X663637Y442820D01*
G01X606903Y440587D02*
X608903D01*
G01X607820Y441670D02*
Y439503D01*
G01X611920Y438753D02*
X614920Y443920D01*
G01X617937Y440587D02*
X620103D01*
G01X622787Y439670D02*
X623287Y439253D01*
X623870Y439003D01*
X624620Y438920D01*
X625370Y439087D01*
X625953Y439420D01*
X626370Y440003D01*
X626453Y440670D01*
X626287Y441337D01*
X625870Y441753D01*
X625287Y442087D01*
X624703Y442170D01*
X624120Y442087D01*
X623370Y441753D01*
X623620Y443920D01*
X625870D01*
G01X627720Y438920D02*
Y442253D01*
G01Y441337D02*
X627970Y441753D01*
X628387Y442087D01*
X628970Y442253D01*
X629553Y442087D01*
X629970Y441753D01*
X630220Y441337D01*
Y438920D01*
G01Y441337D02*
X630470Y441753D01*
X630887Y442087D01*
X631470Y442253D01*
X632053Y442087D01*
X632470Y441753D01*
X632720Y441253D01*
Y438920D01*
G01X635820Y442253D02*
Y438920D01*
G01Y443587D02*
X635653Y443670D01*
Y443837D01*
X635820Y443920D01*
X635987Y443837D01*
Y443670D01*
X635820Y443587D01*
G01X641420Y438920D02*
Y443920D01*
G01X607500Y452000D02*
Y457000D01*
X606500Y456000D01*
G01Y452000D02*
X608500D01*
G01X613100Y451833D02*
X612933Y451917D01*
Y452083D01*
X613100Y452167D01*
X613267Y452083D01*
Y451917D01*
X613100Y451833D01*
G01X618700Y457000D02*
X618033Y456833D01*
X617533Y456417D01*
X617200Y455917D01*
X616950Y455250D01*
X616867Y454500D01*
X616950Y453750D01*
X617200Y453083D01*
X617533Y452583D01*
X618033Y452167D01*
X618700Y452000D01*
X619367Y452167D01*
X619867Y452583D01*
X620200Y453083D01*
X620450Y453750D01*
X620533Y454500D01*
X620450Y455250D01*
X620200Y455917D01*
X619867Y456417D01*
X619367Y456833D01*
X618700Y457000D01*
G01X621800Y452000D02*
Y455333D01*
G01Y454417D02*
X622050Y454833D01*
X622467Y455167D01*
X623050Y455333D01*
X623633Y455167D01*
X624050Y454833D01*
X624300Y454417D01*
Y452000D01*
G01Y454417D02*
X624550Y454833D01*
X624967Y455167D01*
X625550Y455333D01*
X626133Y455167D01*
X626550Y454833D01*
X626800Y454333D01*
Y452000D01*
G01X629900Y455333D02*
Y452000D01*
G01Y456667D02*
X629733Y456750D01*
Y456917D01*
X629900Y457000D01*
X630067Y456917D01*
Y456750D01*
X629900Y456667D01*
G01X635500Y452000D02*
Y457000D01*
G01X644200Y452000D02*
Y455333D01*
G01Y454417D02*
X644450Y454833D01*
X644867Y455167D01*
X645450Y455333D01*
X646033Y455167D01*
X646450Y454833D01*
X646700Y454417D01*
Y452000D01*
G01Y454417D02*
X646950Y454833D01*
X647367Y455167D01*
X647950Y455333D01*
X648533Y455167D01*
X648950Y454833D01*
X649200Y454333D01*
Y452000D01*
G01X653800D02*
Y455333D01*
G01Y454750D02*
X653467Y455083D01*
X652967Y455250D01*
X652383Y455333D01*
X651800Y455167D01*
X651300Y454833D01*
X650967Y454333D01*
X650800Y453667D01*
X650967Y453000D01*
X651300Y452500D01*
X651800Y452167D01*
X652383Y452000D01*
X652967Y452083D01*
X653467Y452333D01*
X653800Y452667D01*
G01X656650Y455333D02*
X659150Y452000D01*
G01Y455333D02*
X656650Y452000D01*
G01X606583Y471667D02*
X608583D01*
G01X607500Y472750D02*
Y470583D01*
G01X611600Y469833D02*
X614600Y475000D01*
G01X617617Y471667D02*
X619783D01*
G01X622467Y470750D02*
X622967Y470333D01*
X623550Y470083D01*
X624300Y470000D01*
X625050Y470167D01*
X625633Y470500D01*
X626050Y471083D01*
X626133Y471750D01*
X625967Y472417D01*
X625550Y472833D01*
X624967Y473167D01*
X624383Y473250D01*
X623800Y473167D01*
X623050Y472833D01*
X623300Y475000D01*
X625550D01*
G01X627400Y470000D02*
Y473333D01*
G01Y472417D02*
X627650Y472833D01*
X628067Y473167D01*
X628650Y473333D01*
X629233Y473167D01*
X629650Y472833D01*
X629900Y472417D01*
Y470000D01*
G01Y472417D02*
X630150Y472833D01*
X630567Y473167D01*
X631150Y473333D01*
X631733Y473167D01*
X632150Y472833D01*
X632400Y472333D01*
Y470000D01*
G01X635500Y473333D02*
Y470000D01*
G01Y474667D02*
X635333Y474750D01*
Y474917D01*
X635500Y475000D01*
X635667Y474917D01*
Y474750D01*
X635500Y474667D01*
G01X641100Y470000D02*
Y475000D01*
G01X606583Y486667D02*
X608583D01*
G01X607500Y487750D02*
Y485583D01*
G01X611600Y484833D02*
X614600Y490000D01*
G01X617617Y486667D02*
X619783D01*
G01X622467Y485750D02*
X622967Y485333D01*
X623550Y485083D01*
X624300Y485000D01*
X625050Y485167D01*
X625633Y485500D01*
X626050Y486083D01*
X626133Y486750D01*
X625967Y487417D01*
X625550Y487833D01*
X624967Y488167D01*
X624383Y488250D01*
X623800Y488167D01*
X623050Y487833D01*
X623300Y490000D01*
X625550D01*
G01X627400Y485000D02*
Y488333D01*
G01Y487417D02*
X627650Y487833D01*
X628067Y488167D01*
X628650Y488333D01*
X629233Y488167D01*
X629650Y487833D01*
X629900Y487417D01*
Y485000D01*
G01Y487417D02*
X630150Y487833D01*
X630567Y488167D01*
X631150Y488333D01*
X631733Y488167D01*
X632150Y487833D01*
X632400Y487333D01*
Y485000D01*
G01X635500Y488333D02*
Y485000D01*
G01Y489667D02*
X635333Y489750D01*
Y489917D01*
X635500Y490000D01*
X635667Y489917D01*
Y489750D01*
X635500Y489667D01*
G01X641100Y485000D02*
Y490000D01*
G01X606583Y501667D02*
X608583D01*
G01X607500Y502750D02*
Y500583D01*
G01X611267Y501000D02*
X611767Y500417D01*
X612433Y500083D01*
X613183Y500000D01*
X613850Y500083D01*
X614517Y500500D01*
X614933Y501000D01*
X615017Y501500D01*
X614850Y502083D01*
X614267Y502500D01*
X613683Y502667D01*
X612933D01*
G01X613683D02*
X614183Y502917D01*
X614600Y503333D01*
X614767Y503833D01*
X614600Y504333D01*
X614183Y504750D01*
X613433Y505000D01*
X612683Y504917D01*
X611933Y504583D01*
G01X617200Y499833D02*
X620200Y505000D01*
G01X623217Y501667D02*
X625383D01*
G01X629900Y505000D02*
X629233Y504833D01*
X628733Y504417D01*
X628400Y503917D01*
X628150Y503250D01*
X628067Y502500D01*
X628150Y501750D01*
X628400Y501083D01*
X628733Y500583D01*
X629233Y500167D01*
X629900Y500000D01*
X630567Y500167D01*
X631067Y500583D01*
X631400Y501083D01*
X631650Y501750D01*
X631733Y502500D01*
X631650Y503250D01*
X631400Y503917D01*
X631067Y504417D01*
X630567Y504833D01*
X629900Y505000D01*
G01X633000Y500000D02*
Y503333D01*
G01Y502417D02*
X633250Y502833D01*
X633667Y503167D01*
X634250Y503333D01*
X634833Y503167D01*
X635250Y502833D01*
X635500Y502417D01*
Y500000D01*
G01Y502417D02*
X635750Y502833D01*
X636167Y503167D01*
X636750Y503333D01*
X637333Y503167D01*
X637750Y502833D01*
X638000Y502333D01*
Y500000D01*
G01X641100Y503333D02*
Y500000D01*
G01Y504667D02*
X640933Y504750D01*
Y504917D01*
X641100Y505000D01*
X641267Y504917D01*
Y504750D01*
X641100Y504667D01*
G01X646700Y500000D02*
Y505000D01*
G01X605810Y429990D02*
Y434240D01*
X605977Y434657D01*
X606310Y434907D01*
X606810Y434990D01*
X607310Y434823D01*
X607560Y434407D01*
G01X606560Y432990D02*
X604893D01*
G01X611910Y429990D02*
X611410Y430073D01*
X610910Y430407D01*
X610577Y430990D01*
X610410Y431657D01*
X610577Y432323D01*
X610910Y432907D01*
X611410Y433240D01*
X611910Y433323D01*
X612410Y433240D01*
X612910Y432907D01*
X613243Y432323D01*
X613327Y431657D01*
X613243Y430990D01*
X612910Y430407D01*
X612410Y430073D01*
X611910Y429990D01*
G01X617510D02*
Y434990D01*
G01X623110Y429990D02*
Y434990D01*
G01X628710Y429990D02*
X628210Y430073D01*
X627710Y430407D01*
X627377Y430990D01*
X627210Y431657D01*
X627377Y432323D01*
X627710Y432907D01*
X628210Y433240D01*
X628710Y433323D01*
X629210Y433240D01*
X629710Y432907D01*
X630043Y432323D01*
X630127Y431657D01*
X630043Y430990D01*
X629710Y430407D01*
X629210Y430073D01*
X628710Y429990D01*
G01X632227Y433323D02*
X633227Y429990D01*
X634310Y433323D01*
X635393Y429990D01*
X636393Y433323D01*
G01X647010Y434990D02*
Y429990D01*
G01Y430740D02*
X646677Y430323D01*
X646177Y430073D01*
X645593Y429990D01*
X644927Y430157D01*
X644427Y430573D01*
X644093Y431073D01*
X644010Y431657D01*
X644093Y432240D01*
X644427Y432740D01*
X644927Y433157D01*
X645593Y433323D01*
X646177Y433240D01*
X646593Y433073D01*
X647010Y432740D01*
G01X649943Y429990D02*
Y433323D01*
G01Y432657D02*
X650360Y432990D01*
X650777Y433240D01*
X651360Y433323D01*
X651777Y433240D01*
X652277Y432990D01*
G01X658210Y429990D02*
Y433323D01*
G01Y432740D02*
X657877Y433073D01*
X657377Y433240D01*
X656793Y433323D01*
X656210Y433157D01*
X655710Y432823D01*
X655377Y432323D01*
X655210Y431657D01*
X655377Y430990D01*
X655710Y430490D01*
X656210Y430157D01*
X656793Y429990D01*
X657377Y430073D01*
X657877Y430323D01*
X658210Y430657D01*
G01X660227Y433323D02*
X661227Y429990D01*
X662310Y433323D01*
X663393Y429990D01*
X664393Y433323D01*
G01X667910D02*
Y429990D01*
G01Y434657D02*
X667743Y434740D01*
Y434907D01*
X667910Y434990D01*
X668077Y434907D01*
Y434740D01*
X667910Y434657D01*
G01X672093Y429990D02*
Y433323D01*
G01Y432490D02*
X672427Y432907D01*
X672927Y433240D01*
X673593Y433323D01*
X674177Y433240D01*
X674677Y432907D01*
X674927Y432323D01*
Y429990D01*
G01X677943Y428740D02*
X678527Y428407D01*
X679193Y428323D01*
X679777Y428407D01*
X680277Y428823D01*
X680610Y429407D01*
Y433323D01*
G01Y432657D02*
X680277Y432990D01*
X679777Y433240D01*
X679193Y433323D01*
X678527Y433157D01*
X678110Y432823D01*
X677777Y432240D01*
X677610Y431657D01*
X677693Y431157D01*
X678027Y430573D01*
X678527Y430157D01*
X679193Y429990D01*
X679693Y430073D01*
X680277Y430407D01*
X680610Y430740D01*
G01X685127Y428323D02*
X685960Y429157D01*
X686377Y429990D01*
Y433323D01*
X685960Y434157D01*
X685127Y434990D01*
G01X650853Y438153D02*
X650020Y438987D01*
X649603Y439820D01*
Y443153D01*
X650020Y443987D01*
X650853Y444820D01*
G01X656870Y439820D02*
X656370Y439903D01*
X655870Y440237D01*
X655537Y440820D01*
X655370Y441487D01*
X655537Y442153D01*
X655870Y442737D01*
X656370Y443070D01*
X656870Y443153D01*
X657370Y443070D01*
X657870Y442737D01*
X658203Y442153D01*
X658287Y441487D01*
X658203Y440820D01*
X657870Y440237D01*
X657370Y439903D01*
X656870Y439820D01*
G01X661303D02*
Y443153D01*
G01Y442487D02*
X661720Y442820D01*
X662137Y443070D01*
X662720Y443153D01*
X663137Y443070D01*
X663637Y442820D01*
G01X606903Y440587D02*
X608903D01*
G01X607820Y441670D02*
Y439503D01*
G01X611920Y438753D02*
X614920Y443920D01*
G01X617937Y440587D02*
X620103D01*
G01X622787Y439670D02*
X623287Y439253D01*
X623870Y439003D01*
X624620Y438920D01*
X625370Y439087D01*
X625953Y439420D01*
X626370Y440003D01*
X626453Y440670D01*
X626287Y441337D01*
X625870Y441753D01*
X625287Y442087D01*
X624703Y442170D01*
X624120Y442087D01*
X623370Y441753D01*
X623620Y443920D01*
X625870D01*
G01X627720Y438920D02*
Y442253D01*
G01Y441337D02*
X627970Y441753D01*
X628387Y442087D01*
X628970Y442253D01*
X629553Y442087D01*
X629970Y441753D01*
X630220Y441337D01*
Y438920D01*
G01Y441337D02*
X630470Y441753D01*
X630887Y442087D01*
X631470Y442253D01*
X632053Y442087D01*
X632470Y441753D01*
X632720Y441253D01*
Y438920D01*
G01X635820Y442253D02*
Y438920D01*
G01Y443587D02*
X635653Y443670D01*
Y443837D01*
X635820Y443920D01*
X635987Y443837D01*
Y443670D01*
X635820Y443587D01*
G01X641420Y438920D02*
Y443920D01*
G01X607500Y452000D02*
Y457000D01*
X606500Y456000D01*
G01Y452000D02*
X608500D01*
G01X613100Y451833D02*
X612933Y451917D01*
Y452083D01*
X613100Y452167D01*
X613267Y452083D01*
Y451917D01*
X613100Y451833D01*
G01X618700Y457000D02*
X618033Y456833D01*
X617533Y456417D01*
X617200Y455917D01*
X616950Y455250D01*
X616867Y454500D01*
X616950Y453750D01*
X617200Y453083D01*
X617533Y452583D01*
X618033Y452167D01*
X618700Y452000D01*
X619367Y452167D01*
X619867Y452583D01*
X620200Y453083D01*
X620450Y453750D01*
X620533Y454500D01*
X620450Y455250D01*
X620200Y455917D01*
X619867Y456417D01*
X619367Y456833D01*
X618700Y457000D01*
G01X621800Y452000D02*
Y455333D01*
G01Y454417D02*
X622050Y454833D01*
X622467Y455167D01*
X623050Y455333D01*
X623633Y455167D01*
X624050Y454833D01*
X624300Y454417D01*
Y452000D01*
G01Y454417D02*
X624550Y454833D01*
X624967Y455167D01*
X625550Y455333D01*
X626133Y455167D01*
X626550Y454833D01*
X626800Y454333D01*
Y452000D01*
G01X629900Y455333D02*
Y452000D01*
G01Y456667D02*
X629733Y456750D01*
Y456917D01*
X629900Y457000D01*
X630067Y456917D01*
Y456750D01*
X629900Y456667D01*
G01X635500Y452000D02*
Y457000D01*
G01X644200Y452000D02*
Y455333D01*
G01Y454417D02*
X644450Y454833D01*
X644867Y455167D01*
X645450Y455333D01*
X646033Y455167D01*
X646450Y454833D01*
X646700Y454417D01*
Y452000D01*
G01Y454417D02*
X646950Y454833D01*
X647367Y455167D01*
X647950Y455333D01*
X648533Y455167D01*
X648950Y454833D01*
X649200Y454333D01*
Y452000D01*
G01X653800D02*
Y455333D01*
G01Y454750D02*
X653467Y455083D01*
X652967Y455250D01*
X652383Y455333D01*
X651800Y455167D01*
X651300Y454833D01*
X650967Y454333D01*
X650800Y453667D01*
X650967Y453000D01*
X651300Y452500D01*
X651800Y452167D01*
X652383Y452000D01*
X652967Y452083D01*
X653467Y452333D01*
X653800Y452667D01*
G01X656650Y455333D02*
X659150Y452000D01*
G01Y455333D02*
X656650Y452000D01*
G01X606583Y471667D02*
X608583D01*
G01X607500Y472750D02*
Y470583D01*
G01X611600Y469833D02*
X614600Y475000D01*
G01X617617Y471667D02*
X619783D01*
G01X622467Y470750D02*
X622967Y470333D01*
X623550Y470083D01*
X624300Y470000D01*
X625050Y470167D01*
X625633Y470500D01*
X626050Y471083D01*
X626133Y471750D01*
X625967Y472417D01*
X625550Y472833D01*
X624967Y473167D01*
X624383Y473250D01*
X623800Y473167D01*
X623050Y472833D01*
X623300Y475000D01*
X625550D01*
G01X627400Y470000D02*
Y473333D01*
G01Y472417D02*
X627650Y472833D01*
X628067Y473167D01*
X628650Y473333D01*
X629233Y473167D01*
X629650Y472833D01*
X629900Y472417D01*
Y470000D01*
G01Y472417D02*
X630150Y472833D01*
X630567Y473167D01*
X631150Y473333D01*
X631733Y473167D01*
X632150Y472833D01*
X632400Y472333D01*
Y470000D01*
G01X635500Y473333D02*
Y470000D01*
G01Y474667D02*
X635333Y474750D01*
Y474917D01*
X635500Y475000D01*
X635667Y474917D01*
Y474750D01*
X635500Y474667D01*
G01X641100Y470000D02*
Y475000D01*
G01X606583Y486667D02*
X608583D01*
G01X607500Y487750D02*
Y485583D01*
G01X611600Y484833D02*
X614600Y490000D01*
G01X617617Y486667D02*
X619783D01*
G01X622467Y485750D02*
X622967Y485333D01*
X623550Y485083D01*
X624300Y485000D01*
X625050Y485167D01*
X625633Y485500D01*
X626050Y486083D01*
X626133Y486750D01*
X625967Y487417D01*
X625550Y487833D01*
X624967Y488167D01*
X624383Y488250D01*
X623800Y488167D01*
X623050Y487833D01*
X623300Y490000D01*
X625550D01*
G01X627400Y485000D02*
Y488333D01*
G01Y487417D02*
X627650Y487833D01*
X628067Y488167D01*
X628650Y488333D01*
X629233Y488167D01*
X629650Y487833D01*
X629900Y487417D01*
Y485000D01*
G01Y487417D02*
X630150Y487833D01*
X630567Y488167D01*
X631150Y488333D01*
X631733Y488167D01*
X632150Y487833D01*
X632400Y487333D01*
Y485000D01*
G01X635500Y488333D02*
Y485000D01*
G01Y489667D02*
X635333Y489750D01*
Y489917D01*
X635500Y490000D01*
X635667Y489917D01*
Y489750D01*
X635500Y489667D01*
G01X641100Y485000D02*
Y490000D01*
G01X606583Y501667D02*
X608583D01*
G01X607500Y502750D02*
Y500583D01*
G01X611267Y501000D02*
X611767Y500417D01*
X612433Y500083D01*
X613183Y500000D01*
X613850Y500083D01*
X614517Y500500D01*
X614933Y501000D01*
X615017Y501500D01*
X614850Y502083D01*
X614267Y502500D01*
X613683Y502667D01*
X612933D01*
G01X613683D02*
X614183Y502917D01*
X614600Y503333D01*
X614767Y503833D01*
X614600Y504333D01*
X614183Y504750D01*
X613433Y505000D01*
X612683Y504917D01*
X611933Y504583D01*
G01X617200Y499833D02*
X620200Y505000D01*
G01X623217Y501667D02*
X625383D01*
G01X629900Y505000D02*
X629233Y504833D01*
X628733Y504417D01*
X628400Y503917D01*
X628150Y503250D01*
X628067Y502500D01*
X628150Y501750D01*
X628400Y501083D01*
X628733Y500583D01*
X629233Y500167D01*
X629900Y500000D01*
X630567Y500167D01*
X631067Y500583D01*
X631400Y501083D01*
X631650Y501750D01*
X631733Y502500D01*
X631650Y503250D01*
X631400Y503917D01*
X631067Y504417D01*
X630567Y504833D01*
X629900Y505000D01*
G01X633000Y500000D02*
Y503333D01*
G01Y502417D02*
X633250Y502833D01*
X633667Y503167D01*
X634250Y503333D01*
X634833Y503167D01*
X635250Y502833D01*
X635500Y502417D01*
Y500000D01*
G01Y502417D02*
X635750Y502833D01*
X636167Y503167D01*
X636750Y503333D01*
X637333Y503167D01*
X637750Y502833D01*
X638000Y502333D01*
Y500000D01*
G01X641100Y503333D02*
Y500000D01*
G01Y504667D02*
X640933Y504750D01*
Y504917D01*
X641100Y505000D01*
X641267Y504917D01*
Y504750D01*
X641100Y504667D01*
G01X646700Y500000D02*
Y505000D01*
G01X606583Y546667D02*
X608583D01*
G01X607500Y547750D02*
Y545583D01*
G01X611600Y544833D02*
X614600Y550000D01*
G01X617617Y546667D02*
X619783D01*
G01X622717Y549167D02*
X623217Y549667D01*
X623800Y549917D01*
X624467Y550000D01*
X625300Y549833D01*
X625883Y549417D01*
X626050Y548917D01*
X625967Y548417D01*
X625633Y548000D01*
X623967Y547167D01*
X623217Y546583D01*
X622717Y545750D01*
X622550Y545000D01*
X626050D01*
G01X627400D02*
Y548333D01*
G01Y547417D02*
X627650Y547833D01*
X628067Y548167D01*
X628650Y548333D01*
X629233Y548167D01*
X629650Y547833D01*
X629900Y547417D01*
Y545000D01*
G01Y547417D02*
X630150Y547833D01*
X630567Y548167D01*
X631150Y548333D01*
X631733Y548167D01*
X632150Y547833D01*
X632400Y547333D01*
Y545000D01*
G01X635500Y548333D02*
Y545000D01*
G01Y549667D02*
X635333Y549750D01*
Y549917D01*
X635500Y550000D01*
X635667Y549917D01*
Y549750D01*
X635500Y549667D01*
G01X641100Y545000D02*
Y550000D01*
G01X606583Y516667D02*
X608583D01*
G01X607500Y517750D02*
Y515583D01*
G01X611600Y514833D02*
X614600Y520000D01*
G01X617617Y516667D02*
X619783D01*
G01X622717Y519167D02*
X623217Y519667D01*
X623800Y519917D01*
X624467Y520000D01*
X625300Y519833D01*
X625883Y519417D01*
X626050Y518917D01*
X625967Y518417D01*
X625633Y518000D01*
X623967Y517167D01*
X623217Y516583D01*
X622717Y515750D01*
X622550Y515000D01*
X626050D01*
G01X627400D02*
Y518333D01*
G01Y517417D02*
X627650Y517833D01*
X628067Y518167D01*
X628650Y518333D01*
X629233Y518167D01*
X629650Y517833D01*
X629900Y517417D01*
Y515000D01*
G01Y517417D02*
X630150Y517833D01*
X630567Y518167D01*
X631150Y518333D01*
X631733Y518167D01*
X632150Y517833D01*
X632400Y517333D01*
Y515000D01*
G01X635500Y518333D02*
Y515000D01*
G01Y519667D02*
X635333Y519750D01*
Y519917D01*
X635500Y520000D01*
X635667Y519917D01*
Y519750D01*
X635500Y519667D01*
G01X641100Y515000D02*
Y520000D01*
G01X606583Y530167D02*
X608583D01*
G01X607500Y531250D02*
Y529083D01*
G01X611600Y528333D02*
X614600Y533500D01*
G01X617617Y530167D02*
X619783D01*
G01X622467Y529500D02*
X622967Y528917D01*
X623633Y528583D01*
X624383Y528500D01*
X625050Y528583D01*
X625717Y529000D01*
X626133Y529500D01*
X626217Y530000D01*
X626050Y530583D01*
X625467Y531000D01*
X624883Y531167D01*
X624133D01*
G01X624883D02*
X625383Y531417D01*
X625800Y531833D01*
X625967Y532333D01*
X625800Y532833D01*
X625383Y533250D01*
X624633Y533500D01*
X623883Y533417D01*
X623133Y533083D01*
G01X627400Y528500D02*
Y531833D01*
G01Y530917D02*
X627650Y531333D01*
X628067Y531667D01*
X628650Y531833D01*
X629233Y531667D01*
X629650Y531333D01*
X629900Y530917D01*
Y528500D01*
G01Y530917D02*
X630150Y531333D01*
X630567Y531667D01*
X631150Y531833D01*
X631733Y531667D01*
X632150Y531333D01*
X632400Y530833D01*
Y528500D01*
G01X635500Y531833D02*
Y528500D01*
G01Y533167D02*
X635333Y533250D01*
Y533417D01*
X635500Y533500D01*
X635667Y533417D01*
Y533250D01*
X635500Y533167D01*
G01X641100Y528500D02*
Y533500D01*
G01X606583Y575167D02*
X608583D01*
G01X607500Y576250D02*
Y574083D01*
G01X611517Y577667D02*
X612017Y578167D01*
X612600Y578417D01*
X613267Y578500D01*
X614100Y578333D01*
X614683Y577917D01*
X614850Y577417D01*
X614767Y576917D01*
X614433Y576500D01*
X612767Y575667D01*
X612017Y575083D01*
X611517Y574250D01*
X611350Y573500D01*
X614850D01*
G01X617200Y573333D02*
X620200Y578500D01*
G01X623217Y575167D02*
X625383D01*
G01X630900Y573500D02*
Y578500D01*
X627817Y574917D01*
X631983D01*
G01X633000Y573500D02*
Y576833D01*
G01Y575917D02*
X633250Y576333D01*
X633667Y576667D01*
X634250Y576833D01*
X634833Y576667D01*
X635250Y576333D01*
X635500Y575917D01*
Y573500D01*
G01Y575917D02*
X635750Y576333D01*
X636167Y576667D01*
X636750Y576833D01*
X637333Y576667D01*
X637750Y576333D01*
X638000Y575833D01*
Y573500D01*
G01X641100Y576833D02*
Y573500D01*
G01Y578167D02*
X640933Y578250D01*
Y578417D01*
X641100Y578500D01*
X641267Y578417D01*
Y578250D01*
X641100Y578167D01*
G01X646700Y573500D02*
Y578500D01*
G01X606583Y561667D02*
X608583D01*
G01X607500Y562750D02*
Y560583D01*
G01X611600Y559833D02*
X614600Y565000D01*
G01X617617Y561667D02*
X619783D01*
G01X622717Y564167D02*
X623217Y564667D01*
X623800Y564917D01*
X624467Y565000D01*
X625300Y564833D01*
X625883Y564417D01*
X626050Y563917D01*
X625967Y563417D01*
X625633Y563000D01*
X623967Y562167D01*
X623217Y561583D01*
X622717Y560750D01*
X622550Y560000D01*
X626050D01*
G01X627400D02*
Y563333D01*
G01Y562417D02*
X627650Y562833D01*
X628067Y563167D01*
X628650Y563333D01*
X629233Y563167D01*
X629650Y562833D01*
X629900Y562417D01*
Y560000D01*
G01Y562417D02*
X630150Y562833D01*
X630567Y563167D01*
X631150Y563333D01*
X631733Y563167D01*
X632150Y562833D01*
X632400Y562333D01*
Y560000D01*
G01X635500Y563333D02*
Y560000D01*
G01Y564667D02*
X635333Y564750D01*
Y564917D01*
X635500Y565000D01*
X635667Y564917D01*
Y564750D01*
X635500Y564667D01*
G01X641100Y560000D02*
Y565000D01*
G01X606583Y546667D02*
X608583D01*
G01X607500Y547750D02*
Y545583D01*
G01X611600Y544833D02*
X614600Y550000D01*
G01X617617Y546667D02*
X619783D01*
G01X622717Y549167D02*
X623217Y549667D01*
X623800Y549917D01*
X624467Y550000D01*
X625300Y549833D01*
X625883Y549417D01*
X626050Y548917D01*
X625967Y548417D01*
X625633Y548000D01*
X623967Y547167D01*
X623217Y546583D01*
X622717Y545750D01*
X622550Y545000D01*
X626050D01*
G01X627400D02*
Y548333D01*
G01Y547417D02*
X627650Y547833D01*
X628067Y548167D01*
X628650Y548333D01*
X629233Y548167D01*
X629650Y547833D01*
X629900Y547417D01*
Y545000D01*
G01Y547417D02*
X630150Y547833D01*
X630567Y548167D01*
X631150Y548333D01*
X631733Y548167D01*
X632150Y547833D01*
X632400Y547333D01*
Y545000D01*
G01X635500Y548333D02*
Y545000D01*
G01Y549667D02*
X635333Y549750D01*
Y549917D01*
X635500Y550000D01*
X635667Y549917D01*
Y549750D01*
X635500Y549667D01*
G01X641100Y545000D02*
Y550000D01*
G01X606583Y516667D02*
X608583D01*
G01X607500Y517750D02*
Y515583D01*
G01X611600Y514833D02*
X614600Y520000D01*
G01X617617Y516667D02*
X619783D01*
G01X622717Y519167D02*
X623217Y519667D01*
X623800Y519917D01*
X624467Y520000D01*
X625300Y519833D01*
X625883Y519417D01*
X626050Y518917D01*
X625967Y518417D01*
X625633Y518000D01*
X623967Y517167D01*
X623217Y516583D01*
X622717Y515750D01*
X622550Y515000D01*
X626050D01*
G01X627400D02*
Y518333D01*
G01Y517417D02*
X627650Y517833D01*
X628067Y518167D01*
X628650Y518333D01*
X629233Y518167D01*
X629650Y517833D01*
X629900Y517417D01*
Y515000D01*
G01Y517417D02*
X630150Y517833D01*
X630567Y518167D01*
X631150Y518333D01*
X631733Y518167D01*
X632150Y517833D01*
X632400Y517333D01*
Y515000D01*
G01X635500Y518333D02*
Y515000D01*
G01Y519667D02*
X635333Y519750D01*
Y519917D01*
X635500Y520000D01*
X635667Y519917D01*
Y519750D01*
X635500Y519667D01*
G01X641100Y515000D02*
Y520000D01*
G01X606583Y530167D02*
X608583D01*
G01X607500Y531250D02*
Y529083D01*
G01X611600Y528333D02*
X614600Y533500D01*
G01X617617Y530167D02*
X619783D01*
G01X622467Y529500D02*
X622967Y528917D01*
X623633Y528583D01*
X624383Y528500D01*
X625050Y528583D01*
X625717Y529000D01*
X626133Y529500D01*
X626217Y530000D01*
X626050Y530583D01*
X625467Y531000D01*
X624883Y531167D01*
X624133D01*
G01X624883D02*
X625383Y531417D01*
X625800Y531833D01*
X625967Y532333D01*
X625800Y532833D01*
X625383Y533250D01*
X624633Y533500D01*
X623883Y533417D01*
X623133Y533083D01*
G01X627400Y528500D02*
Y531833D01*
G01Y530917D02*
X627650Y531333D01*
X628067Y531667D01*
X628650Y531833D01*
X629233Y531667D01*
X629650Y531333D01*
X629900Y530917D01*
Y528500D01*
G01Y530917D02*
X630150Y531333D01*
X630567Y531667D01*
X631150Y531833D01*
X631733Y531667D01*
X632150Y531333D01*
X632400Y530833D01*
Y528500D01*
G01X635500Y531833D02*
Y528500D01*
G01Y533167D02*
X635333Y533250D01*
Y533417D01*
X635500Y533500D01*
X635667Y533417D01*
Y533250D01*
X635500Y533167D01*
G01X641100Y528500D02*
Y533500D01*
G01X606583Y575167D02*
X608583D01*
G01X607500Y576250D02*
Y574083D01*
G01X611517Y577667D02*
X612017Y578167D01*
X612600Y578417D01*
X613267Y578500D01*
X614100Y578333D01*
X614683Y577917D01*
X614850Y577417D01*
X614767Y576917D01*
X614433Y576500D01*
X612767Y575667D01*
X612017Y575083D01*
X611517Y574250D01*
X611350Y573500D01*
X614850D01*
G01X617200Y573333D02*
X620200Y578500D01*
G01X623217Y575167D02*
X625383D01*
G01X630900Y573500D02*
Y578500D01*
X627817Y574917D01*
X631983D01*
G01X633000Y573500D02*
Y576833D01*
G01Y575917D02*
X633250Y576333D01*
X633667Y576667D01*
X634250Y576833D01*
X634833Y576667D01*
X635250Y576333D01*
X635500Y575917D01*
Y573500D01*
G01Y575917D02*
X635750Y576333D01*
X636167Y576667D01*
X636750Y576833D01*
X637333Y576667D01*
X637750Y576333D01*
X638000Y575833D01*
Y573500D01*
G01X641100Y576833D02*
Y573500D01*
G01Y578167D02*
X640933Y578250D01*
Y578417D01*
X641100Y578500D01*
X641267Y578417D01*
Y578250D01*
X641100Y578167D01*
G01X646700Y573500D02*
Y578500D01*
G01X606583Y561667D02*
X608583D01*
G01X607500Y562750D02*
Y560583D01*
G01X611600Y559833D02*
X614600Y565000D01*
G01X617617Y561667D02*
X619783D01*
G01X622717Y564167D02*
X623217Y564667D01*
X623800Y564917D01*
X624467Y565000D01*
X625300Y564833D01*
X625883Y564417D01*
X626050Y563917D01*
X625967Y563417D01*
X625633Y563000D01*
X623967Y562167D01*
X623217Y561583D01*
X622717Y560750D01*
X622550Y560000D01*
X626050D01*
G01X627400D02*
Y563333D01*
G01Y562417D02*
X627650Y562833D01*
X628067Y563167D01*
X628650Y563333D01*
X629233Y563167D01*
X629650Y562833D01*
X629900Y562417D01*
Y560000D01*
G01Y562417D02*
X630150Y562833D01*
X630567Y563167D01*
X631150Y563333D01*
X631733Y563167D01*
X632150Y562833D01*
X632400Y562333D01*
Y560000D01*
G01X635500Y563333D02*
Y560000D01*
G01Y564667D02*
X635333Y564750D01*
Y564917D01*
X635500Y565000D01*
X635667Y564917D01*
Y564750D01*
X635500Y564667D01*
G01X641100Y560000D02*
Y565000D01*
G01X606583Y620167D02*
X608583D01*
G01X607500Y621250D02*
Y619083D01*
G01X611600Y618333D02*
X614600Y623500D01*
G01X617617Y620167D02*
X619783D01*
G01X622717Y622667D02*
X623217Y623167D01*
X623800Y623417D01*
X624467Y623500D01*
X625300Y623333D01*
X625883Y622917D01*
X626050Y622417D01*
X625967Y621917D01*
X625633Y621500D01*
X623967Y620667D01*
X623217Y620083D01*
X622717Y619250D01*
X622550Y618500D01*
X626050D01*
G01X627400D02*
Y621833D01*
G01Y620917D02*
X627650Y621333D01*
X628067Y621667D01*
X628650Y621833D01*
X629233Y621667D01*
X629650Y621333D01*
X629900Y620917D01*
Y618500D01*
G01Y620917D02*
X630150Y621333D01*
X630567Y621667D01*
X631150Y621833D01*
X631733Y621667D01*
X632150Y621333D01*
X632400Y620833D01*
Y618500D01*
G01X635500Y621833D02*
Y618500D01*
G01Y623167D02*
X635333Y623250D01*
Y623417D01*
X635500Y623500D01*
X635667Y623417D01*
Y623250D01*
X635500Y623167D01*
G01X641100Y618500D02*
Y623500D01*
G01X606583Y591667D02*
X608583D01*
G01X607500Y592750D02*
Y590583D01*
G01X611600Y589833D02*
X614600Y595000D01*
G01X617617Y591667D02*
X619783D01*
G01X622467Y591000D02*
X622967Y590417D01*
X623633Y590083D01*
X624383Y590000D01*
X625050Y590083D01*
X625717Y590500D01*
X626133Y591000D01*
X626217Y591500D01*
X626050Y592083D01*
X625467Y592500D01*
X624883Y592667D01*
X624133D01*
G01X624883D02*
X625383Y592917D01*
X625800Y593333D01*
X625967Y593833D01*
X625800Y594333D01*
X625383Y594750D01*
X624633Y595000D01*
X623883Y594917D01*
X623133Y594583D01*
G01X627400Y590000D02*
Y593333D01*
G01Y592417D02*
X627650Y592833D01*
X628067Y593167D01*
X628650Y593333D01*
X629233Y593167D01*
X629650Y592833D01*
X629900Y592417D01*
Y590000D01*
G01Y592417D02*
X630150Y592833D01*
X630567Y593167D01*
X631150Y593333D01*
X631733Y593167D01*
X632150Y592833D01*
X632400Y592333D01*
Y590000D01*
G01X635500Y593333D02*
Y590000D01*
G01Y594667D02*
X635333Y594750D01*
Y594917D01*
X635500Y595000D01*
X635667Y594917D01*
Y594750D01*
X635500Y594667D01*
G01X641100Y590000D02*
Y595000D01*
G01X605417Y603500D02*
X607500Y608500D01*
X609583Y603500D01*
G01X608833Y605250D02*
X606167D01*
G01X613100Y603500D02*
Y608500D01*
G01X618700Y603500D02*
Y608500D01*
G01X624300Y603500D02*
X623800Y603583D01*
X623300Y603917D01*
X622967Y604500D01*
X622800Y605167D01*
X622967Y605833D01*
X623300Y606417D01*
X623800Y606750D01*
X624300Y606833D01*
X624800Y606750D01*
X625300Y606417D01*
X625633Y605833D01*
X625717Y605167D01*
X625633Y604500D01*
X625300Y603917D01*
X624800Y603583D01*
X624300Y603500D01*
G01X627817Y606833D02*
X628817Y603500D01*
X629900Y606833D01*
X630983Y603500D01*
X631983Y606833D01*
G01X605353Y638700D02*
Y643700D01*
X607520Y639533D01*
X609687Y643700D01*
Y638700D01*
G01X611703Y642033D02*
Y639700D01*
X612037Y639117D01*
X612537Y638783D01*
X613120Y638700D01*
X613703Y638783D01*
X614203Y639117D01*
X614537Y639700D01*
G01Y638700D02*
Y642033D01*
G01X617470Y639283D02*
X617887Y638950D01*
X618470Y638700D01*
X618970D01*
X619470Y638867D01*
X619803Y639117D01*
X619970Y639450D01*
X619887Y639950D01*
X619553Y640200D01*
X618053Y640700D01*
X617720Y641283D01*
X617887Y641700D01*
X618220Y641950D01*
X618720Y642033D01*
X619220Y641950D01*
X619720Y641700D01*
G01X624320Y643700D02*
Y638700D01*
G01X623153Y642033D02*
X625487D01*
G01X635020Y638700D02*
Y642950D01*
X635187Y643367D01*
X635520Y643617D01*
X636020Y643700D01*
X636520Y643533D01*
X636770Y643117D01*
G01X635770Y641700D02*
X634103D01*
G01X641120Y638700D02*
X640620Y638783D01*
X640120Y639117D01*
X639787Y639700D01*
X639620Y640367D01*
X639787Y641033D01*
X640120Y641617D01*
X640620Y641950D01*
X641120Y642033D01*
X641620Y641950D01*
X642120Y641617D01*
X642453Y641033D01*
X642537Y640367D01*
X642453Y639700D01*
X642120Y639117D01*
X641620Y638783D01*
X641120Y638700D01*
G01X646720D02*
Y643700D01*
G01X652320Y638700D02*
Y643700D01*
G01X657920Y638700D02*
X657420Y638783D01*
X656920Y639117D01*
X656587Y639700D01*
X656420Y640367D01*
X656587Y641033D01*
X656920Y641617D01*
X657420Y641950D01*
X657920Y642033D01*
X658420Y641950D01*
X658920Y641617D01*
X659253Y641033D01*
X659337Y640367D01*
X659253Y639700D01*
X658920Y639117D01*
X658420Y638783D01*
X657920Y638700D01*
G01X661437Y642033D02*
X662437Y638700D01*
X663520Y642033D01*
X664603Y638700D01*
X665603Y642033D01*
G01X606583Y620167D02*
X608583D01*
G01X607500Y621250D02*
Y619083D01*
G01X611600Y618333D02*
X614600Y623500D01*
G01X617617Y620167D02*
X619783D01*
G01X622717Y622667D02*
X623217Y623167D01*
X623800Y623417D01*
X624467Y623500D01*
X625300Y623333D01*
X625883Y622917D01*
X626050Y622417D01*
X625967Y621917D01*
X625633Y621500D01*
X623967Y620667D01*
X623217Y620083D01*
X622717Y619250D01*
X622550Y618500D01*
X626050D01*
G01X627400D02*
Y621833D01*
G01Y620917D02*
X627650Y621333D01*
X628067Y621667D01*
X628650Y621833D01*
X629233Y621667D01*
X629650Y621333D01*
X629900Y620917D01*
Y618500D01*
G01Y620917D02*
X630150Y621333D01*
X630567Y621667D01*
X631150Y621833D01*
X631733Y621667D01*
X632150Y621333D01*
X632400Y620833D01*
Y618500D01*
G01X635500Y621833D02*
Y618500D01*
G01Y623167D02*
X635333Y623250D01*
Y623417D01*
X635500Y623500D01*
X635667Y623417D01*
Y623250D01*
X635500Y623167D01*
G01X641100Y618500D02*
Y623500D01*
G01X606583Y591667D02*
X608583D01*
G01X607500Y592750D02*
Y590583D01*
G01X611600Y589833D02*
X614600Y595000D01*
G01X617617Y591667D02*
X619783D01*
G01X622467Y591000D02*
X622967Y590417D01*
X623633Y590083D01*
X624383Y590000D01*
X625050Y590083D01*
X625717Y590500D01*
X626133Y591000D01*
X626217Y591500D01*
X626050Y592083D01*
X625467Y592500D01*
X624883Y592667D01*
X624133D01*
G01X624883D02*
X625383Y592917D01*
X625800Y593333D01*
X625967Y593833D01*
X625800Y594333D01*
X625383Y594750D01*
X624633Y595000D01*
X623883Y594917D01*
X623133Y594583D01*
G01X627400Y590000D02*
Y593333D01*
G01Y592417D02*
X627650Y592833D01*
X628067Y593167D01*
X628650Y593333D01*
X629233Y593167D01*
X629650Y592833D01*
X629900Y592417D01*
Y590000D01*
G01Y592417D02*
X630150Y592833D01*
X630567Y593167D01*
X631150Y593333D01*
X631733Y593167D01*
X632150Y592833D01*
X632400Y592333D01*
Y590000D01*
G01X635500Y593333D02*
Y590000D01*
G01Y594667D02*
X635333Y594750D01*
Y594917D01*
X635500Y595000D01*
X635667Y594917D01*
Y594750D01*
X635500Y594667D01*
G01X641100Y590000D02*
Y595000D01*
G01X605417Y603500D02*
X607500Y608500D01*
X609583Y603500D01*
G01X608833Y605250D02*
X606167D01*
G01X613100Y603500D02*
Y608500D01*
G01X618700Y603500D02*
Y608500D01*
G01X624300Y603500D02*
X623800Y603583D01*
X623300Y603917D01*
X622967Y604500D01*
X622800Y605167D01*
X622967Y605833D01*
X623300Y606417D01*
X623800Y606750D01*
X624300Y606833D01*
X624800Y606750D01*
X625300Y606417D01*
X625633Y605833D01*
X625717Y605167D01*
X625633Y604500D01*
X625300Y603917D01*
X624800Y603583D01*
X624300Y603500D01*
G01X627817Y606833D02*
X628817Y603500D01*
X629900Y606833D01*
X630983Y603500D01*
X631983Y606833D01*
G01X605353Y638700D02*
Y643700D01*
X607520Y639533D01*
X609687Y643700D01*
Y638700D01*
G01X611703Y642033D02*
Y639700D01*
X612037Y639117D01*
X612537Y638783D01*
X613120Y638700D01*
X613703Y638783D01*
X614203Y639117D01*
X614537Y639700D01*
G01Y638700D02*
Y642033D01*
G01X617470Y639283D02*
X617887Y638950D01*
X618470Y638700D01*
X618970D01*
X619470Y638867D01*
X619803Y639117D01*
X619970Y639450D01*
X619887Y639950D01*
X619553Y640200D01*
X618053Y640700D01*
X617720Y641283D01*
X617887Y641700D01*
X618220Y641950D01*
X618720Y642033D01*
X619220Y641950D01*
X619720Y641700D01*
G01X624320Y643700D02*
Y638700D01*
G01X623153Y642033D02*
X625487D01*
G01X635020Y638700D02*
Y642950D01*
X635187Y643367D01*
X635520Y643617D01*
X636020Y643700D01*
X636520Y643533D01*
X636770Y643117D01*
G01X635770Y641700D02*
X634103D01*
G01X641120Y638700D02*
X640620Y638783D01*
X640120Y639117D01*
X639787Y639700D01*
X639620Y640367D01*
X639787Y641033D01*
X640120Y641617D01*
X640620Y641950D01*
X641120Y642033D01*
X641620Y641950D01*
X642120Y641617D01*
X642453Y641033D01*
X642537Y640367D01*
X642453Y639700D01*
X642120Y639117D01*
X641620Y638783D01*
X641120Y638700D01*
G01X646720D02*
Y643700D01*
G01X652320Y638700D02*
Y643700D01*
G01X657920Y638700D02*
X657420Y638783D01*
X656920Y639117D01*
X656587Y639700D01*
X656420Y640367D01*
X656587Y641033D01*
X656920Y641617D01*
X657420Y641950D01*
X657920Y642033D01*
X658420Y641950D01*
X658920Y641617D01*
X659253Y641033D01*
X659337Y640367D01*
X659253Y639700D01*
X658920Y639117D01*
X658420Y638783D01*
X657920Y638700D01*
G01X661437Y642033D02*
X662437Y638700D01*
X663520Y642033D01*
X664603Y638700D01*
X665603Y642033D01*
G01X617500Y668500D02*
Y663500D01*
G01X615583Y668500D02*
X619417D01*
G01X623100Y663500D02*
X622600Y663583D01*
X622100Y663917D01*
X621767Y664500D01*
X621600Y665167D01*
X621767Y665833D01*
X622100Y666417D01*
X622600Y666750D01*
X623100Y666833D01*
X623600Y666750D01*
X624100Y666417D01*
X624433Y665833D01*
X624517Y665167D01*
X624433Y664500D01*
X624100Y663917D01*
X623600Y663583D01*
X623100Y663500D01*
G01X628700D02*
Y668500D01*
G01X633050Y665750D02*
X635717D01*
X635467Y666333D01*
X635050Y666667D01*
X634467Y666833D01*
X633883Y666750D01*
X633383Y666500D01*
X633050Y665917D01*
X632883Y665417D01*
Y664917D01*
X633050Y664417D01*
X633467Y663917D01*
X633967Y663583D01*
X634550Y663500D01*
X635133Y663667D01*
X635717Y664167D01*
G01X638733Y663500D02*
Y666833D01*
G01Y666167D02*
X639150Y666500D01*
X639567Y666750D01*
X640150Y666833D01*
X640567Y666750D01*
X641067Y666500D01*
G01X647000Y663500D02*
Y666833D01*
G01Y666250D02*
X646667Y666583D01*
X646167Y666750D01*
X645583Y666833D01*
X645000Y666667D01*
X644500Y666333D01*
X644167Y665833D01*
X644000Y665167D01*
X644167Y664500D01*
X644500Y664000D01*
X645000Y663667D01*
X645583Y663500D01*
X646167Y663583D01*
X646667Y663833D01*
X647000Y664167D01*
G01X649683Y663500D02*
Y666833D01*
G01Y666000D02*
X650017Y666417D01*
X650517Y666750D01*
X651183Y666833D01*
X651767Y666750D01*
X652267Y666417D01*
X652517Y665833D01*
Y663500D01*
G01X658033Y666417D02*
X657450Y666750D01*
X656950Y666833D01*
X656283Y666667D01*
X655783Y666333D01*
X655450Y665750D01*
X655367Y665167D01*
X655450Y664583D01*
X655783Y664083D01*
X656283Y663667D01*
X656950Y663500D01*
X657533Y663667D01*
X658033Y664000D01*
G01X661050Y665750D02*
X663717D01*
X663467Y666333D01*
X663050Y666667D01*
X662467Y666833D01*
X661883Y666750D01*
X661383Y666500D01*
X661050Y665917D01*
X660883Y665417D01*
Y664917D01*
X661050Y664417D01*
X661467Y663917D01*
X661967Y663583D01*
X662550Y663500D01*
X663133Y663667D01*
X663717Y664167D01*
G01X617500Y668500D02*
Y663500D01*
G01X615583Y668500D02*
X619417D01*
G01X623100Y663500D02*
X622600Y663583D01*
X622100Y663917D01*
X621767Y664500D01*
X621600Y665167D01*
X621767Y665833D01*
X622100Y666417D01*
X622600Y666750D01*
X623100Y666833D01*
X623600Y666750D01*
X624100Y666417D01*
X624433Y665833D01*
X624517Y665167D01*
X624433Y664500D01*
X624100Y663917D01*
X623600Y663583D01*
X623100Y663500D01*
G01X628700D02*
Y668500D01*
G01X633050Y665750D02*
X635717D01*
X635467Y666333D01*
X635050Y666667D01*
X634467Y666833D01*
X633883Y666750D01*
X633383Y666500D01*
X633050Y665917D01*
X632883Y665417D01*
Y664917D01*
X633050Y664417D01*
X633467Y663917D01*
X633967Y663583D01*
X634550Y663500D01*
X635133Y663667D01*
X635717Y664167D01*
G01X638733Y663500D02*
Y666833D01*
G01Y666167D02*
X639150Y666500D01*
X639567Y666750D01*
X640150Y666833D01*
X640567Y666750D01*
X641067Y666500D01*
G01X647000Y663500D02*
Y666833D01*
G01Y666250D02*
X646667Y666583D01*
X646167Y666750D01*
X645583Y666833D01*
X645000Y666667D01*
X644500Y666333D01*
X644167Y665833D01*
X644000Y665167D01*
X644167Y664500D01*
X644500Y664000D01*
X645000Y663667D01*
X645583Y663500D01*
X646167Y663583D01*
X646667Y663833D01*
X647000Y664167D01*
G01X649683Y663500D02*
Y666833D01*
G01Y666000D02*
X650017Y666417D01*
X650517Y666750D01*
X651183Y666833D01*
X651767Y666750D01*
X652267Y666417D01*
X652517Y665833D01*
Y663500D01*
G01X658033Y666417D02*
X657450Y666750D01*
X656950Y666833D01*
X656283Y666667D01*
X655783Y666333D01*
X655450Y665750D01*
X655367Y665167D01*
X655450Y664583D01*
X655783Y664083D01*
X656283Y663667D01*
X656950Y663500D01*
X657533Y663667D01*
X658033Y664000D01*
G01X661050Y665750D02*
X663717D01*
X663467Y666333D01*
X663050Y666667D01*
X662467Y666833D01*
X661883Y666750D01*
X661383Y666500D01*
X661050Y665917D01*
X660883Y665417D01*
Y664917D01*
X661050Y664417D01*
X661467Y663917D01*
X661967Y663583D01*
X662550Y663500D01*
X663133Y663667D01*
X663717Y664167D01*
G01X590417Y860000D02*
X592500Y855000D01*
X594583Y860000D01*
G01X596267Y856000D02*
X596767Y855417D01*
X597433Y855083D01*
X598183Y855000D01*
X598850Y855083D01*
X599517Y855500D01*
X599933Y856000D01*
X600017Y856500D01*
X599850Y857083D01*
X599267Y857500D01*
X598683Y857667D01*
X597933D01*
G01X598683D02*
X599183Y857917D01*
X599600Y858333D01*
X599767Y858833D01*
X599600Y859333D01*
X599183Y859750D01*
X598433Y860000D01*
X597683Y859917D01*
X596933Y859583D01*
G01X603700Y854833D02*
X603533Y854917D01*
Y855083D01*
X603700Y855167D01*
X603867Y855083D01*
Y854917D01*
X603700Y854833D01*
G01X610300Y855000D02*
Y860000D01*
X607217Y856417D01*
X611383D01*
G01X614900Y854833D02*
X614733Y854917D01*
Y855083D01*
X614900Y855167D01*
X615067Y855083D01*
Y854917D01*
X614900Y854833D01*
G01X620500Y855000D02*
Y860000D01*
X619500Y859000D01*
G01Y855000D02*
X621500D01*
G01X641317Y859167D02*
X641817Y859667D01*
X642400Y859917D01*
X643067Y860000D01*
X643900Y859833D01*
X644483Y859417D01*
X644650Y858917D01*
X644567Y858417D01*
X644233Y858000D01*
X642567Y857167D01*
X641817Y856583D01*
X641317Y855750D01*
X641150Y855000D01*
X644650D01*
G01X648500Y860000D02*
X647833Y859833D01*
X647333Y859417D01*
X647000Y858917D01*
X646750Y858250D01*
X646667Y857500D01*
X646750Y856750D01*
X647000Y856083D01*
X647333Y855583D01*
X647833Y855167D01*
X648500Y855000D01*
X649167Y855167D01*
X649667Y855583D01*
X650000Y856083D01*
X650250Y856750D01*
X650333Y857500D01*
X650250Y858250D01*
X650000Y858917D01*
X649667Y859417D01*
X649167Y859833D01*
X648500Y860000D01*
G01X654100Y855000D02*
Y860000D01*
X653100Y859000D01*
G01Y855000D02*
X655100D01*
G01X657867Y855750D02*
X658367Y855333D01*
X658950Y855083D01*
X659700Y855000D01*
X660450Y855167D01*
X661033Y855500D01*
X661450Y856083D01*
X661533Y856750D01*
X661367Y857417D01*
X660950Y857833D01*
X660367Y858167D01*
X659783Y858250D01*
X659200Y858167D01*
X658450Y857833D01*
X658700Y860000D01*
X660950D01*
G01X663800Y854833D02*
X666800Y860000D01*
G01X670900D02*
X670233Y859833D01*
X669733Y859417D01*
X669400Y858917D01*
X669150Y858250D01*
X669067Y857500D01*
X669150Y856750D01*
X669400Y856083D01*
X669733Y855583D01*
X670233Y855167D01*
X670900Y855000D01*
X671567Y855167D01*
X672067Y855583D01*
X672400Y856083D01*
X672650Y856750D01*
X672733Y857500D01*
X672650Y858250D01*
X672400Y858917D01*
X672067Y859417D01*
X671567Y859833D01*
X670900Y860000D01*
G01X674917Y857083D02*
X675500Y857667D01*
X676000Y858000D01*
X676667Y858167D01*
X677250Y858000D01*
X677667Y857667D01*
X678000Y857167D01*
X678083Y856583D01*
X678000Y856083D01*
X677667Y855583D01*
X677167Y855167D01*
X676583Y855000D01*
X675917Y855167D01*
X675333Y855667D01*
X675000Y856417D01*
X674917Y857250D01*
X675083Y858333D01*
X675333Y858917D01*
X675750Y859500D01*
X676333Y859917D01*
X676917Y860000D01*
X677500Y859833D01*
X677917Y859417D01*
G01X590417Y860000D02*
X592500Y855000D01*
X594583Y860000D01*
G01X596267Y856000D02*
X596767Y855417D01*
X597433Y855083D01*
X598183Y855000D01*
X598850Y855083D01*
X599517Y855500D01*
X599933Y856000D01*
X600017Y856500D01*
X599850Y857083D01*
X599267Y857500D01*
X598683Y857667D01*
X597933D01*
G01X598683D02*
X599183Y857917D01*
X599600Y858333D01*
X599767Y858833D01*
X599600Y859333D01*
X599183Y859750D01*
X598433Y860000D01*
X597683Y859917D01*
X596933Y859583D01*
G01X603700Y854833D02*
X603533Y854917D01*
Y855083D01*
X603700Y855167D01*
X603867Y855083D01*
Y854917D01*
X603700Y854833D01*
G01X610300Y855000D02*
Y860000D01*
X607217Y856417D01*
X611383D01*
G01X614900Y854833D02*
X614733Y854917D01*
Y855083D01*
X614900Y855167D01*
X615067Y855083D01*
Y854917D01*
X614900Y854833D01*
G01X620500Y855000D02*
Y860000D01*
X619500Y859000D01*
G01Y855000D02*
X621500D01*
G01X641317Y859167D02*
X641817Y859667D01*
X642400Y859917D01*
X643067Y860000D01*
X643900Y859833D01*
X644483Y859417D01*
X644650Y858917D01*
X644567Y858417D01*
X644233Y858000D01*
X642567Y857167D01*
X641817Y856583D01*
X641317Y855750D01*
X641150Y855000D01*
X644650D01*
G01X648500Y860000D02*
X647833Y859833D01*
X647333Y859417D01*
X647000Y858917D01*
X646750Y858250D01*
X646667Y857500D01*
X646750Y856750D01*
X647000Y856083D01*
X647333Y855583D01*
X647833Y855167D01*
X648500Y855000D01*
X649167Y855167D01*
X649667Y855583D01*
X650000Y856083D01*
X650250Y856750D01*
X650333Y857500D01*
X650250Y858250D01*
X650000Y858917D01*
X649667Y859417D01*
X649167Y859833D01*
X648500Y860000D01*
G01X654100Y855000D02*
Y860000D01*
X653100Y859000D01*
G01Y855000D02*
X655100D01*
G01X657867Y855750D02*
X658367Y855333D01*
X658950Y855083D01*
X659700Y855000D01*
X660450Y855167D01*
X661033Y855500D01*
X661450Y856083D01*
X661533Y856750D01*
X661367Y857417D01*
X660950Y857833D01*
X660367Y858167D01*
X659783Y858250D01*
X659200Y858167D01*
X658450Y857833D01*
X658700Y860000D01*
X660950D01*
G01X663800Y854833D02*
X666800Y860000D01*
G01X670900D02*
X670233Y859833D01*
X669733Y859417D01*
X669400Y858917D01*
X669150Y858250D01*
X669067Y857500D01*
X669150Y856750D01*
X669400Y856083D01*
X669733Y855583D01*
X670233Y855167D01*
X670900Y855000D01*
X671567Y855167D01*
X672067Y855583D01*
X672400Y856083D01*
X672650Y856750D01*
X672733Y857500D01*
X672650Y858250D01*
X672400Y858917D01*
X672067Y859417D01*
X671567Y859833D01*
X670900Y860000D01*
G01X674917Y857083D02*
X675500Y857667D01*
X676000Y858000D01*
X676667Y858167D01*
X677250Y858000D01*
X677667Y857667D01*
X678000Y857167D01*
X678083Y856583D01*
X678000Y856083D01*
X677667Y855583D01*
X677167Y855167D01*
X676583Y855000D01*
X675917Y855167D01*
X675333Y855667D01*
X675000Y856417D01*
X674917Y857250D01*
X675083Y858333D01*
X675333Y858917D01*
X675750Y859500D01*
X676333Y859917D01*
X676917Y860000D01*
X677500Y859833D01*
X677917Y859417D01*
G01X736937Y-65320D02*
X737437Y-65737D01*
X738020Y-65987D01*
X738770Y-66070D01*
X739520Y-65903D01*
X740103Y-65570D01*
X740520Y-64987D01*
X740603Y-64320D01*
X740437Y-63653D01*
X740020Y-63237D01*
X739437Y-62903D01*
X738853Y-62820D01*
X738270Y-62903D01*
X737520Y-63237D01*
X737770Y-61070D01*
X740020D01*
G01X744370Y-66237D02*
X744203Y-66153D01*
Y-65987D01*
X744370Y-65903D01*
X744537Y-65987D01*
Y-66153D01*
X744370Y-66237D01*
G01X749970Y-66070D02*
Y-61070D01*
X748970Y-62070D01*
G01Y-66070D02*
X750970D01*
G01X760170Y-61070D02*
X762170D01*
G01X761170D02*
Y-66070D01*
G01X760170D02*
X762170D01*
G01X766270D02*
Y-61820D01*
X766437Y-61403D01*
X766770Y-61153D01*
X767270Y-61070D01*
X767770Y-61237D01*
X768020Y-61653D01*
G01X767020Y-63070D02*
X765353D01*
G01X778470Y-63570D02*
X780137D01*
Y-65070D01*
X779637Y-65570D01*
X779053Y-65903D01*
X778220Y-66070D01*
X777387Y-65903D01*
X776803Y-65570D01*
X776303Y-65070D01*
X775970Y-64487D01*
X775803Y-63820D01*
Y-63237D01*
X775970Y-62737D01*
X776303Y-62153D01*
X776803Y-61653D01*
X777303Y-61320D01*
X777970Y-61070D01*
X778553D01*
X779220Y-61237D01*
X779720Y-61570D01*
G01X782320Y-63820D02*
X784987D01*
X784737Y-63237D01*
X784320Y-62903D01*
X783737Y-62737D01*
X783153Y-62820D01*
X782653Y-63070D01*
X782320Y-63653D01*
X782153Y-64153D01*
Y-64653D01*
X782320Y-65153D01*
X782737Y-65653D01*
X783237Y-65987D01*
X783820Y-66070D01*
X784403Y-65903D01*
X784987Y-65403D01*
G01X788003Y-66070D02*
Y-62737D01*
G01Y-63403D02*
X788420Y-63070D01*
X788837Y-62820D01*
X789420Y-62737D01*
X789837Y-62820D01*
X790337Y-63070D01*
G01X793270Y-66070D02*
Y-61070D01*
G01Y-63570D02*
X793687Y-63070D01*
X794187Y-62820D01*
X794687Y-62737D01*
X795437Y-62903D01*
X795937Y-63237D01*
X796270Y-63820D01*
Y-64487D01*
X796103Y-65153D01*
X795770Y-65653D01*
X795187Y-65987D01*
X794687Y-66070D01*
X794187Y-65987D01*
X793687Y-65737D01*
X793270Y-65320D01*
G01X799120Y-63820D02*
X801787D01*
X801537Y-63237D01*
X801120Y-62903D01*
X800537Y-62737D01*
X799953Y-62820D01*
X799453Y-63070D01*
X799120Y-63653D01*
X798953Y-64153D01*
Y-64653D01*
X799120Y-65153D01*
X799537Y-65653D01*
X800037Y-65987D01*
X800620Y-66070D01*
X801203Y-65903D01*
X801787Y-65403D01*
G01X804803Y-66070D02*
Y-62737D01*
G01Y-63403D02*
X805220Y-63070D01*
X805637Y-62820D01*
X806220Y-62737D01*
X806637Y-62820D01*
X807137Y-63070D01*
G01X815753Y-66070D02*
Y-61070D01*
G01Y-63487D02*
X816170Y-63070D01*
X816587Y-62820D01*
X817253Y-62737D01*
X817753Y-62820D01*
X818337Y-63153D01*
X818587Y-63653D01*
Y-66070D01*
G01X824270D02*
Y-62737D01*
G01Y-63320D02*
X823937Y-62987D01*
X823437Y-62820D01*
X822853Y-62737D01*
X822270Y-62903D01*
X821770Y-63237D01*
X821437Y-63737D01*
X821270Y-64403D01*
X821437Y-65070D01*
X821770Y-65570D01*
X822270Y-65903D01*
X822853Y-66070D01*
X823437Y-65987D01*
X823937Y-65737D01*
X824270Y-65403D01*
G01X827120Y-65487D02*
X827537Y-65820D01*
X828120Y-66070D01*
X828620D01*
X829120Y-65903D01*
X829453Y-65653D01*
X829620Y-65320D01*
X829537Y-64820D01*
X829203Y-64570D01*
X827703Y-64070D01*
X827370Y-63487D01*
X827537Y-63070D01*
X827870Y-62820D01*
X828370Y-62737D01*
X828870Y-62820D01*
X829370Y-63070D01*
G01X839570Y-61070D02*
Y-66070D01*
G01X838403Y-62737D02*
X840737D01*
G01X843753Y-66070D02*
Y-61070D01*
G01Y-63487D02*
X844170Y-63070D01*
X844587Y-62820D01*
X845253Y-62737D01*
X845753Y-62820D01*
X846337Y-63153D01*
X846587Y-63653D01*
Y-66070D01*
G01X850770Y-62737D02*
Y-66070D01*
G01Y-61403D02*
X850603Y-61320D01*
Y-61153D01*
X850770Y-61070D01*
X850937Y-61153D01*
Y-61320D01*
X850770Y-61403D01*
G01X855120Y-65487D02*
X855537Y-65820D01*
X856120Y-66070D01*
X856620D01*
X857120Y-65903D01*
X857453Y-65653D01*
X857620Y-65320D01*
X857537Y-64820D01*
X857203Y-64570D01*
X855703Y-64070D01*
X855370Y-63487D01*
X855537Y-63070D01*
X855870Y-62820D01*
X856370Y-62737D01*
X856870Y-62820D01*
X857370Y-63070D01*
G01X866153Y-66070D02*
Y-61070D01*
G01X868820Y-62737D02*
X866153Y-64653D01*
G01X867237Y-63903D02*
X868987Y-66070D01*
G01X873170Y-62737D02*
Y-66070D01*
G01Y-61403D02*
X873003Y-61320D01*
Y-61153D01*
X873170Y-61070D01*
X873337Y-61153D01*
Y-61320D01*
X873170Y-61403D01*
G01X877353Y-66070D02*
Y-62737D01*
G01Y-63570D02*
X877687Y-63153D01*
X878187Y-62820D01*
X878853Y-62737D01*
X879437Y-62820D01*
X879937Y-63153D01*
X880187Y-63737D01*
Y-66070D01*
G01X885870Y-61070D02*
Y-66070D01*
G01Y-65320D02*
X885537Y-65737D01*
X885037Y-65987D01*
X884453Y-66070D01*
X883787Y-65903D01*
X883287Y-65487D01*
X882953Y-64987D01*
X882870Y-64403D01*
X882953Y-63820D01*
X883287Y-63320D01*
X883787Y-62903D01*
X884453Y-62737D01*
X885037Y-62820D01*
X885453Y-62987D01*
X885870Y-63320D01*
G01X895570Y-66070D02*
X895070Y-65987D01*
X894570Y-65653D01*
X894237Y-65070D01*
X894070Y-64403D01*
X894237Y-63737D01*
X894570Y-63153D01*
X895070Y-62820D01*
X895570Y-62737D01*
X896070Y-62820D01*
X896570Y-63153D01*
X896903Y-63737D01*
X896987Y-64403D01*
X896903Y-65070D01*
X896570Y-65653D01*
X896070Y-65987D01*
X895570Y-66070D01*
G01X900670D02*
Y-61820D01*
X900837Y-61403D01*
X901170Y-61153D01*
X901670Y-61070D01*
X902170Y-61237D01*
X902420Y-61653D01*
G01X901420Y-63070D02*
X899753D01*
G01X913870Y-61070D02*
Y-66070D01*
G01Y-65320D02*
X913537Y-65737D01*
X913037Y-65987D01*
X912453Y-66070D01*
X911787Y-65903D01*
X911287Y-65487D01*
X910953Y-64987D01*
X910870Y-64403D01*
X910953Y-63820D01*
X911287Y-63320D01*
X911787Y-62903D01*
X912453Y-62737D01*
X913037Y-62820D01*
X913453Y-62987D01*
X913870Y-63320D01*
G01X916720Y-63820D02*
X919387D01*
X919137Y-63237D01*
X918720Y-62903D01*
X918137Y-62737D01*
X917553Y-62820D01*
X917053Y-63070D01*
X916720Y-63653D01*
X916553Y-64153D01*
Y-64653D01*
X916720Y-65153D01*
X917137Y-65653D01*
X917637Y-65987D01*
X918220Y-66070D01*
X918803Y-65903D01*
X919387Y-65403D01*
G01X922320Y-65487D02*
X922737Y-65820D01*
X923320Y-66070D01*
X923820D01*
X924320Y-65903D01*
X924653Y-65653D01*
X924820Y-65320D01*
X924737Y-64820D01*
X924403Y-64570D01*
X922903Y-64070D01*
X922570Y-63487D01*
X922737Y-63070D01*
X923070Y-62820D01*
X923570Y-62737D01*
X924070Y-62820D01*
X924570Y-63070D01*
G01X929170Y-62737D02*
Y-66070D01*
G01Y-61403D02*
X929003Y-61320D01*
Y-61153D01*
X929170Y-61070D01*
X929337Y-61153D01*
Y-61320D01*
X929170Y-61403D01*
G01X933603Y-67320D02*
X934187Y-67653D01*
X934853Y-67737D01*
X935437Y-67653D01*
X935937Y-67237D01*
X936270Y-66653D01*
Y-62737D01*
G01Y-63403D02*
X935937Y-63070D01*
X935437Y-62820D01*
X934853Y-62737D01*
X934187Y-62903D01*
X933770Y-63237D01*
X933437Y-63820D01*
X933270Y-64403D01*
X933353Y-64903D01*
X933687Y-65487D01*
X934187Y-65903D01*
X934853Y-66070D01*
X935353Y-65987D01*
X935937Y-65653D01*
X936270Y-65320D01*
G01X938953Y-66070D02*
Y-62737D01*
G01Y-63570D02*
X939287Y-63153D01*
X939787Y-62820D01*
X940453Y-62737D01*
X941037Y-62820D01*
X941537Y-63153D01*
X941787Y-63737D01*
Y-66070D01*
G01X945803Y-66987D02*
X946137Y-65903D01*
G01X955670Y-67737D02*
Y-62737D01*
G01Y-63487D02*
X956087Y-63070D01*
X956503Y-62820D01*
X957170Y-62737D01*
X957753Y-62820D01*
X958337Y-63237D01*
X958587Y-63820D01*
X958670Y-64403D01*
X958587Y-64987D01*
X958337Y-65570D01*
X957837Y-65903D01*
X957170Y-66070D01*
X956587Y-65987D01*
X956003Y-65737D01*
X955670Y-65403D01*
G01X962770Y-66070D02*
Y-61070D01*
G01X967120Y-63820D02*
X969787D01*
X969537Y-63237D01*
X969120Y-62903D01*
X968537Y-62737D01*
X967953Y-62820D01*
X967453Y-63070D01*
X967120Y-63653D01*
X966953Y-64153D01*
Y-64653D01*
X967120Y-65153D01*
X967537Y-65653D01*
X968037Y-65987D01*
X968620Y-66070D01*
X969203Y-65903D01*
X969787Y-65403D01*
G01X975470Y-66070D02*
Y-62737D01*
G01Y-63320D02*
X975137Y-62987D01*
X974637Y-62820D01*
X974053Y-62737D01*
X973470Y-62903D01*
X972970Y-63237D01*
X972637Y-63737D01*
X972470Y-64403D01*
X972637Y-65070D01*
X972970Y-65570D01*
X973470Y-65903D01*
X974053Y-66070D01*
X974637Y-65987D01*
X975137Y-65737D01*
X975470Y-65403D01*
G01X978320Y-65487D02*
X978737Y-65820D01*
X979320Y-66070D01*
X979820D01*
X980320Y-65903D01*
X980653Y-65653D01*
X980820Y-65320D01*
X980737Y-64820D01*
X980403Y-64570D01*
X978903Y-64070D01*
X978570Y-63487D01*
X978737Y-63070D01*
X979070Y-62820D01*
X979570Y-62737D01*
X980070Y-62820D01*
X980570Y-63070D01*
G01X983920Y-63820D02*
X986587D01*
X986337Y-63237D01*
X985920Y-62903D01*
X985337Y-62737D01*
X984753Y-62820D01*
X984253Y-63070D01*
X983920Y-63653D01*
X983753Y-64153D01*
Y-64653D01*
X983920Y-65153D01*
X984337Y-65653D01*
X984837Y-65987D01*
X985420Y-66070D01*
X986003Y-65903D01*
X986587Y-65403D01*
G01X995870Y-66070D02*
Y-61820D01*
X996037Y-61403D01*
X996370Y-61153D01*
X996870Y-61070D01*
X997370Y-61237D01*
X997620Y-61653D01*
G01X996620Y-63070D02*
X994953D01*
G01X1001970Y-66070D02*
X1001470Y-65987D01*
X1000970Y-65653D01*
X1000637Y-65070D01*
X1000470Y-64403D01*
X1000637Y-63737D01*
X1000970Y-63153D01*
X1001470Y-62820D01*
X1001970Y-62737D01*
X1002470Y-62820D01*
X1002970Y-63153D01*
X1003303Y-63737D01*
X1003387Y-64403D01*
X1003303Y-65070D01*
X1002970Y-65653D01*
X1002470Y-65987D01*
X1001970Y-66070D01*
G01X1007570D02*
Y-61070D01*
G01X1013170Y-66070D02*
Y-61070D01*
G01X1018770Y-66070D02*
X1018270Y-65987D01*
X1017770Y-65653D01*
X1017437Y-65070D01*
X1017270Y-64403D01*
X1017437Y-63737D01*
X1017770Y-63153D01*
X1018270Y-62820D01*
X1018770Y-62737D01*
X1019270Y-62820D01*
X1019770Y-63153D01*
X1020103Y-63737D01*
X1020187Y-64403D01*
X1020103Y-65070D01*
X1019770Y-65653D01*
X1019270Y-65987D01*
X1018770Y-66070D01*
G01X1022287Y-62737D02*
X1023287Y-66070D01*
X1024370Y-62737D01*
X1025453Y-66070D01*
X1026453Y-62737D01*
G01X1029970Y-66237D02*
X1029803Y-66153D01*
Y-65987D01*
X1029970Y-65903D01*
X1030137Y-65987D01*
Y-66153D01*
X1029970Y-66237D01*
G01X1040170Y-61070D02*
X1042170D01*
G01X1041170D02*
Y-66070D01*
G01X1040170D02*
X1042170D01*
G01X1046270D02*
Y-61820D01*
X1046437Y-61403D01*
X1046770Y-61153D01*
X1047270Y-61070D01*
X1047770Y-61237D01*
X1048020Y-61653D01*
G01X1047020Y-63070D02*
X1045353D01*
G01X1056553Y-66070D02*
Y-62737D01*
G01Y-63570D02*
X1056887Y-63153D01*
X1057387Y-62820D01*
X1058053Y-62737D01*
X1058637Y-62820D01*
X1059137Y-63153D01*
X1059387Y-63737D01*
Y-66070D01*
G01X1063570D02*
X1063070Y-65987D01*
X1062570Y-65653D01*
X1062237Y-65070D01*
X1062070Y-64403D01*
X1062237Y-63737D01*
X1062570Y-63153D01*
X1063070Y-62820D01*
X1063570Y-62737D01*
X1064070Y-62820D01*
X1064570Y-63153D01*
X1064903Y-63737D01*
X1064987Y-64403D01*
X1064903Y-65070D01*
X1064570Y-65653D01*
X1064070Y-65987D01*
X1063570Y-66070D01*
G01X1069170Y-61070D02*
Y-66070D01*
G01X1068003Y-62737D02*
X1070337D01*
G01X1074603Y-66987D02*
X1074937Y-65903D01*
G01X1084470Y-67737D02*
Y-62737D01*
G01Y-63487D02*
X1084887Y-63070D01*
X1085303Y-62820D01*
X1085970Y-62737D01*
X1086553Y-62820D01*
X1087137Y-63237D01*
X1087387Y-63820D01*
X1087470Y-64403D01*
X1087387Y-64987D01*
X1087137Y-65570D01*
X1086637Y-65903D01*
X1085970Y-66070D01*
X1085387Y-65987D01*
X1084803Y-65737D01*
X1084470Y-65403D01*
G01X1091570Y-66070D02*
Y-61070D01*
G01X1095920Y-63820D02*
X1098587D01*
X1098337Y-63237D01*
X1097920Y-62903D01*
X1097337Y-62737D01*
X1096753Y-62820D01*
X1096253Y-63070D01*
X1095920Y-63653D01*
X1095753Y-64153D01*
Y-64653D01*
X1095920Y-65153D01*
X1096337Y-65653D01*
X1096837Y-65987D01*
X1097420Y-66070D01*
X1098003Y-65903D01*
X1098587Y-65403D01*
G01X1104270Y-66070D02*
Y-62737D01*
G01Y-63320D02*
X1103937Y-62987D01*
X1103437Y-62820D01*
X1102853Y-62737D01*
X1102270Y-62903D01*
X1101770Y-63237D01*
X1101437Y-63737D01*
X1101270Y-64403D01*
X1101437Y-65070D01*
X1101770Y-65570D01*
X1102270Y-65903D01*
X1102853Y-66070D01*
X1103437Y-65987D01*
X1103937Y-65737D01*
X1104270Y-65403D01*
G01X1107120Y-65487D02*
X1107537Y-65820D01*
X1108120Y-66070D01*
X1108620D01*
X1109120Y-65903D01*
X1109453Y-65653D01*
X1109620Y-65320D01*
X1109537Y-64820D01*
X1109203Y-64570D01*
X1107703Y-64070D01*
X1107370Y-63487D01*
X1107537Y-63070D01*
X1107870Y-62820D01*
X1108370Y-62737D01*
X1108870Y-62820D01*
X1109370Y-63070D01*
G01X1112720Y-63820D02*
X1115387D01*
X1115137Y-63237D01*
X1114720Y-62903D01*
X1114137Y-62737D01*
X1113553Y-62820D01*
X1113053Y-63070D01*
X1112720Y-63653D01*
X1112553Y-64153D01*
Y-64653D01*
X1112720Y-65153D01*
X1113137Y-65653D01*
X1113637Y-65987D01*
X1114220Y-66070D01*
X1114803Y-65903D01*
X1115387Y-65403D01*
G01X1125170Y-62737D02*
Y-66070D01*
G01Y-61403D02*
X1125003Y-61320D01*
Y-61153D01*
X1125170Y-61070D01*
X1125337Y-61153D01*
Y-61320D01*
X1125170Y-61403D01*
G01X1132270Y-67737D02*
Y-62737D01*
G01Y-63487D02*
X1131853Y-63070D01*
X1131353Y-62820D01*
X1130770Y-62737D01*
X1130270Y-62820D01*
X1129687Y-63237D01*
X1129353Y-63820D01*
X1129270Y-64403D01*
X1129353Y-64987D01*
X1129687Y-65570D01*
X1130270Y-65987D01*
X1130770Y-66070D01*
X1131353Y-65987D01*
X1131853Y-65737D01*
X1132270Y-65320D01*
G01X1134953Y-66070D02*
Y-62737D01*
G01Y-63570D02*
X1135287Y-63153D01*
X1135787Y-62820D01*
X1136453Y-62737D01*
X1137037Y-62820D01*
X1137537Y-63153D01*
X1137787Y-63737D01*
Y-66070D01*
G01X1141970D02*
X1141470Y-65987D01*
X1140970Y-65653D01*
X1140637Y-65070D01*
X1140470Y-64403D01*
X1140637Y-63737D01*
X1140970Y-63153D01*
X1141470Y-62820D01*
X1141970Y-62737D01*
X1142470Y-62820D01*
X1142970Y-63153D01*
X1143303Y-63737D01*
X1143387Y-64403D01*
X1143303Y-65070D01*
X1142970Y-65653D01*
X1142470Y-65987D01*
X1141970Y-66070D01*
G01X1146403D02*
Y-62737D01*
G01Y-63403D02*
X1146820Y-63070D01*
X1147237Y-62820D01*
X1147820Y-62737D01*
X1148237Y-62820D01*
X1148737Y-63070D01*
G01X1151920Y-63820D02*
X1154587D01*
X1154337Y-63237D01*
X1153920Y-62903D01*
X1153337Y-62737D01*
X1152753Y-62820D01*
X1152253Y-63070D01*
X1151920Y-63653D01*
X1151753Y-64153D01*
Y-64653D01*
X1151920Y-65153D01*
X1152337Y-65653D01*
X1152837Y-65987D01*
X1153420Y-66070D01*
X1154003Y-65903D01*
X1154587Y-65403D01*
G01X1164370Y-61070D02*
Y-66070D01*
G01X1163203Y-62737D02*
X1165537D01*
G01X1168553Y-66070D02*
Y-61070D01*
G01Y-63487D02*
X1168970Y-63070D01*
X1169387Y-62820D01*
X1170053Y-62737D01*
X1170553Y-62820D01*
X1171137Y-63153D01*
X1171387Y-63653D01*
Y-66070D01*
G01X1175570Y-62737D02*
Y-66070D01*
G01Y-61403D02*
X1175403Y-61320D01*
Y-61153D01*
X1175570Y-61070D01*
X1175737Y-61153D01*
Y-61320D01*
X1175570Y-61403D01*
G01X1179920Y-65487D02*
X1180337Y-65820D01*
X1180920Y-66070D01*
X1181420D01*
X1181920Y-65903D01*
X1182253Y-65653D01*
X1182420Y-65320D01*
X1182337Y-64820D01*
X1182003Y-64570D01*
X1180503Y-64070D01*
X1180170Y-63487D01*
X1180337Y-63070D01*
X1180670Y-62820D01*
X1181170Y-62737D01*
X1181670Y-62820D01*
X1182170Y-63070D01*
G01X1191203Y-66070D02*
Y-62737D01*
G01Y-63403D02*
X1191620Y-63070D01*
X1192037Y-62820D01*
X1192620Y-62737D01*
X1193037Y-62820D01*
X1193537Y-63070D01*
G01X1196720Y-63820D02*
X1199387D01*
X1199137Y-63237D01*
X1198720Y-62903D01*
X1198137Y-62737D01*
X1197553Y-62820D01*
X1197053Y-63070D01*
X1196720Y-63653D01*
X1196553Y-64153D01*
Y-64653D01*
X1196720Y-65153D01*
X1197137Y-65653D01*
X1197637Y-65987D01*
X1198220Y-66070D01*
X1198803Y-65903D01*
X1199387Y-65403D01*
G01X1205070Y-67737D02*
Y-62737D01*
G01Y-63487D02*
X1204653Y-63070D01*
X1204153Y-62820D01*
X1203570Y-62737D01*
X1203070Y-62820D01*
X1202487Y-63237D01*
X1202153Y-63820D01*
X1202070Y-64403D01*
X1202153Y-64987D01*
X1202487Y-65570D01*
X1203070Y-65987D01*
X1203570Y-66070D01*
X1204153Y-65987D01*
X1204653Y-65737D01*
X1205070Y-65320D01*
G01X1207753Y-62737D02*
Y-65070D01*
X1208087Y-65653D01*
X1208587Y-65987D01*
X1209170Y-66070D01*
X1209753Y-65987D01*
X1210253Y-65653D01*
X1210587Y-65070D01*
G01Y-66070D02*
Y-62737D01*
G01X1213520Y-63820D02*
X1216187D01*
X1215937Y-63237D01*
X1215520Y-62903D01*
X1214937Y-62737D01*
X1214353Y-62820D01*
X1213853Y-63070D01*
X1213520Y-63653D01*
X1213353Y-64153D01*
Y-64653D01*
X1213520Y-65153D01*
X1213937Y-65653D01*
X1214437Y-65987D01*
X1215020Y-66070D01*
X1215603Y-65903D01*
X1216187Y-65403D01*
G01X1219120Y-65487D02*
X1219537Y-65820D01*
X1220120Y-66070D01*
X1220620D01*
X1221120Y-65903D01*
X1221453Y-65653D01*
X1221620Y-65320D01*
X1221537Y-64820D01*
X1221203Y-64570D01*
X1219703Y-64070D01*
X1219370Y-63487D01*
X1219537Y-63070D01*
X1219870Y-62820D01*
X1220370Y-62737D01*
X1220870Y-62820D01*
X1221370Y-63070D01*
G01X1225970Y-61070D02*
Y-66070D01*
G01X1224803Y-62737D02*
X1227137D01*
G01X1231570Y-66237D02*
X1231403Y-66153D01*
Y-65987D01*
X1231570Y-65903D01*
X1231737Y-65987D01*
Y-66153D01*
X1231570Y-66237D01*
G01X713000Y850500D02*
Y-73000D01*
X1343000D01*
Y782000D01*
X713000D01*
G01X694500Y716000D02*
Y-69500D01*
G01X736937Y-65320D02*
X737437Y-65737D01*
X738020Y-65987D01*
X738770Y-66070D01*
X739520Y-65903D01*
X740103Y-65570D01*
X740520Y-64987D01*
X740603Y-64320D01*
X740437Y-63653D01*
X740020Y-63237D01*
X739437Y-62903D01*
X738853Y-62820D01*
X738270Y-62903D01*
X737520Y-63237D01*
X737770Y-61070D01*
X740020D01*
G01X744370Y-66237D02*
X744203Y-66153D01*
Y-65987D01*
X744370Y-65903D01*
X744537Y-65987D01*
Y-66153D01*
X744370Y-66237D01*
G01X749970Y-66070D02*
Y-61070D01*
X748970Y-62070D01*
G01Y-66070D02*
X750970D01*
G01X760170Y-61070D02*
X762170D01*
G01X761170D02*
Y-66070D01*
G01X760170D02*
X762170D01*
G01X766270D02*
Y-61820D01*
X766437Y-61403D01*
X766770Y-61153D01*
X767270Y-61070D01*
X767770Y-61237D01*
X768020Y-61653D01*
G01X767020Y-63070D02*
X765353D01*
G01X778470Y-63570D02*
X780137D01*
Y-65070D01*
X779637Y-65570D01*
X779053Y-65903D01*
X778220Y-66070D01*
X777387Y-65903D01*
X776803Y-65570D01*
X776303Y-65070D01*
X775970Y-64487D01*
X775803Y-63820D01*
Y-63237D01*
X775970Y-62737D01*
X776303Y-62153D01*
X776803Y-61653D01*
X777303Y-61320D01*
X777970Y-61070D01*
X778553D01*
X779220Y-61237D01*
X779720Y-61570D01*
G01X782320Y-63820D02*
X784987D01*
X784737Y-63237D01*
X784320Y-62903D01*
X783737Y-62737D01*
X783153Y-62820D01*
X782653Y-63070D01*
X782320Y-63653D01*
X782153Y-64153D01*
Y-64653D01*
X782320Y-65153D01*
X782737Y-65653D01*
X783237Y-65987D01*
X783820Y-66070D01*
X784403Y-65903D01*
X784987Y-65403D01*
G01X788003Y-66070D02*
Y-62737D01*
G01Y-63403D02*
X788420Y-63070D01*
X788837Y-62820D01*
X789420Y-62737D01*
X789837Y-62820D01*
X790337Y-63070D01*
G01X793270Y-66070D02*
Y-61070D01*
G01Y-63570D02*
X793687Y-63070D01*
X794187Y-62820D01*
X794687Y-62737D01*
X795437Y-62903D01*
X795937Y-63237D01*
X796270Y-63820D01*
Y-64487D01*
X796103Y-65153D01*
X795770Y-65653D01*
X795187Y-65987D01*
X794687Y-66070D01*
X794187Y-65987D01*
X793687Y-65737D01*
X793270Y-65320D01*
G01X799120Y-63820D02*
X801787D01*
X801537Y-63237D01*
X801120Y-62903D01*
X800537Y-62737D01*
X799953Y-62820D01*
X799453Y-63070D01*
X799120Y-63653D01*
X798953Y-64153D01*
Y-64653D01*
X799120Y-65153D01*
X799537Y-65653D01*
X800037Y-65987D01*
X800620Y-66070D01*
X801203Y-65903D01*
X801787Y-65403D01*
G01X804803Y-66070D02*
Y-62737D01*
G01Y-63403D02*
X805220Y-63070D01*
X805637Y-62820D01*
X806220Y-62737D01*
X806637Y-62820D01*
X807137Y-63070D01*
G01X815753Y-66070D02*
Y-61070D01*
G01Y-63487D02*
X816170Y-63070D01*
X816587Y-62820D01*
X817253Y-62737D01*
X817753Y-62820D01*
X818337Y-63153D01*
X818587Y-63653D01*
Y-66070D01*
G01X824270D02*
Y-62737D01*
G01Y-63320D02*
X823937Y-62987D01*
X823437Y-62820D01*
X822853Y-62737D01*
X822270Y-62903D01*
X821770Y-63237D01*
X821437Y-63737D01*
X821270Y-64403D01*
X821437Y-65070D01*
X821770Y-65570D01*
X822270Y-65903D01*
X822853Y-66070D01*
X823437Y-65987D01*
X823937Y-65737D01*
X824270Y-65403D01*
G01X827120Y-65487D02*
X827537Y-65820D01*
X828120Y-66070D01*
X828620D01*
X829120Y-65903D01*
X829453Y-65653D01*
X829620Y-65320D01*
X829537Y-64820D01*
X829203Y-64570D01*
X827703Y-64070D01*
X827370Y-63487D01*
X827537Y-63070D01*
X827870Y-62820D01*
X828370Y-62737D01*
X828870Y-62820D01*
X829370Y-63070D01*
G01X839570Y-61070D02*
Y-66070D01*
G01X838403Y-62737D02*
X840737D01*
G01X843753Y-66070D02*
Y-61070D01*
G01Y-63487D02*
X844170Y-63070D01*
X844587Y-62820D01*
X845253Y-62737D01*
X845753Y-62820D01*
X846337Y-63153D01*
X846587Y-63653D01*
Y-66070D01*
G01X850770Y-62737D02*
Y-66070D01*
G01Y-61403D02*
X850603Y-61320D01*
Y-61153D01*
X850770Y-61070D01*
X850937Y-61153D01*
Y-61320D01*
X850770Y-61403D01*
G01X855120Y-65487D02*
X855537Y-65820D01*
X856120Y-66070D01*
X856620D01*
X857120Y-65903D01*
X857453Y-65653D01*
X857620Y-65320D01*
X857537Y-64820D01*
X857203Y-64570D01*
X855703Y-64070D01*
X855370Y-63487D01*
X855537Y-63070D01*
X855870Y-62820D01*
X856370Y-62737D01*
X856870Y-62820D01*
X857370Y-63070D01*
G01X866153Y-66070D02*
Y-61070D01*
G01X868820Y-62737D02*
X866153Y-64653D01*
G01X867237Y-63903D02*
X868987Y-66070D01*
G01X873170Y-62737D02*
Y-66070D01*
G01Y-61403D02*
X873003Y-61320D01*
Y-61153D01*
X873170Y-61070D01*
X873337Y-61153D01*
Y-61320D01*
X873170Y-61403D01*
G01X877353Y-66070D02*
Y-62737D01*
G01Y-63570D02*
X877687Y-63153D01*
X878187Y-62820D01*
X878853Y-62737D01*
X879437Y-62820D01*
X879937Y-63153D01*
X880187Y-63737D01*
Y-66070D01*
G01X885870Y-61070D02*
Y-66070D01*
G01Y-65320D02*
X885537Y-65737D01*
X885037Y-65987D01*
X884453Y-66070D01*
X883787Y-65903D01*
X883287Y-65487D01*
X882953Y-64987D01*
X882870Y-64403D01*
X882953Y-63820D01*
X883287Y-63320D01*
X883787Y-62903D01*
X884453Y-62737D01*
X885037Y-62820D01*
X885453Y-62987D01*
X885870Y-63320D01*
G01X895570Y-66070D02*
X895070Y-65987D01*
X894570Y-65653D01*
X894237Y-65070D01*
X894070Y-64403D01*
X894237Y-63737D01*
X894570Y-63153D01*
X895070Y-62820D01*
X895570Y-62737D01*
X896070Y-62820D01*
X896570Y-63153D01*
X896903Y-63737D01*
X896987Y-64403D01*
X896903Y-65070D01*
X896570Y-65653D01*
X896070Y-65987D01*
X895570Y-66070D01*
G01X900670D02*
Y-61820D01*
X900837Y-61403D01*
X901170Y-61153D01*
X901670Y-61070D01*
X902170Y-61237D01*
X902420Y-61653D01*
G01X901420Y-63070D02*
X899753D01*
G01X913870Y-61070D02*
Y-66070D01*
G01Y-65320D02*
X913537Y-65737D01*
X913037Y-65987D01*
X912453Y-66070D01*
X911787Y-65903D01*
X911287Y-65487D01*
X910953Y-64987D01*
X910870Y-64403D01*
X910953Y-63820D01*
X911287Y-63320D01*
X911787Y-62903D01*
X912453Y-62737D01*
X913037Y-62820D01*
X913453Y-62987D01*
X913870Y-63320D01*
G01X916720Y-63820D02*
X919387D01*
X919137Y-63237D01*
X918720Y-62903D01*
X918137Y-62737D01*
X917553Y-62820D01*
X917053Y-63070D01*
X916720Y-63653D01*
X916553Y-64153D01*
Y-64653D01*
X916720Y-65153D01*
X917137Y-65653D01*
X917637Y-65987D01*
X918220Y-66070D01*
X918803Y-65903D01*
X919387Y-65403D01*
G01X922320Y-65487D02*
X922737Y-65820D01*
X923320Y-66070D01*
X923820D01*
X924320Y-65903D01*
X924653Y-65653D01*
X924820Y-65320D01*
X924737Y-64820D01*
X924403Y-64570D01*
X922903Y-64070D01*
X922570Y-63487D01*
X922737Y-63070D01*
X923070Y-62820D01*
X923570Y-62737D01*
X924070Y-62820D01*
X924570Y-63070D01*
G01X929170Y-62737D02*
Y-66070D01*
G01Y-61403D02*
X929003Y-61320D01*
Y-61153D01*
X929170Y-61070D01*
X929337Y-61153D01*
Y-61320D01*
X929170Y-61403D01*
G01X933603Y-67320D02*
X934187Y-67653D01*
X934853Y-67737D01*
X935437Y-67653D01*
X935937Y-67237D01*
X936270Y-66653D01*
Y-62737D01*
G01Y-63403D02*
X935937Y-63070D01*
X935437Y-62820D01*
X934853Y-62737D01*
X934187Y-62903D01*
X933770Y-63237D01*
X933437Y-63820D01*
X933270Y-64403D01*
X933353Y-64903D01*
X933687Y-65487D01*
X934187Y-65903D01*
X934853Y-66070D01*
X935353Y-65987D01*
X935937Y-65653D01*
X936270Y-65320D01*
G01X938953Y-66070D02*
Y-62737D01*
G01Y-63570D02*
X939287Y-63153D01*
X939787Y-62820D01*
X940453Y-62737D01*
X941037Y-62820D01*
X941537Y-63153D01*
X941787Y-63737D01*
Y-66070D01*
G01X945803Y-66987D02*
X946137Y-65903D01*
G01X955670Y-67737D02*
Y-62737D01*
G01Y-63487D02*
X956087Y-63070D01*
X956503Y-62820D01*
X957170Y-62737D01*
X957753Y-62820D01*
X958337Y-63237D01*
X958587Y-63820D01*
X958670Y-64403D01*
X958587Y-64987D01*
X958337Y-65570D01*
X957837Y-65903D01*
X957170Y-66070D01*
X956587Y-65987D01*
X956003Y-65737D01*
X955670Y-65403D01*
G01X962770Y-66070D02*
Y-61070D01*
G01X967120Y-63820D02*
X969787D01*
X969537Y-63237D01*
X969120Y-62903D01*
X968537Y-62737D01*
X967953Y-62820D01*
X967453Y-63070D01*
X967120Y-63653D01*
X966953Y-64153D01*
Y-64653D01*
X967120Y-65153D01*
X967537Y-65653D01*
X968037Y-65987D01*
X968620Y-66070D01*
X969203Y-65903D01*
X969787Y-65403D01*
G01X975470Y-66070D02*
Y-62737D01*
G01Y-63320D02*
X975137Y-62987D01*
X974637Y-62820D01*
X974053Y-62737D01*
X973470Y-62903D01*
X972970Y-63237D01*
X972637Y-63737D01*
X972470Y-64403D01*
X972637Y-65070D01*
X972970Y-65570D01*
X973470Y-65903D01*
X974053Y-66070D01*
X974637Y-65987D01*
X975137Y-65737D01*
X975470Y-65403D01*
G01X978320Y-65487D02*
X978737Y-65820D01*
X979320Y-66070D01*
X979820D01*
X980320Y-65903D01*
X980653Y-65653D01*
X980820Y-65320D01*
X980737Y-64820D01*
X980403Y-64570D01*
X978903Y-64070D01*
X978570Y-63487D01*
X978737Y-63070D01*
X979070Y-62820D01*
X979570Y-62737D01*
X980070Y-62820D01*
X980570Y-63070D01*
G01X983920Y-63820D02*
X986587D01*
X986337Y-63237D01*
X985920Y-62903D01*
X985337Y-62737D01*
X984753Y-62820D01*
X984253Y-63070D01*
X983920Y-63653D01*
X983753Y-64153D01*
Y-64653D01*
X983920Y-65153D01*
X984337Y-65653D01*
X984837Y-65987D01*
X985420Y-66070D01*
X986003Y-65903D01*
X986587Y-65403D01*
G01X995870Y-66070D02*
Y-61820D01*
X996037Y-61403D01*
X996370Y-61153D01*
X996870Y-61070D01*
X997370Y-61237D01*
X997620Y-61653D01*
G01X996620Y-63070D02*
X994953D01*
G01X1001970Y-66070D02*
X1001470Y-65987D01*
X1000970Y-65653D01*
X1000637Y-65070D01*
X1000470Y-64403D01*
X1000637Y-63737D01*
X1000970Y-63153D01*
X1001470Y-62820D01*
X1001970Y-62737D01*
X1002470Y-62820D01*
X1002970Y-63153D01*
X1003303Y-63737D01*
X1003387Y-64403D01*
X1003303Y-65070D01*
X1002970Y-65653D01*
X1002470Y-65987D01*
X1001970Y-66070D01*
G01X1007570D02*
Y-61070D01*
G01X1013170Y-66070D02*
Y-61070D01*
G01X1018770Y-66070D02*
X1018270Y-65987D01*
X1017770Y-65653D01*
X1017437Y-65070D01*
X1017270Y-64403D01*
X1017437Y-63737D01*
X1017770Y-63153D01*
X1018270Y-62820D01*
X1018770Y-62737D01*
X1019270Y-62820D01*
X1019770Y-63153D01*
X1020103Y-63737D01*
X1020187Y-64403D01*
X1020103Y-65070D01*
X1019770Y-65653D01*
X1019270Y-65987D01*
X1018770Y-66070D01*
G01X1022287Y-62737D02*
X1023287Y-66070D01*
X1024370Y-62737D01*
X1025453Y-66070D01*
X1026453Y-62737D01*
G01X1029970Y-66237D02*
X1029803Y-66153D01*
Y-65987D01*
X1029970Y-65903D01*
X1030137Y-65987D01*
Y-66153D01*
X1029970Y-66237D01*
G01X1040170Y-61070D02*
X1042170D01*
G01X1041170D02*
Y-66070D01*
G01X1040170D02*
X1042170D01*
G01X1046270D02*
Y-61820D01*
X1046437Y-61403D01*
X1046770Y-61153D01*
X1047270Y-61070D01*
X1047770Y-61237D01*
X1048020Y-61653D01*
G01X1047020Y-63070D02*
X1045353D01*
G01X1056553Y-66070D02*
Y-62737D01*
G01Y-63570D02*
X1056887Y-63153D01*
X1057387Y-62820D01*
X1058053Y-62737D01*
X1058637Y-62820D01*
X1059137Y-63153D01*
X1059387Y-63737D01*
Y-66070D01*
G01X1063570D02*
X1063070Y-65987D01*
X1062570Y-65653D01*
X1062237Y-65070D01*
X1062070Y-64403D01*
X1062237Y-63737D01*
X1062570Y-63153D01*
X1063070Y-62820D01*
X1063570Y-62737D01*
X1064070Y-62820D01*
X1064570Y-63153D01*
X1064903Y-63737D01*
X1064987Y-64403D01*
X1064903Y-65070D01*
X1064570Y-65653D01*
X1064070Y-65987D01*
X1063570Y-66070D01*
G01X1069170Y-61070D02*
Y-66070D01*
G01X1068003Y-62737D02*
X1070337D01*
G01X1074603Y-66987D02*
X1074937Y-65903D01*
G01X1084470Y-67737D02*
Y-62737D01*
G01Y-63487D02*
X1084887Y-63070D01*
X1085303Y-62820D01*
X1085970Y-62737D01*
X1086553Y-62820D01*
X1087137Y-63237D01*
X1087387Y-63820D01*
X1087470Y-64403D01*
X1087387Y-64987D01*
X1087137Y-65570D01*
X1086637Y-65903D01*
X1085970Y-66070D01*
X1085387Y-65987D01*
X1084803Y-65737D01*
X1084470Y-65403D01*
G01X1091570Y-66070D02*
Y-61070D01*
G01X1095920Y-63820D02*
X1098587D01*
X1098337Y-63237D01*
X1097920Y-62903D01*
X1097337Y-62737D01*
X1096753Y-62820D01*
X1096253Y-63070D01*
X1095920Y-63653D01*
X1095753Y-64153D01*
Y-64653D01*
X1095920Y-65153D01*
X1096337Y-65653D01*
X1096837Y-65987D01*
X1097420Y-66070D01*
X1098003Y-65903D01*
X1098587Y-65403D01*
G01X1104270Y-66070D02*
Y-62737D01*
G01Y-63320D02*
X1103937Y-62987D01*
X1103437Y-62820D01*
X1102853Y-62737D01*
X1102270Y-62903D01*
X1101770Y-63237D01*
X1101437Y-63737D01*
X1101270Y-64403D01*
X1101437Y-65070D01*
X1101770Y-65570D01*
X1102270Y-65903D01*
X1102853Y-66070D01*
X1103437Y-65987D01*
X1103937Y-65737D01*
X1104270Y-65403D01*
G01X1107120Y-65487D02*
X1107537Y-65820D01*
X1108120Y-66070D01*
X1108620D01*
X1109120Y-65903D01*
X1109453Y-65653D01*
X1109620Y-65320D01*
X1109537Y-64820D01*
X1109203Y-64570D01*
X1107703Y-64070D01*
X1107370Y-63487D01*
X1107537Y-63070D01*
X1107870Y-62820D01*
X1108370Y-62737D01*
X1108870Y-62820D01*
X1109370Y-63070D01*
G01X1112720Y-63820D02*
X1115387D01*
X1115137Y-63237D01*
X1114720Y-62903D01*
X1114137Y-62737D01*
X1113553Y-62820D01*
X1113053Y-63070D01*
X1112720Y-63653D01*
X1112553Y-64153D01*
Y-64653D01*
X1112720Y-65153D01*
X1113137Y-65653D01*
X1113637Y-65987D01*
X1114220Y-66070D01*
X1114803Y-65903D01*
X1115387Y-65403D01*
G01X1125170Y-62737D02*
Y-66070D01*
G01Y-61403D02*
X1125003Y-61320D01*
Y-61153D01*
X1125170Y-61070D01*
X1125337Y-61153D01*
Y-61320D01*
X1125170Y-61403D01*
G01X1132270Y-67737D02*
Y-62737D01*
G01Y-63487D02*
X1131853Y-63070D01*
X1131353Y-62820D01*
X1130770Y-62737D01*
X1130270Y-62820D01*
X1129687Y-63237D01*
X1129353Y-63820D01*
X1129270Y-64403D01*
X1129353Y-64987D01*
X1129687Y-65570D01*
X1130270Y-65987D01*
X1130770Y-66070D01*
X1131353Y-65987D01*
X1131853Y-65737D01*
X1132270Y-65320D01*
G01X1134953Y-66070D02*
Y-62737D01*
G01Y-63570D02*
X1135287Y-63153D01*
X1135787Y-62820D01*
X1136453Y-62737D01*
X1137037Y-62820D01*
X1137537Y-63153D01*
X1137787Y-63737D01*
Y-66070D01*
G01X1141970D02*
X1141470Y-65987D01*
X1140970Y-65653D01*
X1140637Y-65070D01*
X1140470Y-64403D01*
X1140637Y-63737D01*
X1140970Y-63153D01*
X1141470Y-62820D01*
X1141970Y-62737D01*
X1142470Y-62820D01*
X1142970Y-63153D01*
X1143303Y-63737D01*
X1143387Y-64403D01*
X1143303Y-65070D01*
X1142970Y-65653D01*
X1142470Y-65987D01*
X1141970Y-66070D01*
G01X1146403D02*
Y-62737D01*
G01Y-63403D02*
X1146820Y-63070D01*
X1147237Y-62820D01*
X1147820Y-62737D01*
X1148237Y-62820D01*
X1148737Y-63070D01*
G01X1151920Y-63820D02*
X1154587D01*
X1154337Y-63237D01*
X1153920Y-62903D01*
X1153337Y-62737D01*
X1152753Y-62820D01*
X1152253Y-63070D01*
X1151920Y-63653D01*
X1151753Y-64153D01*
Y-64653D01*
X1151920Y-65153D01*
X1152337Y-65653D01*
X1152837Y-65987D01*
X1153420Y-66070D01*
X1154003Y-65903D01*
X1154587Y-65403D01*
G01X1164370Y-61070D02*
Y-66070D01*
G01X1163203Y-62737D02*
X1165537D01*
G01X1168553Y-66070D02*
Y-61070D01*
G01Y-63487D02*
X1168970Y-63070D01*
X1169387Y-62820D01*
X1170053Y-62737D01*
X1170553Y-62820D01*
X1171137Y-63153D01*
X1171387Y-63653D01*
Y-66070D01*
G01X1175570Y-62737D02*
Y-66070D01*
G01Y-61403D02*
X1175403Y-61320D01*
Y-61153D01*
X1175570Y-61070D01*
X1175737Y-61153D01*
Y-61320D01*
X1175570Y-61403D01*
G01X1179920Y-65487D02*
X1180337Y-65820D01*
X1180920Y-66070D01*
X1181420D01*
X1181920Y-65903D01*
X1182253Y-65653D01*
X1182420Y-65320D01*
X1182337Y-64820D01*
X1182003Y-64570D01*
X1180503Y-64070D01*
X1180170Y-63487D01*
X1180337Y-63070D01*
X1180670Y-62820D01*
X1181170Y-62737D01*
X1181670Y-62820D01*
X1182170Y-63070D01*
G01X1191203Y-66070D02*
Y-62737D01*
G01Y-63403D02*
X1191620Y-63070D01*
X1192037Y-62820D01*
X1192620Y-62737D01*
X1193037Y-62820D01*
X1193537Y-63070D01*
G01X1196720Y-63820D02*
X1199387D01*
X1199137Y-63237D01*
X1198720Y-62903D01*
X1198137Y-62737D01*
X1197553Y-62820D01*
X1197053Y-63070D01*
X1196720Y-63653D01*
X1196553Y-64153D01*
Y-64653D01*
X1196720Y-65153D01*
X1197137Y-65653D01*
X1197637Y-65987D01*
X1198220Y-66070D01*
X1198803Y-65903D01*
X1199387Y-65403D01*
G01X1205070Y-67737D02*
Y-62737D01*
G01Y-63487D02*
X1204653Y-63070D01*
X1204153Y-62820D01*
X1203570Y-62737D01*
X1203070Y-62820D01*
X1202487Y-63237D01*
X1202153Y-63820D01*
X1202070Y-64403D01*
X1202153Y-64987D01*
X1202487Y-65570D01*
X1203070Y-65987D01*
X1203570Y-66070D01*
X1204153Y-65987D01*
X1204653Y-65737D01*
X1205070Y-65320D01*
G01X1207753Y-62737D02*
Y-65070D01*
X1208087Y-65653D01*
X1208587Y-65987D01*
X1209170Y-66070D01*
X1209753Y-65987D01*
X1210253Y-65653D01*
X1210587Y-65070D01*
G01Y-66070D02*
Y-62737D01*
G01X1213520Y-63820D02*
X1216187D01*
X1215937Y-63237D01*
X1215520Y-62903D01*
X1214937Y-62737D01*
X1214353Y-62820D01*
X1213853Y-63070D01*
X1213520Y-63653D01*
X1213353Y-64153D01*
Y-64653D01*
X1213520Y-65153D01*
X1213937Y-65653D01*
X1214437Y-65987D01*
X1215020Y-66070D01*
X1215603Y-65903D01*
X1216187Y-65403D01*
G01X1219120Y-65487D02*
X1219537Y-65820D01*
X1220120Y-66070D01*
X1220620D01*
X1221120Y-65903D01*
X1221453Y-65653D01*
X1221620Y-65320D01*
X1221537Y-64820D01*
X1221203Y-64570D01*
X1219703Y-64070D01*
X1219370Y-63487D01*
X1219537Y-63070D01*
X1219870Y-62820D01*
X1220370Y-62737D01*
X1220870Y-62820D01*
X1221370Y-63070D01*
G01X1225970Y-61070D02*
Y-66070D01*
G01X1224803Y-62737D02*
X1227137D01*
G01X1231570Y-66237D02*
X1231403Y-66153D01*
Y-65987D01*
X1231570Y-65903D01*
X1231737Y-65987D01*
Y-66153D01*
X1231570Y-66237D01*
G01X713000Y850500D02*
Y-73000D01*
X1343000D01*
Y782000D01*
X713000D01*
G01X694500Y716000D02*
Y-69500D01*
G01X722667Y-38250D02*
X723167Y-38667D01*
X723750Y-38917D01*
X724500Y-39000D01*
X725250Y-38833D01*
X725833Y-38500D01*
X726250Y-37917D01*
X726333Y-37250D01*
X726167Y-36583D01*
X725750Y-36167D01*
X725167Y-35833D01*
X724583Y-35750D01*
X724000Y-35833D01*
X723250Y-36167D01*
X723500Y-34000D01*
X725750D01*
G01X730100Y-39167D02*
X729933Y-39083D01*
Y-38917D01*
X730100Y-38833D01*
X730267Y-38917D01*
Y-39083D01*
X730100Y-39167D01*
G01X739633Y-39000D02*
Y-34000D01*
X741717D01*
X742383Y-34250D01*
X742800Y-34583D01*
X742967Y-35250D01*
X742800Y-35917D01*
X742300Y-36333D01*
X741717Y-36583D01*
X739633D01*
G01X741717D02*
X742967Y-39000D01*
G01X745650Y-36750D02*
X748317D01*
X748067Y-36167D01*
X747650Y-35833D01*
X747067Y-35667D01*
X746483Y-35750D01*
X745983Y-36000D01*
X745650Y-36583D01*
X745483Y-37083D01*
Y-37583D01*
X745650Y-38083D01*
X746067Y-38583D01*
X746567Y-38917D01*
X747150Y-39000D01*
X747733Y-38833D01*
X748317Y-38333D01*
G01X750000Y-39000D02*
Y-35667D01*
G01Y-36583D02*
X750250Y-36167D01*
X750667Y-35833D01*
X751250Y-35667D01*
X751833Y-35833D01*
X752250Y-36167D01*
X752500Y-36583D01*
Y-39000D01*
G01Y-36583D02*
X752750Y-36167D01*
X753167Y-35833D01*
X753750Y-35667D01*
X754333Y-35833D01*
X754750Y-36167D01*
X755000Y-36667D01*
Y-39000D01*
G01X759600D02*
Y-35667D01*
G01Y-36250D02*
X759267Y-35917D01*
X758767Y-35750D01*
X758183Y-35667D01*
X757600Y-35833D01*
X757100Y-36167D01*
X756767Y-36667D01*
X756600Y-37333D01*
X756767Y-38000D01*
X757100Y-38500D01*
X757600Y-38833D01*
X758183Y-39000D01*
X758767Y-38917D01*
X759267Y-38667D01*
X759600Y-38333D01*
G01X762533Y-39000D02*
Y-35667D01*
G01Y-36333D02*
X762950Y-36000D01*
X763367Y-35750D01*
X763950Y-35667D01*
X764367Y-35750D01*
X764867Y-36000D01*
G01X767883Y-39000D02*
Y-34000D01*
G01X770550Y-35667D02*
X767883Y-37583D01*
G01X768967Y-36833D02*
X770717Y-39000D01*
G01X773067Y-39167D02*
X776733Y-35500D01*
G01X774900Y-34833D02*
Y-39833D01*
G01X776733Y-39167D02*
X773067Y-35500D01*
G01X772400Y-37333D02*
X777400D01*
G01X713000Y-53000D02*
X1343000D01*
G01X713000Y-23000D02*
X1343000D01*
G01X722667Y-38250D02*
X723167Y-38667D01*
X723750Y-38917D01*
X724500Y-39000D01*
X725250Y-38833D01*
X725833Y-38500D01*
X726250Y-37917D01*
X726333Y-37250D01*
X726167Y-36583D01*
X725750Y-36167D01*
X725167Y-35833D01*
X724583Y-35750D01*
X724000Y-35833D01*
X723250Y-36167D01*
X723500Y-34000D01*
X725750D01*
G01X730100Y-39167D02*
X729933Y-39083D01*
Y-38917D01*
X730100Y-38833D01*
X730267Y-38917D01*
Y-39083D01*
X730100Y-39167D01*
G01X739633Y-39000D02*
Y-34000D01*
X741717D01*
X742383Y-34250D01*
X742800Y-34583D01*
X742967Y-35250D01*
X742800Y-35917D01*
X742300Y-36333D01*
X741717Y-36583D01*
X739633D01*
G01X741717D02*
X742967Y-39000D01*
G01X745650Y-36750D02*
X748317D01*
X748067Y-36167D01*
X747650Y-35833D01*
X747067Y-35667D01*
X746483Y-35750D01*
X745983Y-36000D01*
X745650Y-36583D01*
X745483Y-37083D01*
Y-37583D01*
X745650Y-38083D01*
X746067Y-38583D01*
X746567Y-38917D01*
X747150Y-39000D01*
X747733Y-38833D01*
X748317Y-38333D01*
G01X750000Y-39000D02*
Y-35667D01*
G01Y-36583D02*
X750250Y-36167D01*
X750667Y-35833D01*
X751250Y-35667D01*
X751833Y-35833D01*
X752250Y-36167D01*
X752500Y-36583D01*
Y-39000D01*
G01Y-36583D02*
X752750Y-36167D01*
X753167Y-35833D01*
X753750Y-35667D01*
X754333Y-35833D01*
X754750Y-36167D01*
X755000Y-36667D01*
Y-39000D01*
G01X759600D02*
Y-35667D01*
G01Y-36250D02*
X759267Y-35917D01*
X758767Y-35750D01*
X758183Y-35667D01*
X757600Y-35833D01*
X757100Y-36167D01*
X756767Y-36667D01*
X756600Y-37333D01*
X756767Y-38000D01*
X757100Y-38500D01*
X757600Y-38833D01*
X758183Y-39000D01*
X758767Y-38917D01*
X759267Y-38667D01*
X759600Y-38333D01*
G01X762533Y-39000D02*
Y-35667D01*
G01Y-36333D02*
X762950Y-36000D01*
X763367Y-35750D01*
X763950Y-35667D01*
X764367Y-35750D01*
X764867Y-36000D01*
G01X767883Y-39000D02*
Y-34000D01*
G01X770550Y-35667D02*
X767883Y-37583D01*
G01X768967Y-36833D02*
X770717Y-39000D01*
G01X773067Y-39167D02*
X776733Y-35500D01*
G01X774900Y-34833D02*
Y-39833D01*
G01X776733Y-39167D02*
X773067Y-35500D01*
G01X772400Y-37333D02*
X777400D01*
G01X713000Y-53000D02*
X1343000D01*
G01X713000Y-23000D02*
X1343000D01*
G01X713000Y85500D02*
X1343000D01*
G01X713000D02*
X1343000D01*
G01X713000Y335500D02*
X1343000D01*
G01X713000D02*
X1343000D01*
G01X721407Y374673D02*
X725073Y378340D01*
G01X723240Y379007D02*
Y374007D01*
G01X725073Y374673D02*
X721407Y378340D01*
G01X720740Y376507D02*
X725740D01*
G01X728423Y373173D02*
X727590Y374007D01*
X727173Y374840D01*
Y378173D01*
X727590Y379007D01*
X728423Y379840D01*
G01X732607Y375590D02*
X733107Y375173D01*
X733690Y374923D01*
X734440Y374840D01*
X735190Y375007D01*
X735773Y375340D01*
X736190Y375923D01*
X736273Y376590D01*
X736107Y377257D01*
X735690Y377673D01*
X735107Y378007D01*
X734523Y378090D01*
X733940Y378007D01*
X733190Y377673D01*
X733440Y379840D01*
X735690D01*
G01X740040Y374673D02*
X739873Y374757D01*
Y374923D01*
X740040Y375007D01*
X740207Y374923D01*
Y374757D01*
X740040Y374673D01*
G01X745640Y374840D02*
Y379840D01*
X744640Y378840D01*
G01Y374840D02*
X746640D01*
G01X751657Y373173D02*
X752490Y374007D01*
X752907Y374840D01*
Y378173D01*
X752490Y379007D01*
X751657Y379840D01*
G01X721107Y408303D02*
X724773Y411970D01*
G01X722940Y412637D02*
Y407637D01*
G01X724773Y408303D02*
X721107Y411970D01*
G01X720440Y410137D02*
X725440D01*
G01X728123Y406803D02*
X727290Y407637D01*
X726873Y408470D01*
Y411803D01*
X727290Y412637D01*
X728123Y413470D01*
G01X732307Y409220D02*
X732807Y408803D01*
X733390Y408553D01*
X734140Y408470D01*
X734890Y408637D01*
X735473Y408970D01*
X735890Y409553D01*
X735973Y410220D01*
X735807Y410887D01*
X735390Y411303D01*
X734807Y411637D01*
X734223Y411720D01*
X733640Y411637D01*
X732890Y411303D01*
X733140Y413470D01*
X735390D01*
G01X739740Y408303D02*
X739573Y408387D01*
Y408553D01*
X739740Y408637D01*
X739907Y408553D01*
Y408387D01*
X739740Y408303D01*
G01X745340Y408470D02*
Y413470D01*
X744340Y412470D01*
G01Y408470D02*
X746340D01*
G01X751357Y406803D02*
X752190Y407637D01*
X752607Y408470D01*
Y411803D01*
X752190Y412637D01*
X751357Y413470D01*
G01X725500Y349500D02*
Y354500D01*
X722417Y350917D01*
X726583D01*
G01X730100Y349333D02*
X729933Y349417D01*
Y349583D01*
X730100Y349667D01*
X730267Y349583D01*
Y349417D01*
X730100Y349333D01*
G01X739800Y349500D02*
Y354500D01*
G01Y352000D02*
X740217Y352500D01*
X740717Y352750D01*
X741217Y352833D01*
X741967Y352667D01*
X742467Y352333D01*
X742800Y351750D01*
Y351083D01*
X742633Y350417D01*
X742300Y349917D01*
X741717Y349583D01*
X741217Y349500D01*
X740717Y349583D01*
X740217Y349833D01*
X739800Y350250D01*
G01X748400Y349500D02*
Y352833D01*
G01Y352250D02*
X748067Y352583D01*
X747567Y352750D01*
X746983Y352833D01*
X746400Y352667D01*
X745900Y352333D01*
X745567Y351833D01*
X745400Y351167D01*
X745567Y350500D01*
X745900Y350000D01*
X746400Y349667D01*
X746983Y349500D01*
X747567Y349583D01*
X748067Y349833D01*
X748400Y350167D01*
G01X753833Y352417D02*
X753250Y352750D01*
X752750Y352833D01*
X752083Y352667D01*
X751583Y352333D01*
X751250Y351750D01*
X751167Y351167D01*
X751250Y350583D01*
X751583Y350083D01*
X752083Y349667D01*
X752750Y349500D01*
X753333Y349667D01*
X753833Y350000D01*
G01X756683Y349500D02*
Y354500D01*
G01X759350Y352833D02*
X756683Y350917D01*
G01X757767Y351667D02*
X759517Y349500D01*
G01X765200Y354500D02*
Y349500D01*
G01Y350250D02*
X764867Y349833D01*
X764367Y349583D01*
X763783Y349500D01*
X763117Y349667D01*
X762617Y350083D01*
X762283Y350583D01*
X762200Y351167D01*
X762283Y351750D01*
X762617Y352250D01*
X763117Y352667D01*
X763783Y352833D01*
X764367Y352750D01*
X764783Y352583D01*
X765200Y352250D01*
G01X768133Y349500D02*
Y352833D01*
G01Y352167D02*
X768550Y352500D01*
X768967Y352750D01*
X769550Y352833D01*
X769967Y352750D01*
X770467Y352500D01*
G01X774900Y352833D02*
Y349500D01*
G01Y354167D02*
X774733Y354250D01*
Y354417D01*
X774900Y354500D01*
X775067Y354417D01*
Y354250D01*
X774900Y354167D01*
G01X780500Y349500D02*
Y354500D01*
G01X786100Y349500D02*
Y354500D01*
G01X798800Y349500D02*
Y352833D01*
G01Y352250D02*
X798467Y352583D01*
X797967Y352750D01*
X797383Y352833D01*
X796800Y352667D01*
X796300Y352333D01*
X795967Y351833D01*
X795800Y351167D01*
X795967Y350500D01*
X796300Y350000D01*
X796800Y349667D01*
X797383Y349500D01*
X797967Y349583D01*
X798467Y349833D01*
X798800Y350167D01*
G01X801483Y349500D02*
Y352833D01*
G01Y352000D02*
X801817Y352417D01*
X802317Y352750D01*
X802983Y352833D01*
X803567Y352750D01*
X804067Y352417D01*
X804317Y351833D01*
Y349500D01*
G01X810000Y354500D02*
Y349500D01*
G01Y350250D02*
X809667Y349833D01*
X809167Y349583D01*
X808583Y349500D01*
X807917Y349667D01*
X807417Y350083D01*
X807083Y350583D01*
X807000Y351167D01*
X807083Y351750D01*
X807417Y352250D01*
X807917Y352667D01*
X808583Y352833D01*
X809167Y352750D01*
X809583Y352583D01*
X810000Y352250D01*
G01X818450Y350083D02*
X818867Y349750D01*
X819450Y349500D01*
X819950D01*
X820450Y349667D01*
X820783Y349917D01*
X820950Y350250D01*
X820867Y350750D01*
X820533Y351000D01*
X819033Y351500D01*
X818700Y352083D01*
X818867Y352500D01*
X819200Y352750D01*
X819700Y352833D01*
X820200Y352750D01*
X820700Y352500D01*
G01X826800Y347833D02*
Y352833D01*
G01Y352083D02*
X826383Y352500D01*
X825883Y352750D01*
X825300Y352833D01*
X824800Y352750D01*
X824217Y352333D01*
X823883Y351750D01*
X823800Y351167D01*
X823883Y350583D01*
X824217Y350000D01*
X824800Y349583D01*
X825300Y349500D01*
X825883Y349583D01*
X826383Y349833D01*
X826800Y350250D01*
G01X829483Y352833D02*
Y350500D01*
X829817Y349917D01*
X830317Y349583D01*
X830900Y349500D01*
X831483Y349583D01*
X831983Y349917D01*
X832317Y350500D01*
G01Y349500D02*
Y352833D01*
G01X838000Y349500D02*
Y352833D01*
G01Y352250D02*
X837667Y352583D01*
X837167Y352750D01*
X836583Y352833D01*
X836000Y352667D01*
X835500Y352333D01*
X835167Y351833D01*
X835000Y351167D01*
X835167Y350500D01*
X835500Y350000D01*
X836000Y349667D01*
X836583Y349500D01*
X837167Y349583D01*
X837667Y349833D01*
X838000Y350167D01*
G01X840933Y349500D02*
Y352833D01*
G01Y352167D02*
X841350Y352500D01*
X841767Y352750D01*
X842350Y352833D01*
X842767Y352750D01*
X843267Y352500D01*
G01X846450Y351750D02*
X849117D01*
X848867Y352333D01*
X848450Y352667D01*
X847867Y352833D01*
X847283Y352750D01*
X846783Y352500D01*
X846450Y351917D01*
X846283Y351417D01*
Y350917D01*
X846450Y350417D01*
X846867Y349917D01*
X847367Y349583D01*
X847950Y349500D01*
X848533Y349667D01*
X849117Y350167D01*
G01X857483Y349500D02*
Y354500D01*
G01Y352083D02*
X857900Y352500D01*
X858317Y352750D01*
X858983Y352833D01*
X859483Y352750D01*
X860067Y352417D01*
X860317Y351917D01*
Y349500D01*
G01X864500D02*
X864000Y349583D01*
X863500Y349917D01*
X863167Y350500D01*
X863000Y351167D01*
X863167Y351833D01*
X863500Y352417D01*
X864000Y352750D01*
X864500Y352833D01*
X865000Y352750D01*
X865500Y352417D01*
X865833Y351833D01*
X865917Y351167D01*
X865833Y350500D01*
X865500Y349917D01*
X865000Y349583D01*
X864500Y349500D01*
G01X870100D02*
Y354500D01*
G01X874450Y351750D02*
X877117D01*
X876867Y352333D01*
X876450Y352667D01*
X875867Y352833D01*
X875283Y352750D01*
X874783Y352500D01*
X874450Y351917D01*
X874283Y351417D01*
Y350917D01*
X874450Y350417D01*
X874867Y349917D01*
X875367Y349583D01*
X875950Y349500D01*
X876533Y349667D01*
X877117Y350167D01*
G01X881300Y349333D02*
X881133Y349417D01*
Y349583D01*
X881300Y349667D01*
X881467Y349583D01*
Y349417D01*
X881300Y349333D01*
G01Y351583D02*
X881133Y351667D01*
Y351833D01*
X881300Y351917D01*
X881467Y351833D01*
Y351667D01*
X881300Y351583D01*
G01X721217Y391740D02*
X723300Y386740D01*
X725383Y391740D01*
G01X728900Y390073D02*
Y386740D01*
G01Y391407D02*
X728733Y391490D01*
Y391657D01*
X728900Y391740D01*
X729067Y391657D01*
Y391490D01*
X728900Y391407D01*
G01X736000Y386740D02*
Y390073D01*
G01Y389490D02*
X735667Y389823D01*
X735167Y389990D01*
X734583Y390073D01*
X734000Y389907D01*
X733500Y389573D01*
X733167Y389073D01*
X733000Y388407D01*
X733167Y387740D01*
X733500Y387240D01*
X734000Y386907D01*
X734583Y386740D01*
X735167Y386823D01*
X735667Y387073D01*
X736000Y387407D01*
G01X744700Y391740D02*
X746700D01*
G01X745700D02*
Y386740D01*
G01X744700D02*
X746700D01*
G01X749883D02*
Y390073D01*
G01Y389240D02*
X750217Y389657D01*
X750717Y389990D01*
X751383Y390073D01*
X751967Y389990D01*
X752467Y389657D01*
X752717Y389073D01*
Y386740D01*
G01X760833D02*
Y391740D01*
X762833D01*
X763500Y391490D01*
X764000Y390907D01*
X764167Y390240D01*
X764000Y389573D01*
X763583Y389073D01*
X762833Y388823D01*
X760833D01*
G01X769600Y386740D02*
Y390073D01*
G01Y389490D02*
X769267Y389823D01*
X768767Y389990D01*
X768183Y390073D01*
X767600Y389907D01*
X767100Y389573D01*
X766767Y389073D01*
X766600Y388407D01*
X766767Y387740D01*
X767100Y387240D01*
X767600Y386907D01*
X768183Y386740D01*
X768767Y386823D01*
X769267Y387073D01*
X769600Y387407D01*
G01X775200Y391740D02*
Y386740D01*
G01Y387490D02*
X774867Y387073D01*
X774367Y386823D01*
X773783Y386740D01*
X773117Y386907D01*
X772617Y387323D01*
X772283Y387823D01*
X772200Y388407D01*
X772283Y388990D01*
X772617Y389490D01*
X773117Y389907D01*
X773783Y390073D01*
X774367Y389990D01*
X774783Y389823D01*
X775200Y389490D01*
G01X778883Y385073D02*
X778050Y385907D01*
X777633Y386740D01*
Y390073D01*
X778050Y390907D01*
X778883Y391740D01*
G01X782817D02*
X784900Y386740D01*
X786983Y391740D01*
G01X789500D02*
X791500D01*
G01X790500D02*
Y386740D01*
G01X789500D02*
X791500D01*
G01X794433D02*
Y391740D01*
X796433D01*
X797100Y391490D01*
X797600Y390907D01*
X797767Y390240D01*
X797600Y389573D01*
X797183Y389073D01*
X796433Y388823D01*
X794433D01*
G01X802117Y385073D02*
X802950Y385907D01*
X803367Y386740D01*
Y390073D01*
X802950Y390907D01*
X802117Y391740D01*
G01X720917Y424500D02*
X723000Y419500D01*
X725083Y424500D01*
G01X728600Y422833D02*
Y419500D01*
G01Y424167D02*
X728433Y424250D01*
Y424417D01*
X728600Y424500D01*
X728767Y424417D01*
Y424250D01*
X728600Y424167D01*
G01X735700Y419500D02*
Y422833D01*
G01Y422250D02*
X735367Y422583D01*
X734867Y422750D01*
X734283Y422833D01*
X733700Y422667D01*
X733200Y422333D01*
X732867Y421833D01*
X732700Y421167D01*
X732867Y420500D01*
X733200Y420000D01*
X733700Y419667D01*
X734283Y419500D01*
X734867Y419583D01*
X735367Y419833D01*
X735700Y420167D01*
G01X745400Y419500D02*
X744733Y419583D01*
X744150Y419917D01*
X743650Y420417D01*
X743317Y421000D01*
X743150Y421667D01*
Y422333D01*
X743317Y423000D01*
X743650Y423583D01*
X744150Y424083D01*
X744733Y424417D01*
X745400Y424500D01*
X746067Y424417D01*
X746650Y424083D01*
X747150Y423583D01*
X747483Y423000D01*
X747650Y422333D01*
Y421667D01*
X747483Y421000D01*
X747150Y420417D01*
X746650Y419917D01*
X746067Y419583D01*
X745400Y419500D01*
G01X749583D02*
Y422833D01*
G01Y422000D02*
X749917Y422417D01*
X750417Y422750D01*
X751083Y422833D01*
X751667Y422750D01*
X752167Y422417D01*
X752417Y421833D01*
Y419500D01*
G01X760533D02*
Y424500D01*
X762533D01*
X763200Y424250D01*
X763700Y423667D01*
X763867Y423000D01*
X763700Y422333D01*
X763283Y421833D01*
X762533Y421583D01*
X760533D01*
G01X769300Y419500D02*
Y422833D01*
G01Y422250D02*
X768967Y422583D01*
X768467Y422750D01*
X767883Y422833D01*
X767300Y422667D01*
X766800Y422333D01*
X766467Y421833D01*
X766300Y421167D01*
X766467Y420500D01*
X766800Y420000D01*
X767300Y419667D01*
X767883Y419500D01*
X768467Y419583D01*
X768967Y419833D01*
X769300Y420167D01*
G01X774900Y424500D02*
Y419500D01*
G01Y420250D02*
X774567Y419833D01*
X774067Y419583D01*
X773483Y419500D01*
X772817Y419667D01*
X772317Y420083D01*
X771983Y420583D01*
X771900Y421167D01*
X771983Y421750D01*
X772317Y422250D01*
X772817Y422667D01*
X773483Y422833D01*
X774067Y422750D01*
X774483Y422583D01*
X774900Y422250D01*
G01X778583Y417833D02*
X777750Y418667D01*
X777333Y419500D01*
Y422833D01*
X777750Y423667D01*
X778583Y424500D01*
G01X782517D02*
X784600Y419500D01*
X786683Y424500D01*
G01X790200Y419500D02*
X789533Y419583D01*
X788950Y419917D01*
X788450Y420417D01*
X788117Y421000D01*
X787950Y421667D01*
Y422333D01*
X788117Y423000D01*
X788450Y423583D01*
X788950Y424083D01*
X789533Y424417D01*
X790200Y424500D01*
X790867Y424417D01*
X791450Y424083D01*
X791950Y423583D01*
X792283Y423000D01*
X792450Y422333D01*
Y421667D01*
X792283Y421000D01*
X791950Y420417D01*
X791450Y419917D01*
X790867Y419583D01*
X790200Y419500D01*
G01X794133D02*
Y424500D01*
X796133D01*
X796800Y424250D01*
X797300Y423667D01*
X797467Y423000D01*
X797300Y422333D01*
X796883Y421833D01*
X796133Y421583D01*
X794133D01*
G01X801817Y417833D02*
X802650Y418667D01*
X803067Y419500D01*
Y422833D01*
X802650Y423667D01*
X801817Y424500D01*
G01X713000Y365500D02*
X1343000D01*
G01X713000Y400500D02*
X1343000D01*
G01X721407Y374673D02*
X725073Y378340D01*
G01X723240Y379007D02*
Y374007D01*
G01X725073Y374673D02*
X721407Y378340D01*
G01X720740Y376507D02*
X725740D01*
G01X728423Y373173D02*
X727590Y374007D01*
X727173Y374840D01*
Y378173D01*
X727590Y379007D01*
X728423Y379840D01*
G01X732607Y375590D02*
X733107Y375173D01*
X733690Y374923D01*
X734440Y374840D01*
X735190Y375007D01*
X735773Y375340D01*
X736190Y375923D01*
X736273Y376590D01*
X736107Y377257D01*
X735690Y377673D01*
X735107Y378007D01*
X734523Y378090D01*
X733940Y378007D01*
X733190Y377673D01*
X733440Y379840D01*
X735690D01*
G01X740040Y374673D02*
X739873Y374757D01*
Y374923D01*
X740040Y375007D01*
X740207Y374923D01*
Y374757D01*
X740040Y374673D01*
G01X745640Y374840D02*
Y379840D01*
X744640Y378840D01*
G01Y374840D02*
X746640D01*
G01X751657Y373173D02*
X752490Y374007D01*
X752907Y374840D01*
Y378173D01*
X752490Y379007D01*
X751657Y379840D01*
G01X721107Y408303D02*
X724773Y411970D01*
G01X722940Y412637D02*
Y407637D01*
G01X724773Y408303D02*
X721107Y411970D01*
G01X720440Y410137D02*
X725440D01*
G01X728123Y406803D02*
X727290Y407637D01*
X726873Y408470D01*
Y411803D01*
X727290Y412637D01*
X728123Y413470D01*
G01X732307Y409220D02*
X732807Y408803D01*
X733390Y408553D01*
X734140Y408470D01*
X734890Y408637D01*
X735473Y408970D01*
X735890Y409553D01*
X735973Y410220D01*
X735807Y410887D01*
X735390Y411303D01*
X734807Y411637D01*
X734223Y411720D01*
X733640Y411637D01*
X732890Y411303D01*
X733140Y413470D01*
X735390D01*
G01X739740Y408303D02*
X739573Y408387D01*
Y408553D01*
X739740Y408637D01*
X739907Y408553D01*
Y408387D01*
X739740Y408303D01*
G01X745340Y408470D02*
Y413470D01*
X744340Y412470D01*
G01Y408470D02*
X746340D01*
G01X751357Y406803D02*
X752190Y407637D01*
X752607Y408470D01*
Y411803D01*
X752190Y412637D01*
X751357Y413470D01*
G01X725500Y349500D02*
Y354500D01*
X722417Y350917D01*
X726583D01*
G01X730100Y349333D02*
X729933Y349417D01*
Y349583D01*
X730100Y349667D01*
X730267Y349583D01*
Y349417D01*
X730100Y349333D01*
G01X739800Y349500D02*
Y354500D01*
G01Y352000D02*
X740217Y352500D01*
X740717Y352750D01*
X741217Y352833D01*
X741967Y352667D01*
X742467Y352333D01*
X742800Y351750D01*
Y351083D01*
X742633Y350417D01*
X742300Y349917D01*
X741717Y349583D01*
X741217Y349500D01*
X740717Y349583D01*
X740217Y349833D01*
X739800Y350250D01*
G01X748400Y349500D02*
Y352833D01*
G01Y352250D02*
X748067Y352583D01*
X747567Y352750D01*
X746983Y352833D01*
X746400Y352667D01*
X745900Y352333D01*
X745567Y351833D01*
X745400Y351167D01*
X745567Y350500D01*
X745900Y350000D01*
X746400Y349667D01*
X746983Y349500D01*
X747567Y349583D01*
X748067Y349833D01*
X748400Y350167D01*
G01X753833Y352417D02*
X753250Y352750D01*
X752750Y352833D01*
X752083Y352667D01*
X751583Y352333D01*
X751250Y351750D01*
X751167Y351167D01*
X751250Y350583D01*
X751583Y350083D01*
X752083Y349667D01*
X752750Y349500D01*
X753333Y349667D01*
X753833Y350000D01*
G01X756683Y349500D02*
Y354500D01*
G01X759350Y352833D02*
X756683Y350917D01*
G01X757767Y351667D02*
X759517Y349500D01*
G01X765200Y354500D02*
Y349500D01*
G01Y350250D02*
X764867Y349833D01*
X764367Y349583D01*
X763783Y349500D01*
X763117Y349667D01*
X762617Y350083D01*
X762283Y350583D01*
X762200Y351167D01*
X762283Y351750D01*
X762617Y352250D01*
X763117Y352667D01*
X763783Y352833D01*
X764367Y352750D01*
X764783Y352583D01*
X765200Y352250D01*
G01X768133Y349500D02*
Y352833D01*
G01Y352167D02*
X768550Y352500D01*
X768967Y352750D01*
X769550Y352833D01*
X769967Y352750D01*
X770467Y352500D01*
G01X774900Y352833D02*
Y349500D01*
G01Y354167D02*
X774733Y354250D01*
Y354417D01*
X774900Y354500D01*
X775067Y354417D01*
Y354250D01*
X774900Y354167D01*
G01X780500Y349500D02*
Y354500D01*
G01X786100Y349500D02*
Y354500D01*
G01X798800Y349500D02*
Y352833D01*
G01Y352250D02*
X798467Y352583D01*
X797967Y352750D01*
X797383Y352833D01*
X796800Y352667D01*
X796300Y352333D01*
X795967Y351833D01*
X795800Y351167D01*
X795967Y350500D01*
X796300Y350000D01*
X796800Y349667D01*
X797383Y349500D01*
X797967Y349583D01*
X798467Y349833D01*
X798800Y350167D01*
G01X801483Y349500D02*
Y352833D01*
G01Y352000D02*
X801817Y352417D01*
X802317Y352750D01*
X802983Y352833D01*
X803567Y352750D01*
X804067Y352417D01*
X804317Y351833D01*
Y349500D01*
G01X810000Y354500D02*
Y349500D01*
G01Y350250D02*
X809667Y349833D01*
X809167Y349583D01*
X808583Y349500D01*
X807917Y349667D01*
X807417Y350083D01*
X807083Y350583D01*
X807000Y351167D01*
X807083Y351750D01*
X807417Y352250D01*
X807917Y352667D01*
X808583Y352833D01*
X809167Y352750D01*
X809583Y352583D01*
X810000Y352250D01*
G01X818450Y350083D02*
X818867Y349750D01*
X819450Y349500D01*
X819950D01*
X820450Y349667D01*
X820783Y349917D01*
X820950Y350250D01*
X820867Y350750D01*
X820533Y351000D01*
X819033Y351500D01*
X818700Y352083D01*
X818867Y352500D01*
X819200Y352750D01*
X819700Y352833D01*
X820200Y352750D01*
X820700Y352500D01*
G01X826800Y347833D02*
Y352833D01*
G01Y352083D02*
X826383Y352500D01*
X825883Y352750D01*
X825300Y352833D01*
X824800Y352750D01*
X824217Y352333D01*
X823883Y351750D01*
X823800Y351167D01*
X823883Y350583D01*
X824217Y350000D01*
X824800Y349583D01*
X825300Y349500D01*
X825883Y349583D01*
X826383Y349833D01*
X826800Y350250D01*
G01X829483Y352833D02*
Y350500D01*
X829817Y349917D01*
X830317Y349583D01*
X830900Y349500D01*
X831483Y349583D01*
X831983Y349917D01*
X832317Y350500D01*
G01Y349500D02*
Y352833D01*
G01X838000Y349500D02*
Y352833D01*
G01Y352250D02*
X837667Y352583D01*
X837167Y352750D01*
X836583Y352833D01*
X836000Y352667D01*
X835500Y352333D01*
X835167Y351833D01*
X835000Y351167D01*
X835167Y350500D01*
X835500Y350000D01*
X836000Y349667D01*
X836583Y349500D01*
X837167Y349583D01*
X837667Y349833D01*
X838000Y350167D01*
G01X840933Y349500D02*
Y352833D01*
G01Y352167D02*
X841350Y352500D01*
X841767Y352750D01*
X842350Y352833D01*
X842767Y352750D01*
X843267Y352500D01*
G01X846450Y351750D02*
X849117D01*
X848867Y352333D01*
X848450Y352667D01*
X847867Y352833D01*
X847283Y352750D01*
X846783Y352500D01*
X846450Y351917D01*
X846283Y351417D01*
Y350917D01*
X846450Y350417D01*
X846867Y349917D01*
X847367Y349583D01*
X847950Y349500D01*
X848533Y349667D01*
X849117Y350167D01*
G01X857483Y349500D02*
Y354500D01*
G01Y352083D02*
X857900Y352500D01*
X858317Y352750D01*
X858983Y352833D01*
X859483Y352750D01*
X860067Y352417D01*
X860317Y351917D01*
Y349500D01*
G01X864500D02*
X864000Y349583D01*
X863500Y349917D01*
X863167Y350500D01*
X863000Y351167D01*
X863167Y351833D01*
X863500Y352417D01*
X864000Y352750D01*
X864500Y352833D01*
X865000Y352750D01*
X865500Y352417D01*
X865833Y351833D01*
X865917Y351167D01*
X865833Y350500D01*
X865500Y349917D01*
X865000Y349583D01*
X864500Y349500D01*
G01X870100D02*
Y354500D01*
G01X874450Y351750D02*
X877117D01*
X876867Y352333D01*
X876450Y352667D01*
X875867Y352833D01*
X875283Y352750D01*
X874783Y352500D01*
X874450Y351917D01*
X874283Y351417D01*
Y350917D01*
X874450Y350417D01*
X874867Y349917D01*
X875367Y349583D01*
X875950Y349500D01*
X876533Y349667D01*
X877117Y350167D01*
G01X881300Y349333D02*
X881133Y349417D01*
Y349583D01*
X881300Y349667D01*
X881467Y349583D01*
Y349417D01*
X881300Y349333D01*
G01Y351583D02*
X881133Y351667D01*
Y351833D01*
X881300Y351917D01*
X881467Y351833D01*
Y351667D01*
X881300Y351583D01*
G01X721217Y391740D02*
X723300Y386740D01*
X725383Y391740D01*
G01X728900Y390073D02*
Y386740D01*
G01Y391407D02*
X728733Y391490D01*
Y391657D01*
X728900Y391740D01*
X729067Y391657D01*
Y391490D01*
X728900Y391407D01*
G01X736000Y386740D02*
Y390073D01*
G01Y389490D02*
X735667Y389823D01*
X735167Y389990D01*
X734583Y390073D01*
X734000Y389907D01*
X733500Y389573D01*
X733167Y389073D01*
X733000Y388407D01*
X733167Y387740D01*
X733500Y387240D01*
X734000Y386907D01*
X734583Y386740D01*
X735167Y386823D01*
X735667Y387073D01*
X736000Y387407D01*
G01X744700Y391740D02*
X746700D01*
G01X745700D02*
Y386740D01*
G01X744700D02*
X746700D01*
G01X749883D02*
Y390073D01*
G01Y389240D02*
X750217Y389657D01*
X750717Y389990D01*
X751383Y390073D01*
X751967Y389990D01*
X752467Y389657D01*
X752717Y389073D01*
Y386740D01*
G01X760833D02*
Y391740D01*
X762833D01*
X763500Y391490D01*
X764000Y390907D01*
X764167Y390240D01*
X764000Y389573D01*
X763583Y389073D01*
X762833Y388823D01*
X760833D01*
G01X769600Y386740D02*
Y390073D01*
G01Y389490D02*
X769267Y389823D01*
X768767Y389990D01*
X768183Y390073D01*
X767600Y389907D01*
X767100Y389573D01*
X766767Y389073D01*
X766600Y388407D01*
X766767Y387740D01*
X767100Y387240D01*
X767600Y386907D01*
X768183Y386740D01*
X768767Y386823D01*
X769267Y387073D01*
X769600Y387407D01*
G01X775200Y391740D02*
Y386740D01*
G01Y387490D02*
X774867Y387073D01*
X774367Y386823D01*
X773783Y386740D01*
X773117Y386907D01*
X772617Y387323D01*
X772283Y387823D01*
X772200Y388407D01*
X772283Y388990D01*
X772617Y389490D01*
X773117Y389907D01*
X773783Y390073D01*
X774367Y389990D01*
X774783Y389823D01*
X775200Y389490D01*
G01X778883Y385073D02*
X778050Y385907D01*
X777633Y386740D01*
Y390073D01*
X778050Y390907D01*
X778883Y391740D01*
G01X782817D02*
X784900Y386740D01*
X786983Y391740D01*
G01X789500D02*
X791500D01*
G01X790500D02*
Y386740D01*
G01X789500D02*
X791500D01*
G01X794433D02*
Y391740D01*
X796433D01*
X797100Y391490D01*
X797600Y390907D01*
X797767Y390240D01*
X797600Y389573D01*
X797183Y389073D01*
X796433Y388823D01*
X794433D01*
G01X802117Y385073D02*
X802950Y385907D01*
X803367Y386740D01*
Y390073D01*
X802950Y390907D01*
X802117Y391740D01*
G01X720917Y424500D02*
X723000Y419500D01*
X725083Y424500D01*
G01X728600Y422833D02*
Y419500D01*
G01Y424167D02*
X728433Y424250D01*
Y424417D01*
X728600Y424500D01*
X728767Y424417D01*
Y424250D01*
X728600Y424167D01*
G01X735700Y419500D02*
Y422833D01*
G01Y422250D02*
X735367Y422583D01*
X734867Y422750D01*
X734283Y422833D01*
X733700Y422667D01*
X733200Y422333D01*
X732867Y421833D01*
X732700Y421167D01*
X732867Y420500D01*
X733200Y420000D01*
X733700Y419667D01*
X734283Y419500D01*
X734867Y419583D01*
X735367Y419833D01*
X735700Y420167D01*
G01X745400Y419500D02*
X744733Y419583D01*
X744150Y419917D01*
X743650Y420417D01*
X743317Y421000D01*
X743150Y421667D01*
Y422333D01*
X743317Y423000D01*
X743650Y423583D01*
X744150Y424083D01*
X744733Y424417D01*
X745400Y424500D01*
X746067Y424417D01*
X746650Y424083D01*
X747150Y423583D01*
X747483Y423000D01*
X747650Y422333D01*
Y421667D01*
X747483Y421000D01*
X747150Y420417D01*
X746650Y419917D01*
X746067Y419583D01*
X745400Y419500D01*
G01X749583D02*
Y422833D01*
G01Y422000D02*
X749917Y422417D01*
X750417Y422750D01*
X751083Y422833D01*
X751667Y422750D01*
X752167Y422417D01*
X752417Y421833D01*
Y419500D01*
G01X760533D02*
Y424500D01*
X762533D01*
X763200Y424250D01*
X763700Y423667D01*
X763867Y423000D01*
X763700Y422333D01*
X763283Y421833D01*
X762533Y421583D01*
X760533D01*
G01X769300Y419500D02*
Y422833D01*
G01Y422250D02*
X768967Y422583D01*
X768467Y422750D01*
X767883Y422833D01*
X767300Y422667D01*
X766800Y422333D01*
X766467Y421833D01*
X766300Y421167D01*
X766467Y420500D01*
X766800Y420000D01*
X767300Y419667D01*
X767883Y419500D01*
X768467Y419583D01*
X768967Y419833D01*
X769300Y420167D01*
G01X774900Y424500D02*
Y419500D01*
G01Y420250D02*
X774567Y419833D01*
X774067Y419583D01*
X773483Y419500D01*
X772817Y419667D01*
X772317Y420083D01*
X771983Y420583D01*
X771900Y421167D01*
X771983Y421750D01*
X772317Y422250D01*
X772817Y422667D01*
X773483Y422833D01*
X774067Y422750D01*
X774483Y422583D01*
X774900Y422250D01*
G01X778583Y417833D02*
X777750Y418667D01*
X777333Y419500D01*
Y422833D01*
X777750Y423667D01*
X778583Y424500D01*
G01X782517D02*
X784600Y419500D01*
X786683Y424500D01*
G01X790200Y419500D02*
X789533Y419583D01*
X788950Y419917D01*
X788450Y420417D01*
X788117Y421000D01*
X787950Y421667D01*
Y422333D01*
X788117Y423000D01*
X788450Y423583D01*
X788950Y424083D01*
X789533Y424417D01*
X790200Y424500D01*
X790867Y424417D01*
X791450Y424083D01*
X791950Y423583D01*
X792283Y423000D01*
X792450Y422333D01*
Y421667D01*
X792283Y421000D01*
X791950Y420417D01*
X791450Y419917D01*
X790867Y419583D01*
X790200Y419500D01*
G01X794133D02*
Y424500D01*
X796133D01*
X796800Y424250D01*
X797300Y423667D01*
X797467Y423000D01*
X797300Y422333D01*
X796883Y421833D01*
X796133Y421583D01*
X794133D01*
G01X801817Y417833D02*
X802650Y418667D01*
X803067Y419500D01*
Y422833D01*
X802650Y423667D01*
X801817Y424500D01*
G01X713000Y365500D02*
X1343000D01*
G01X713000Y400500D02*
X1343000D01*
G01X723667Y443167D02*
X724000Y443417D01*
X724250Y443833D01*
X724417Y444417D01*
X724250Y444917D01*
X723917Y445250D01*
X723333Y445500D01*
X721083D01*
Y440500D01*
X723833D01*
X724417Y440833D01*
X724750Y441333D01*
X724917Y441917D01*
X724750Y442500D01*
X724250Y443000D01*
X723667Y443167D01*
X721083D01*
G01X727183Y443833D02*
Y441500D01*
X727517Y440917D01*
X728017Y440583D01*
X728600Y440500D01*
X729183Y440583D01*
X729683Y440917D01*
X730017Y441500D01*
G01Y440500D02*
Y443833D01*
G01X733033Y440500D02*
Y443833D01*
G01Y443167D02*
X733450Y443500D01*
X733867Y443750D01*
X734450Y443833D01*
X734867Y443750D01*
X735367Y443500D01*
G01X739800Y443833D02*
Y440500D01*
G01Y445167D02*
X739633Y445250D01*
Y445417D01*
X739800Y445500D01*
X739967Y445417D01*
Y445250D01*
X739800Y445167D01*
G01X744150Y442750D02*
X746817D01*
X746567Y443333D01*
X746150Y443667D01*
X745567Y443833D01*
X744983Y443750D01*
X744483Y443500D01*
X744150Y442917D01*
X743983Y442417D01*
Y441917D01*
X744150Y441417D01*
X744567Y440917D01*
X745067Y440583D01*
X745650Y440500D01*
X746233Y440667D01*
X746817Y441167D01*
G01X752500Y445500D02*
Y440500D01*
G01Y441250D02*
X752167Y440833D01*
X751667Y440583D01*
X751083Y440500D01*
X750417Y440667D01*
X749917Y441083D01*
X749583Y441583D01*
X749500Y442167D01*
X749583Y442750D01*
X749917Y443250D01*
X750417Y443667D01*
X751083Y443833D01*
X751667Y443750D01*
X752083Y443583D01*
X752500Y443250D01*
G01X760783Y440500D02*
Y445500D01*
G01Y443083D02*
X761200Y443500D01*
X761617Y443750D01*
X762283Y443833D01*
X762783Y443750D01*
X763367Y443417D01*
X763617Y442917D01*
Y440500D01*
G01X767800D02*
X767300Y440583D01*
X766800Y440917D01*
X766467Y441500D01*
X766300Y442167D01*
X766467Y442833D01*
X766800Y443417D01*
X767300Y443750D01*
X767800Y443833D01*
X768300Y443750D01*
X768800Y443417D01*
X769133Y442833D01*
X769217Y442167D01*
X769133Y441500D01*
X768800Y440917D01*
X768300Y440583D01*
X767800Y440500D01*
G01X773400D02*
Y445500D01*
G01X777750Y442750D02*
X780417D01*
X780167Y443333D01*
X779750Y443667D01*
X779167Y443833D01*
X778583Y443750D01*
X778083Y443500D01*
X777750Y442917D01*
X777583Y442417D01*
Y441917D01*
X777750Y441417D01*
X778167Y440917D01*
X778667Y440583D01*
X779250Y440500D01*
X779833Y440667D01*
X780417Y441167D01*
G01X721417Y461500D02*
Y466500D01*
X724583D01*
G01X723417Y464083D02*
X721417D01*
G01X727183Y464833D02*
Y462500D01*
X727517Y461917D01*
X728017Y461583D01*
X728600Y461500D01*
X729183Y461583D01*
X729683Y461917D01*
X730017Y462500D01*
G01Y461500D02*
Y464833D01*
G01X734200Y461500D02*
Y466500D01*
G01X739800Y461500D02*
Y466500D01*
G01X749500Y459833D02*
Y464833D01*
G01Y464083D02*
X749917Y464500D01*
X750333Y464750D01*
X751000Y464833D01*
X751583Y464750D01*
X752167Y464333D01*
X752417Y463750D01*
X752500Y463167D01*
X752417Y462583D01*
X752167Y462000D01*
X751667Y461667D01*
X751000Y461500D01*
X750417Y461583D01*
X749833Y461833D01*
X749500Y462167D01*
G01X756600Y461500D02*
Y466500D01*
G01X760783Y464833D02*
Y462500D01*
X761117Y461917D01*
X761617Y461583D01*
X762200Y461500D01*
X762783Y461583D01*
X763283Y461917D01*
X763617Y462500D01*
G01Y461500D02*
Y464833D01*
G01X766633Y460250D02*
X767217Y459917D01*
X767883Y459833D01*
X768467Y459917D01*
X768967Y460333D01*
X769300Y460917D01*
Y464833D01*
G01Y464167D02*
X768967Y464500D01*
X768467Y464750D01*
X767883Y464833D01*
X767217Y464667D01*
X766800Y464333D01*
X766467Y463750D01*
X766300Y463167D01*
X766383Y462667D01*
X766717Y462083D01*
X767217Y461667D01*
X767883Y461500D01*
X768383Y461583D01*
X768967Y461917D01*
X769300Y462250D01*
G01X772233Y460250D02*
X772817Y459917D01*
X773483Y459833D01*
X774067Y459917D01*
X774567Y460333D01*
X774900Y460917D01*
Y464833D01*
G01Y464167D02*
X774567Y464500D01*
X774067Y464750D01*
X773483Y464833D01*
X772817Y464667D01*
X772400Y464333D01*
X772067Y463750D01*
X771900Y463167D01*
X771983Y462667D01*
X772317Y462083D01*
X772817Y461667D01*
X773483Y461500D01*
X773983Y461583D01*
X774567Y461917D01*
X774900Y462250D01*
G01X779000Y464833D02*
Y461500D01*
G01Y466167D02*
X778833Y466250D01*
Y466417D01*
X779000Y466500D01*
X779167Y466417D01*
Y466250D01*
X779000Y466167D01*
G01X783183Y461500D02*
Y464833D01*
G01Y464000D02*
X783517Y464417D01*
X784017Y464750D01*
X784683Y464833D01*
X785267Y464750D01*
X785767Y464417D01*
X786017Y463833D01*
Y461500D01*
G01X789033Y460250D02*
X789617Y459917D01*
X790283Y459833D01*
X790867Y459917D01*
X791367Y460333D01*
X791700Y460917D01*
Y464833D01*
G01Y464167D02*
X791367Y464500D01*
X790867Y464750D01*
X790283Y464833D01*
X789617Y464667D01*
X789200Y464333D01*
X788867Y463750D01*
X788700Y463167D01*
X788783Y462667D01*
X789117Y462083D01*
X789617Y461667D01*
X790283Y461500D01*
X790783Y461583D01*
X791367Y461917D01*
X791700Y462250D01*
G01X713000Y435500D02*
X1343000D01*
G01X713000Y450500D02*
X1343000D01*
G01X713000Y477500D02*
X1343000D01*
G01X723667Y443167D02*
X724000Y443417D01*
X724250Y443833D01*
X724417Y444417D01*
X724250Y444917D01*
X723917Y445250D01*
X723333Y445500D01*
X721083D01*
Y440500D01*
X723833D01*
X724417Y440833D01*
X724750Y441333D01*
X724917Y441917D01*
X724750Y442500D01*
X724250Y443000D01*
X723667Y443167D01*
X721083D01*
G01X727183Y443833D02*
Y441500D01*
X727517Y440917D01*
X728017Y440583D01*
X728600Y440500D01*
X729183Y440583D01*
X729683Y440917D01*
X730017Y441500D01*
G01Y440500D02*
Y443833D01*
G01X733033Y440500D02*
Y443833D01*
G01Y443167D02*
X733450Y443500D01*
X733867Y443750D01*
X734450Y443833D01*
X734867Y443750D01*
X735367Y443500D01*
G01X739800Y443833D02*
Y440500D01*
G01Y445167D02*
X739633Y445250D01*
Y445417D01*
X739800Y445500D01*
X739967Y445417D01*
Y445250D01*
X739800Y445167D01*
G01X744150Y442750D02*
X746817D01*
X746567Y443333D01*
X746150Y443667D01*
X745567Y443833D01*
X744983Y443750D01*
X744483Y443500D01*
X744150Y442917D01*
X743983Y442417D01*
Y441917D01*
X744150Y441417D01*
X744567Y440917D01*
X745067Y440583D01*
X745650Y440500D01*
X746233Y440667D01*
X746817Y441167D01*
G01X752500Y445500D02*
Y440500D01*
G01Y441250D02*
X752167Y440833D01*
X751667Y440583D01*
X751083Y440500D01*
X750417Y440667D01*
X749917Y441083D01*
X749583Y441583D01*
X749500Y442167D01*
X749583Y442750D01*
X749917Y443250D01*
X750417Y443667D01*
X751083Y443833D01*
X751667Y443750D01*
X752083Y443583D01*
X752500Y443250D01*
G01X760783Y440500D02*
Y445500D01*
G01Y443083D02*
X761200Y443500D01*
X761617Y443750D01*
X762283Y443833D01*
X762783Y443750D01*
X763367Y443417D01*
X763617Y442917D01*
Y440500D01*
G01X767800D02*
X767300Y440583D01*
X766800Y440917D01*
X766467Y441500D01*
X766300Y442167D01*
X766467Y442833D01*
X766800Y443417D01*
X767300Y443750D01*
X767800Y443833D01*
X768300Y443750D01*
X768800Y443417D01*
X769133Y442833D01*
X769217Y442167D01*
X769133Y441500D01*
X768800Y440917D01*
X768300Y440583D01*
X767800Y440500D01*
G01X773400D02*
Y445500D01*
G01X777750Y442750D02*
X780417D01*
X780167Y443333D01*
X779750Y443667D01*
X779167Y443833D01*
X778583Y443750D01*
X778083Y443500D01*
X777750Y442917D01*
X777583Y442417D01*
Y441917D01*
X777750Y441417D01*
X778167Y440917D01*
X778667Y440583D01*
X779250Y440500D01*
X779833Y440667D01*
X780417Y441167D01*
G01X721417Y461500D02*
Y466500D01*
X724583D01*
G01X723417Y464083D02*
X721417D01*
G01X727183Y464833D02*
Y462500D01*
X727517Y461917D01*
X728017Y461583D01*
X728600Y461500D01*
X729183Y461583D01*
X729683Y461917D01*
X730017Y462500D01*
G01Y461500D02*
Y464833D01*
G01X734200Y461500D02*
Y466500D01*
G01X739800Y461500D02*
Y466500D01*
G01X749500Y459833D02*
Y464833D01*
G01Y464083D02*
X749917Y464500D01*
X750333Y464750D01*
X751000Y464833D01*
X751583Y464750D01*
X752167Y464333D01*
X752417Y463750D01*
X752500Y463167D01*
X752417Y462583D01*
X752167Y462000D01*
X751667Y461667D01*
X751000Y461500D01*
X750417Y461583D01*
X749833Y461833D01*
X749500Y462167D01*
G01X756600Y461500D02*
Y466500D01*
G01X760783Y464833D02*
Y462500D01*
X761117Y461917D01*
X761617Y461583D01*
X762200Y461500D01*
X762783Y461583D01*
X763283Y461917D01*
X763617Y462500D01*
G01Y461500D02*
Y464833D01*
G01X766633Y460250D02*
X767217Y459917D01*
X767883Y459833D01*
X768467Y459917D01*
X768967Y460333D01*
X769300Y460917D01*
Y464833D01*
G01Y464167D02*
X768967Y464500D01*
X768467Y464750D01*
X767883Y464833D01*
X767217Y464667D01*
X766800Y464333D01*
X766467Y463750D01*
X766300Y463167D01*
X766383Y462667D01*
X766717Y462083D01*
X767217Y461667D01*
X767883Y461500D01*
X768383Y461583D01*
X768967Y461917D01*
X769300Y462250D01*
G01X772233Y460250D02*
X772817Y459917D01*
X773483Y459833D01*
X774067Y459917D01*
X774567Y460333D01*
X774900Y460917D01*
Y464833D01*
G01Y464167D02*
X774567Y464500D01*
X774067Y464750D01*
X773483Y464833D01*
X772817Y464667D01*
X772400Y464333D01*
X772067Y463750D01*
X771900Y463167D01*
X771983Y462667D01*
X772317Y462083D01*
X772817Y461667D01*
X773483Y461500D01*
X773983Y461583D01*
X774567Y461917D01*
X774900Y462250D01*
G01X779000Y464833D02*
Y461500D01*
G01Y466167D02*
X778833Y466250D01*
Y466417D01*
X779000Y466500D01*
X779167Y466417D01*
Y466250D01*
X779000Y466167D01*
G01X783183Y461500D02*
Y464833D01*
G01Y464000D02*
X783517Y464417D01*
X784017Y464750D01*
X784683Y464833D01*
X785267Y464750D01*
X785767Y464417D01*
X786017Y463833D01*
Y461500D01*
G01X789033Y460250D02*
X789617Y459917D01*
X790283Y459833D01*
X790867Y459917D01*
X791367Y460333D01*
X791700Y460917D01*
Y464833D01*
G01Y464167D02*
X791367Y464500D01*
X790867Y464750D01*
X790283Y464833D01*
X789617Y464667D01*
X789200Y464333D01*
X788867Y463750D01*
X788700Y463167D01*
X788783Y462667D01*
X789117Y462083D01*
X789617Y461667D01*
X790283Y461500D01*
X790783Y461583D01*
X791367Y461917D01*
X791700Y462250D01*
G01X713000Y435500D02*
X1343000D01*
G01X713000Y450500D02*
X1343000D01*
G01X713000Y477500D02*
X1343000D01*
G01X721250Y530000D02*
Y535000D01*
G01X724750D02*
Y530000D01*
G01Y532500D02*
X721250D01*
G01X730100Y530000D02*
Y533333D01*
G01Y532750D02*
X729767Y533083D01*
X729267Y533250D01*
X728683Y533333D01*
X728100Y533167D01*
X727600Y532833D01*
X727267Y532333D01*
X727100Y531667D01*
X727267Y531000D01*
X727600Y530500D01*
X728100Y530167D01*
X728683Y530000D01*
X729267Y530083D01*
X729767Y530333D01*
X730100Y530667D01*
G01X734200Y530000D02*
Y535000D01*
G01X739300Y530000D02*
Y534250D01*
X739467Y534667D01*
X739800Y534917D01*
X740300Y535000D01*
X740800Y534833D01*
X741050Y534417D01*
G01X740050Y533000D02*
X738383D01*
G01X749333Y530000D02*
Y535000D01*
X751333D01*
X752000Y534750D01*
X752500Y534167D01*
X752667Y533500D01*
X752500Y532833D01*
X752083Y532333D01*
X751333Y532083D01*
X749333D01*
G01X756600Y530000D02*
Y535000D01*
G01X760783Y533333D02*
Y531000D01*
X761117Y530417D01*
X761617Y530083D01*
X762200Y530000D01*
X762783Y530083D01*
X763283Y530417D01*
X763617Y531000D01*
G01Y530000D02*
Y533333D01*
G01X766633Y528750D02*
X767217Y528417D01*
X767883Y528333D01*
X768467Y528417D01*
X768967Y528833D01*
X769300Y529417D01*
Y533333D01*
G01Y532667D02*
X768967Y533000D01*
X768467Y533250D01*
X767883Y533333D01*
X767217Y533167D01*
X766800Y532833D01*
X766467Y532250D01*
X766300Y531667D01*
X766383Y531167D01*
X766717Y530583D01*
X767217Y530167D01*
X767883Y530000D01*
X768383Y530083D01*
X768967Y530417D01*
X769300Y530750D01*
G01X772233Y528750D02*
X772817Y528417D01*
X773483Y528333D01*
X774067Y528417D01*
X774567Y528833D01*
X774900Y529417D01*
Y533333D01*
G01Y532667D02*
X774567Y533000D01*
X774067Y533250D01*
X773483Y533333D01*
X772817Y533167D01*
X772400Y532833D01*
X772067Y532250D01*
X771900Y531667D01*
X771983Y531167D01*
X772317Y530583D01*
X772817Y530167D01*
X773483Y530000D01*
X773983Y530083D01*
X774567Y530417D01*
X774900Y530750D01*
G01X779000Y533333D02*
Y530000D01*
G01Y534667D02*
X778833Y534750D01*
Y534917D01*
X779000Y535000D01*
X779167Y534917D01*
Y534750D01*
X779000Y534667D01*
G01X783183Y530000D02*
Y533333D01*
G01Y532500D02*
X783517Y532917D01*
X784017Y533250D01*
X784683Y533333D01*
X785267Y533250D01*
X785767Y532917D01*
X786017Y532333D01*
Y530000D01*
G01X789033Y528750D02*
X789617Y528417D01*
X790283Y528333D01*
X790867Y528417D01*
X791367Y528833D01*
X791700Y529417D01*
Y533333D01*
G01Y532667D02*
X791367Y533000D01*
X790867Y533250D01*
X790283Y533333D01*
X789617Y533167D01*
X789200Y532833D01*
X788867Y532250D01*
X788700Y531667D01*
X788783Y531167D01*
X789117Y530583D01*
X789617Y530167D01*
X790283Y530000D01*
X790783Y530083D01*
X791367Y530417D01*
X791700Y530750D01*
G01X713000Y579500D02*
X1343000D01*
G01X721250Y530000D02*
Y535000D01*
G01X724750D02*
Y530000D01*
G01Y532500D02*
X721250D01*
G01X730100Y530000D02*
Y533333D01*
G01Y532750D02*
X729767Y533083D01*
X729267Y533250D01*
X728683Y533333D01*
X728100Y533167D01*
X727600Y532833D01*
X727267Y532333D01*
X727100Y531667D01*
X727267Y531000D01*
X727600Y530500D01*
X728100Y530167D01*
X728683Y530000D01*
X729267Y530083D01*
X729767Y530333D01*
X730100Y530667D01*
G01X734200Y530000D02*
Y535000D01*
G01X739300Y530000D02*
Y534250D01*
X739467Y534667D01*
X739800Y534917D01*
X740300Y535000D01*
X740800Y534833D01*
X741050Y534417D01*
G01X740050Y533000D02*
X738383D01*
G01X749333Y530000D02*
Y535000D01*
X751333D01*
X752000Y534750D01*
X752500Y534167D01*
X752667Y533500D01*
X752500Y532833D01*
X752083Y532333D01*
X751333Y532083D01*
X749333D01*
G01X756600Y530000D02*
Y535000D01*
G01X760783Y533333D02*
Y531000D01*
X761117Y530417D01*
X761617Y530083D01*
X762200Y530000D01*
X762783Y530083D01*
X763283Y530417D01*
X763617Y531000D01*
G01Y530000D02*
Y533333D01*
G01X766633Y528750D02*
X767217Y528417D01*
X767883Y528333D01*
X768467Y528417D01*
X768967Y528833D01*
X769300Y529417D01*
Y533333D01*
G01Y532667D02*
X768967Y533000D01*
X768467Y533250D01*
X767883Y533333D01*
X767217Y533167D01*
X766800Y532833D01*
X766467Y532250D01*
X766300Y531667D01*
X766383Y531167D01*
X766717Y530583D01*
X767217Y530167D01*
X767883Y530000D01*
X768383Y530083D01*
X768967Y530417D01*
X769300Y530750D01*
G01X772233Y528750D02*
X772817Y528417D01*
X773483Y528333D01*
X774067Y528417D01*
X774567Y528833D01*
X774900Y529417D01*
Y533333D01*
G01Y532667D02*
X774567Y533000D01*
X774067Y533250D01*
X773483Y533333D01*
X772817Y533167D01*
X772400Y532833D01*
X772067Y532250D01*
X771900Y531667D01*
X771983Y531167D01*
X772317Y530583D01*
X772817Y530167D01*
X773483Y530000D01*
X773983Y530083D01*
X774567Y530417D01*
X774900Y530750D01*
G01X779000Y533333D02*
Y530000D01*
G01Y534667D02*
X778833Y534750D01*
Y534917D01*
X779000Y535000D01*
X779167Y534917D01*
Y534750D01*
X779000Y534667D01*
G01X783183Y530000D02*
Y533333D01*
G01Y532500D02*
X783517Y532917D01*
X784017Y533250D01*
X784683Y533333D01*
X785267Y533250D01*
X785767Y532917D01*
X786017Y532333D01*
Y530000D01*
G01X789033Y528750D02*
X789617Y528417D01*
X790283Y528333D01*
X790867Y528417D01*
X791367Y528833D01*
X791700Y529417D01*
Y533333D01*
G01Y532667D02*
X791367Y533000D01*
X790867Y533250D01*
X790283Y533333D01*
X789617Y533167D01*
X789200Y532833D01*
X788867Y532250D01*
X788700Y531667D01*
X788783Y531167D01*
X789117Y530583D01*
X789617Y530167D01*
X790283Y530000D01*
X790783Y530083D01*
X791367Y530417D01*
X791700Y530750D01*
G01X713000Y579500D02*
X1343000D01*
G01X722833Y589000D02*
Y594000D01*
X724833D01*
X725500Y593750D01*
X726000Y593167D01*
X726167Y592500D01*
X726000Y591833D01*
X725583Y591333D01*
X724833Y591083D01*
X722833D01*
G01X730100Y589000D02*
Y594000D01*
G01X734283Y592333D02*
Y590000D01*
X734617Y589417D01*
X735117Y589083D01*
X735700Y589000D01*
X736283Y589083D01*
X736783Y589417D01*
X737117Y590000D01*
G01Y589000D02*
Y592333D01*
G01X740133Y587750D02*
X740717Y587417D01*
X741383Y587333D01*
X741967Y587417D01*
X742467Y587833D01*
X742800Y588417D01*
Y592333D01*
G01Y591667D02*
X742467Y592000D01*
X741967Y592250D01*
X741383Y592333D01*
X740717Y592167D01*
X740300Y591833D01*
X739967Y591250D01*
X739800Y590667D01*
X739883Y590167D01*
X740217Y589583D01*
X740717Y589167D01*
X741383Y589000D01*
X741883Y589083D01*
X742467Y589417D01*
X742800Y589750D01*
G01X745733Y587750D02*
X746317Y587417D01*
X746983Y587333D01*
X747567Y587417D01*
X748067Y587833D01*
X748400Y588417D01*
Y592333D01*
G01Y591667D02*
X748067Y592000D01*
X747567Y592250D01*
X746983Y592333D01*
X746317Y592167D01*
X745900Y591833D01*
X745567Y591250D01*
X745400Y590667D01*
X745483Y590167D01*
X745817Y589583D01*
X746317Y589167D01*
X746983Y589000D01*
X747483Y589083D01*
X748067Y589417D01*
X748400Y589750D01*
G01X752500Y592333D02*
Y589000D01*
G01Y593667D02*
X752333Y593750D01*
Y593917D01*
X752500Y594000D01*
X752667Y593917D01*
Y593750D01*
X752500Y593667D01*
G01X756683Y589000D02*
Y592333D01*
G01Y591500D02*
X757017Y591917D01*
X757517Y592250D01*
X758183Y592333D01*
X758767Y592250D01*
X759267Y591917D01*
X759517Y591333D01*
Y589000D01*
G01X762533Y587750D02*
X763117Y587417D01*
X763783Y587333D01*
X764367Y587417D01*
X764867Y587833D01*
X765200Y588417D01*
Y592333D01*
G01Y591667D02*
X764867Y592000D01*
X764367Y592250D01*
X763783Y592333D01*
X763117Y592167D01*
X762700Y591833D01*
X762367Y591250D01*
X762200Y590667D01*
X762283Y590167D01*
X762617Y589583D01*
X763117Y589167D01*
X763783Y589000D01*
X764283Y589083D01*
X764867Y589417D01*
X765200Y589750D01*
G01X776400Y594000D02*
Y589000D01*
G01Y589750D02*
X776067Y589333D01*
X775567Y589083D01*
X774983Y589000D01*
X774317Y589167D01*
X773817Y589583D01*
X773483Y590083D01*
X773400Y590667D01*
X773483Y591250D01*
X773817Y591750D01*
X774317Y592167D01*
X774983Y592333D01*
X775567Y592250D01*
X775983Y592083D01*
X776400Y591750D01*
G01X779250Y591250D02*
X781917D01*
X781667Y591833D01*
X781250Y592167D01*
X780667Y592333D01*
X780083Y592250D01*
X779583Y592000D01*
X779250Y591417D01*
X779083Y590917D01*
Y590417D01*
X779250Y589917D01*
X779667Y589417D01*
X780167Y589083D01*
X780750Y589000D01*
X781333Y589167D01*
X781917Y589667D01*
G01X785600Y589000D02*
Y593250D01*
X785767Y593667D01*
X786100Y593917D01*
X786600Y594000D01*
X787100Y593833D01*
X787350Y593417D01*
G01X786350Y592000D02*
X784683D01*
G01X791700Y592333D02*
Y589000D01*
G01Y593667D02*
X791533Y593750D01*
Y593917D01*
X791700Y594000D01*
X791867Y593917D01*
Y593750D01*
X791700Y593667D01*
G01X795883Y589000D02*
Y592333D01*
G01Y591500D02*
X796217Y591917D01*
X796717Y592250D01*
X797383Y592333D01*
X797967Y592250D01*
X798467Y591917D01*
X798717Y591333D01*
Y589000D01*
G01X801650Y591250D02*
X804317D01*
X804067Y591833D01*
X803650Y592167D01*
X803067Y592333D01*
X802483Y592250D01*
X801983Y592000D01*
X801650Y591417D01*
X801483Y590917D01*
Y590417D01*
X801650Y589917D01*
X802067Y589417D01*
X802567Y589083D01*
X803150Y589000D01*
X803733Y589167D01*
X804317Y589667D01*
G01X713000Y604500D02*
X1343000D01*
G01X722833Y589000D02*
Y594000D01*
X724833D01*
X725500Y593750D01*
X726000Y593167D01*
X726167Y592500D01*
X726000Y591833D01*
X725583Y591333D01*
X724833Y591083D01*
X722833D01*
G01X730100Y589000D02*
Y594000D01*
G01X734283Y592333D02*
Y590000D01*
X734617Y589417D01*
X735117Y589083D01*
X735700Y589000D01*
X736283Y589083D01*
X736783Y589417D01*
X737117Y590000D01*
G01Y589000D02*
Y592333D01*
G01X740133Y587750D02*
X740717Y587417D01*
X741383Y587333D01*
X741967Y587417D01*
X742467Y587833D01*
X742800Y588417D01*
Y592333D01*
G01Y591667D02*
X742467Y592000D01*
X741967Y592250D01*
X741383Y592333D01*
X740717Y592167D01*
X740300Y591833D01*
X739967Y591250D01*
X739800Y590667D01*
X739883Y590167D01*
X740217Y589583D01*
X740717Y589167D01*
X741383Y589000D01*
X741883Y589083D01*
X742467Y589417D01*
X742800Y589750D01*
G01X745733Y587750D02*
X746317Y587417D01*
X746983Y587333D01*
X747567Y587417D01*
X748067Y587833D01*
X748400Y588417D01*
Y592333D01*
G01Y591667D02*
X748067Y592000D01*
X747567Y592250D01*
X746983Y592333D01*
X746317Y592167D01*
X745900Y591833D01*
X745567Y591250D01*
X745400Y590667D01*
X745483Y590167D01*
X745817Y589583D01*
X746317Y589167D01*
X746983Y589000D01*
X747483Y589083D01*
X748067Y589417D01*
X748400Y589750D01*
G01X752500Y592333D02*
Y589000D01*
G01Y593667D02*
X752333Y593750D01*
Y593917D01*
X752500Y594000D01*
X752667Y593917D01*
Y593750D01*
X752500Y593667D01*
G01X756683Y589000D02*
Y592333D01*
G01Y591500D02*
X757017Y591917D01*
X757517Y592250D01*
X758183Y592333D01*
X758767Y592250D01*
X759267Y591917D01*
X759517Y591333D01*
Y589000D01*
G01X762533Y587750D02*
X763117Y587417D01*
X763783Y587333D01*
X764367Y587417D01*
X764867Y587833D01*
X765200Y588417D01*
Y592333D01*
G01Y591667D02*
X764867Y592000D01*
X764367Y592250D01*
X763783Y592333D01*
X763117Y592167D01*
X762700Y591833D01*
X762367Y591250D01*
X762200Y590667D01*
X762283Y590167D01*
X762617Y589583D01*
X763117Y589167D01*
X763783Y589000D01*
X764283Y589083D01*
X764867Y589417D01*
X765200Y589750D01*
G01X776400Y594000D02*
Y589000D01*
G01Y589750D02*
X776067Y589333D01*
X775567Y589083D01*
X774983Y589000D01*
X774317Y589167D01*
X773817Y589583D01*
X773483Y590083D01*
X773400Y590667D01*
X773483Y591250D01*
X773817Y591750D01*
X774317Y592167D01*
X774983Y592333D01*
X775567Y592250D01*
X775983Y592083D01*
X776400Y591750D01*
G01X779250Y591250D02*
X781917D01*
X781667Y591833D01*
X781250Y592167D01*
X780667Y592333D01*
X780083Y592250D01*
X779583Y592000D01*
X779250Y591417D01*
X779083Y590917D01*
Y590417D01*
X779250Y589917D01*
X779667Y589417D01*
X780167Y589083D01*
X780750Y589000D01*
X781333Y589167D01*
X781917Y589667D01*
G01X785600Y589000D02*
Y593250D01*
X785767Y593667D01*
X786100Y593917D01*
X786600Y594000D01*
X787100Y593833D01*
X787350Y593417D01*
G01X786350Y592000D02*
X784683D01*
G01X791700Y592333D02*
Y589000D01*
G01Y593667D02*
X791533Y593750D01*
Y593917D01*
X791700Y594000D01*
X791867Y593917D01*
Y593750D01*
X791700Y593667D01*
G01X795883Y589000D02*
Y592333D01*
G01Y591500D02*
X796217Y591917D01*
X796717Y592250D01*
X797383Y592333D01*
X797967Y592250D01*
X798467Y591917D01*
X798717Y591333D01*
Y589000D01*
G01X801650Y591250D02*
X804317D01*
X804067Y591833D01*
X803650Y592167D01*
X803067Y592333D01*
X802483Y592250D01*
X801983Y592000D01*
X801650Y591417D01*
X801483Y590917D01*
Y590417D01*
X801650Y589917D01*
X802067Y589417D01*
X802567Y589083D01*
X803150Y589000D01*
X803733Y589167D01*
X804317Y589667D01*
G01X713000Y604500D02*
X1343000D01*
G01X722667Y765000D02*
X723167Y764417D01*
X723833Y764083D01*
X724583Y764000D01*
X725250Y764083D01*
X725917Y764500D01*
X726333Y765000D01*
X726417Y765500D01*
X726250Y766083D01*
X725667Y766500D01*
X725083Y766667D01*
X724333D01*
G01X725083D02*
X725583Y766917D01*
X726000Y767333D01*
X726167Y767833D01*
X726000Y768333D01*
X725583Y768750D01*
X724833Y769000D01*
X724083Y768917D01*
X723333Y768583D01*
G01X730100Y763833D02*
X729933Y763917D01*
Y764083D01*
X730100Y764167D01*
X730267Y764083D01*
Y763917D01*
X730100Y763833D01*
G01X739633Y764000D02*
Y769000D01*
X741633D01*
X742300Y768750D01*
X742800Y768167D01*
X742967Y767500D01*
X742800Y766833D01*
X742383Y766333D01*
X741633Y766083D01*
X739633D01*
G01X746900Y764000D02*
Y769000D01*
G01X751083Y767333D02*
Y765000D01*
X751417Y764417D01*
X751917Y764083D01*
X752500Y764000D01*
X753083Y764083D01*
X753583Y764417D01*
X753917Y765000D01*
G01Y764000D02*
Y767333D01*
G01X756933Y762750D02*
X757517Y762417D01*
X758183Y762333D01*
X758767Y762417D01*
X759267Y762833D01*
X759600Y763417D01*
Y767333D01*
G01Y766667D02*
X759267Y767000D01*
X758767Y767250D01*
X758183Y767333D01*
X757517Y767167D01*
X757100Y766833D01*
X756767Y766250D01*
X756600Y765667D01*
X756683Y765167D01*
X757017Y764583D01*
X757517Y764167D01*
X758183Y764000D01*
X758683Y764083D01*
X759267Y764417D01*
X759600Y764750D01*
G01X767800Y767333D02*
X769300Y764000D01*
X770800Y767333D01*
G01X774900D02*
Y764000D01*
G01Y768667D02*
X774733Y768750D01*
Y768917D01*
X774900Y769000D01*
X775067Y768917D01*
Y768750D01*
X774900Y768667D01*
G01X782000Y764000D02*
Y767333D01*
G01Y766750D02*
X781667Y767083D01*
X781167Y767250D01*
X780583Y767333D01*
X780000Y767167D01*
X779500Y766833D01*
X779167Y766333D01*
X779000Y765667D01*
X779167Y765000D01*
X779500Y764500D01*
X780000Y764167D01*
X780583Y764000D01*
X781167Y764083D01*
X781667Y764333D01*
X782000Y764667D01*
G01X790200Y763833D02*
X793200Y769000D01*
G01X795217D02*
X797300Y764000D01*
X799383Y769000D01*
G01X802900Y764000D02*
X802233Y764083D01*
X801650Y764417D01*
X801150Y764917D01*
X800817Y765500D01*
X800650Y766167D01*
Y766833D01*
X800817Y767500D01*
X801150Y768083D01*
X801650Y768583D01*
X802233Y768917D01*
X802900Y769000D01*
X803567Y768917D01*
X804150Y768583D01*
X804650Y768083D01*
X804983Y767500D01*
X805150Y766833D01*
Y766167D01*
X804983Y765500D01*
X804650Y764917D01*
X804150Y764417D01*
X803567Y764083D01*
X802900Y764000D01*
G01X806833D02*
Y769000D01*
X808833D01*
X809500Y768750D01*
X810000Y768167D01*
X810167Y767500D01*
X810000Y766833D01*
X809583Y766333D01*
X808833Y766083D01*
X806833D01*
G01X812600Y763833D02*
X815600Y769000D01*
G01X817617D02*
X819700Y764000D01*
X821783Y769000D01*
G01X824300D02*
X826300D01*
G01X825300D02*
Y764000D01*
G01X824300D02*
X826300D01*
G01X829233D02*
Y769000D01*
X831233D01*
X831900Y768750D01*
X832400Y768167D01*
X832567Y767500D01*
X832400Y766833D01*
X831983Y766333D01*
X831233Y766083D01*
X829233D01*
G01X836500Y763833D02*
X836333Y763917D01*
Y764083D01*
X836500Y764167D01*
X836667Y764083D01*
Y763917D01*
X836500Y763833D01*
G01Y766083D02*
X836333Y766167D01*
Y766333D01*
X836500Y766417D01*
X836667Y766333D01*
Y766167D01*
X836500Y766083D01*
G01X724813Y813000D02*
Y818000D01*
X726897D01*
X727563Y817750D01*
X727980Y817417D01*
X728147Y816750D01*
X727980Y816083D01*
X727480Y815667D01*
X726897Y815417D01*
X724813D01*
G01X726897D02*
X728147Y813000D01*
G01X732080D02*
X731580Y813083D01*
X731080Y813417D01*
X730747Y814000D01*
X730580Y814667D01*
X730747Y815333D01*
X731080Y815917D01*
X731580Y816250D01*
X732080Y816333D01*
X732580Y816250D01*
X733080Y815917D01*
X733413Y815333D01*
X733497Y814667D01*
X733413Y814000D01*
X733080Y813417D01*
X732580Y813083D01*
X732080Y813000D01*
G01X736263Y816333D02*
Y814000D01*
X736597Y813417D01*
X737097Y813083D01*
X737680Y813000D01*
X738263Y813083D01*
X738763Y813417D01*
X739097Y814000D01*
G01Y813000D02*
Y816333D01*
G01X743280Y818000D02*
Y813000D01*
G01X742113Y816333D02*
X744447D01*
G01X748880D02*
Y813000D01*
G01Y817667D02*
X748713Y817750D01*
Y817917D01*
X748880Y818000D01*
X749047Y817917D01*
Y817750D01*
X748880Y817667D01*
G01X753063Y813000D02*
Y816333D01*
G01Y815500D02*
X753397Y815917D01*
X753897Y816250D01*
X754563Y816333D01*
X755147Y816250D01*
X755647Y815917D01*
X755897Y815333D01*
Y813000D01*
G01X758913Y811750D02*
X759497Y811417D01*
X760163Y811333D01*
X760747Y811417D01*
X761247Y811833D01*
X761580Y812417D01*
Y816333D01*
G01Y815667D02*
X761247Y816000D01*
X760747Y816250D01*
X760163Y816333D01*
X759497Y816167D01*
X759080Y815833D01*
X758747Y815250D01*
X758580Y814667D01*
X758663Y814167D01*
X758997Y813583D01*
X759497Y813167D01*
X760163Y813000D01*
X760663Y813083D01*
X761247Y813417D01*
X761580Y813750D01*
G01X713000Y752000D02*
X1344500D01*
G01X722667Y765000D02*
X723167Y764417D01*
X723833Y764083D01*
X724583Y764000D01*
X725250Y764083D01*
X725917Y764500D01*
X726333Y765000D01*
X726417Y765500D01*
X726250Y766083D01*
X725667Y766500D01*
X725083Y766667D01*
X724333D01*
G01X725083D02*
X725583Y766917D01*
X726000Y767333D01*
X726167Y767833D01*
X726000Y768333D01*
X725583Y768750D01*
X724833Y769000D01*
X724083Y768917D01*
X723333Y768583D01*
G01X730100Y763833D02*
X729933Y763917D01*
Y764083D01*
X730100Y764167D01*
X730267Y764083D01*
Y763917D01*
X730100Y763833D01*
G01X739633Y764000D02*
Y769000D01*
X741633D01*
X742300Y768750D01*
X742800Y768167D01*
X742967Y767500D01*
X742800Y766833D01*
X742383Y766333D01*
X741633Y766083D01*
X739633D01*
G01X746900Y764000D02*
Y769000D01*
G01X751083Y767333D02*
Y765000D01*
X751417Y764417D01*
X751917Y764083D01*
X752500Y764000D01*
X753083Y764083D01*
X753583Y764417D01*
X753917Y765000D01*
G01Y764000D02*
Y767333D01*
G01X756933Y762750D02*
X757517Y762417D01*
X758183Y762333D01*
X758767Y762417D01*
X759267Y762833D01*
X759600Y763417D01*
Y767333D01*
G01Y766667D02*
X759267Y767000D01*
X758767Y767250D01*
X758183Y767333D01*
X757517Y767167D01*
X757100Y766833D01*
X756767Y766250D01*
X756600Y765667D01*
X756683Y765167D01*
X757017Y764583D01*
X757517Y764167D01*
X758183Y764000D01*
X758683Y764083D01*
X759267Y764417D01*
X759600Y764750D01*
G01X767800Y767333D02*
X769300Y764000D01*
X770800Y767333D01*
G01X774900D02*
Y764000D01*
G01Y768667D02*
X774733Y768750D01*
Y768917D01*
X774900Y769000D01*
X775067Y768917D01*
Y768750D01*
X774900Y768667D01*
G01X782000Y764000D02*
Y767333D01*
G01Y766750D02*
X781667Y767083D01*
X781167Y767250D01*
X780583Y767333D01*
X780000Y767167D01*
X779500Y766833D01*
X779167Y766333D01*
X779000Y765667D01*
X779167Y765000D01*
X779500Y764500D01*
X780000Y764167D01*
X780583Y764000D01*
X781167Y764083D01*
X781667Y764333D01*
X782000Y764667D01*
G01X790200Y763833D02*
X793200Y769000D01*
G01X795217D02*
X797300Y764000D01*
X799383Y769000D01*
G01X802900Y764000D02*
X802233Y764083D01*
X801650Y764417D01*
X801150Y764917D01*
X800817Y765500D01*
X800650Y766167D01*
Y766833D01*
X800817Y767500D01*
X801150Y768083D01*
X801650Y768583D01*
X802233Y768917D01*
X802900Y769000D01*
X803567Y768917D01*
X804150Y768583D01*
X804650Y768083D01*
X804983Y767500D01*
X805150Y766833D01*
Y766167D01*
X804983Y765500D01*
X804650Y764917D01*
X804150Y764417D01*
X803567Y764083D01*
X802900Y764000D01*
G01X806833D02*
Y769000D01*
X808833D01*
X809500Y768750D01*
X810000Y768167D01*
X810167Y767500D01*
X810000Y766833D01*
X809583Y766333D01*
X808833Y766083D01*
X806833D01*
G01X812600Y763833D02*
X815600Y769000D01*
G01X817617D02*
X819700Y764000D01*
X821783Y769000D01*
G01X824300D02*
X826300D01*
G01X825300D02*
Y764000D01*
G01X824300D02*
X826300D01*
G01X829233D02*
Y769000D01*
X831233D01*
X831900Y768750D01*
X832400Y768167D01*
X832567Y767500D01*
X832400Y766833D01*
X831983Y766333D01*
X831233Y766083D01*
X829233D01*
G01X836500Y763833D02*
X836333Y763917D01*
Y764083D01*
X836500Y764167D01*
X836667Y764083D01*
Y763917D01*
X836500Y763833D01*
G01Y766083D02*
X836333Y766167D01*
Y766333D01*
X836500Y766417D01*
X836667Y766333D01*
Y766167D01*
X836500Y766083D01*
G01X724813Y813000D02*
Y818000D01*
X726897D01*
X727563Y817750D01*
X727980Y817417D01*
X728147Y816750D01*
X727980Y816083D01*
X727480Y815667D01*
X726897Y815417D01*
X724813D01*
G01X726897D02*
X728147Y813000D01*
G01X732080D02*
X731580Y813083D01*
X731080Y813417D01*
X730747Y814000D01*
X730580Y814667D01*
X730747Y815333D01*
X731080Y815917D01*
X731580Y816250D01*
X732080Y816333D01*
X732580Y816250D01*
X733080Y815917D01*
X733413Y815333D01*
X733497Y814667D01*
X733413Y814000D01*
X733080Y813417D01*
X732580Y813083D01*
X732080Y813000D01*
G01X736263Y816333D02*
Y814000D01*
X736597Y813417D01*
X737097Y813083D01*
X737680Y813000D01*
X738263Y813083D01*
X738763Y813417D01*
X739097Y814000D01*
G01Y813000D02*
Y816333D01*
G01X743280Y818000D02*
Y813000D01*
G01X742113Y816333D02*
X744447D01*
G01X748880D02*
Y813000D01*
G01Y817667D02*
X748713Y817750D01*
Y817917D01*
X748880Y818000D01*
X749047Y817917D01*
Y817750D01*
X748880Y817667D01*
G01X753063Y813000D02*
Y816333D01*
G01Y815500D02*
X753397Y815917D01*
X753897Y816250D01*
X754563Y816333D01*
X755147Y816250D01*
X755647Y815917D01*
X755897Y815333D01*
Y813000D01*
G01X758913Y811750D02*
X759497Y811417D01*
X760163Y811333D01*
X760747Y811417D01*
X761247Y811833D01*
X761580Y812417D01*
Y816333D01*
G01Y815667D02*
X761247Y816000D01*
X760747Y816250D01*
X760163Y816333D01*
X759497Y816167D01*
X759080Y815833D01*
X758747Y815250D01*
X758580Y814667D01*
X758663Y814167D01*
X758997Y813583D01*
X759497Y813167D01*
X760163Y813000D01*
X760663Y813083D01*
X761247Y813417D01*
X761580Y813750D01*
G01X713000Y752000D02*
X1344500D01*
G01X712980Y850500D02*
X1343000D01*
G01X712980D02*
X1343000D01*
G01X802167Y-15500D02*
Y-10500D01*
X803833D01*
X804500Y-10750D01*
X805000Y-11083D01*
X805417Y-11583D01*
X805750Y-12167D01*
X805833Y-13000D01*
X805750Y-13833D01*
X805417Y-14417D01*
X805000Y-14917D01*
X804500Y-15250D01*
X803833Y-15500D01*
X802167D01*
G01X809600D02*
Y-10500D01*
X808600Y-11500D01*
G01Y-15500D02*
X810600D01*
G01X813617Y-13417D02*
X814200Y-12833D01*
X814700Y-12500D01*
X815367Y-12333D01*
X815950Y-12500D01*
X816367Y-12833D01*
X816700Y-13333D01*
X816783Y-13917D01*
X816700Y-14417D01*
X816367Y-14917D01*
X815867Y-15333D01*
X815283Y-15500D01*
X814617Y-15333D01*
X814033Y-14833D01*
X813700Y-14083D01*
X813617Y-13250D01*
X813783Y-12167D01*
X814033Y-11583D01*
X814450Y-11000D01*
X815033Y-10583D01*
X815617Y-10500D01*
X816200Y-10667D01*
X816617Y-11083D01*
G01X802167Y-15500D02*
Y-10500D01*
X803833D01*
X804500Y-10750D01*
X805000Y-11083D01*
X805417Y-11583D01*
X805750Y-12167D01*
X805833Y-13000D01*
X805750Y-13833D01*
X805417Y-14417D01*
X805000Y-14917D01*
X804500Y-15250D01*
X803833Y-15500D01*
X802167D01*
G01X809600D02*
Y-10500D01*
X808600Y-11500D01*
G01Y-15500D02*
X810600D01*
G01X813617Y-13417D02*
X814200Y-12833D01*
X814700Y-12500D01*
X815367Y-12333D01*
X815950Y-12500D01*
X816367Y-12833D01*
X816700Y-13333D01*
X816783Y-13917D01*
X816700Y-14417D01*
X816367Y-14917D01*
X815867Y-15333D01*
X815283Y-15500D01*
X814617Y-15333D01*
X814033Y-14833D01*
X813700Y-14083D01*
X813617Y-13250D01*
X813783Y-12167D01*
X814033Y-11583D01*
X814450Y-11000D01*
X815033Y-10583D01*
X815617Y-10500D01*
X816200Y-10667D01*
X816617Y-11083D01*
G01X777583Y104700D02*
Y99700D01*
X780917D01*
G01X783600Y103033D02*
X786100Y99700D01*
G01Y103033D02*
X783600Y99700D01*
G01X790450Y99533D02*
X790283Y99617D01*
Y99783D01*
X790450Y99867D01*
X790617Y99783D01*
Y99617D01*
X790450Y99533D01*
G01Y101783D02*
X790283Y101867D01*
Y102033D01*
X790450Y102117D01*
X790617Y102033D01*
Y101867D01*
X790450Y101783D01*
G01X799150Y99700D02*
Y103033D01*
G01Y102117D02*
X799400Y102533D01*
X799817Y102867D01*
X800400Y103033D01*
X800983Y102867D01*
X801400Y102533D01*
X801650Y102117D01*
Y99700D01*
G01Y102117D02*
X801900Y102533D01*
X802317Y102867D01*
X802900Y103033D01*
X803483Y102867D01*
X803900Y102533D01*
X804150Y102033D01*
Y99700D01*
G01X805833Y103033D02*
Y100700D01*
X806167Y100117D01*
X806667Y99783D01*
X807250Y99700D01*
X807833Y99783D01*
X808333Y100117D01*
X808667Y100700D01*
G01Y99700D02*
Y103033D01*
G01X811600Y100283D02*
X812017Y99950D01*
X812600Y99700D01*
X813100D01*
X813600Y99867D01*
X813933Y100117D01*
X814100Y100450D01*
X814017Y100950D01*
X813683Y101200D01*
X812183Y101700D01*
X811850Y102283D01*
X812017Y102700D01*
X812350Y102950D01*
X812850Y103033D01*
X813350Y102950D01*
X813850Y102700D01*
G01X818450Y104700D02*
Y99700D01*
G01X817283Y103033D02*
X819617D01*
G01X828150Y99700D02*
Y104700D01*
G01Y102200D02*
X828567Y102700D01*
X829067Y102950D01*
X829567Y103033D01*
X830317Y102867D01*
X830817Y102533D01*
X831150Y101950D01*
Y101283D01*
X830983Y100617D01*
X830650Y100117D01*
X830067Y99783D01*
X829567Y99700D01*
X829067Y99783D01*
X828567Y100033D01*
X828150Y100450D01*
G01X834000Y101950D02*
X836667D01*
X836417Y102533D01*
X836000Y102867D01*
X835417Y103033D01*
X834833Y102950D01*
X834333Y102700D01*
X834000Y102117D01*
X833833Y101617D01*
Y101117D01*
X834000Y100617D01*
X834417Y100117D01*
X834917Y99783D01*
X835500Y99700D01*
X836083Y99867D01*
X836667Y100367D01*
G01X844950Y99700D02*
Y104700D01*
G01Y102200D02*
X845367Y102700D01*
X845867Y102950D01*
X846367Y103033D01*
X847117Y102867D01*
X847617Y102533D01*
X847950Y101950D01*
Y101283D01*
X847783Y100617D01*
X847450Y100117D01*
X846867Y99783D01*
X846367Y99700D01*
X845867Y99783D01*
X845367Y100033D01*
X844950Y100450D01*
G01X850883Y99700D02*
Y103033D01*
G01Y102367D02*
X851300Y102700D01*
X851717Y102950D01*
X852300Y103033D01*
X852717Y102950D01*
X853217Y102700D01*
G01X857650Y99700D02*
X857150Y99783D01*
X856650Y100117D01*
X856317Y100700D01*
X856150Y101367D01*
X856317Y102033D01*
X856650Y102617D01*
X857150Y102950D01*
X857650Y103033D01*
X858150Y102950D01*
X858650Y102617D01*
X858983Y102033D01*
X859067Y101367D01*
X858983Y100700D01*
X858650Y100117D01*
X858150Y99783D01*
X857650Y99700D01*
G01X861833D02*
Y104700D01*
G01X864500Y103033D02*
X861833Y101117D01*
G01X862917Y101867D02*
X864667Y99700D01*
G01X867600Y101950D02*
X870267D01*
X870017Y102533D01*
X869600Y102867D01*
X869017Y103033D01*
X868433Y102950D01*
X867933Y102700D01*
X867600Y102117D01*
X867433Y101617D01*
Y101117D01*
X867600Y100617D01*
X868017Y100117D01*
X868517Y99783D01*
X869100Y99700D01*
X869683Y99867D01*
X870267Y100367D01*
G01X873033Y99700D02*
Y103033D01*
G01Y102200D02*
X873367Y102617D01*
X873867Y102950D01*
X874533Y103033D01*
X875117Y102950D01*
X875617Y102617D01*
X875867Y102033D01*
Y99700D01*
G01X885650D02*
Y104700D01*
G01X892750Y99700D02*
Y103033D01*
G01Y102450D02*
X892417Y102783D01*
X891917Y102950D01*
X891333Y103033D01*
X890750Y102867D01*
X890250Y102533D01*
X889917Y102033D01*
X889750Y101367D01*
X889917Y100700D01*
X890250Y100200D01*
X890750Y99867D01*
X891333Y99700D01*
X891917Y99783D01*
X892417Y100033D01*
X892750Y100367D01*
G01X895100Y98200D02*
X895600Y98033D01*
X896267Y98200D01*
X896683Y98533D01*
X897017Y98950D01*
X897517Y100283D01*
X898600Y103033D01*
G01X895933D02*
X897517Y100283D01*
G01X901200Y101950D02*
X903867D01*
X903617Y102533D01*
X903200Y102867D01*
X902617Y103033D01*
X902033Y102950D01*
X901533Y102700D01*
X901200Y102117D01*
X901033Y101617D01*
Y101117D01*
X901200Y100617D01*
X901617Y100117D01*
X902117Y99783D01*
X902700Y99700D01*
X903283Y99867D01*
X903867Y100367D01*
G01X906883Y99700D02*
Y103033D01*
G01Y102367D02*
X907300Y102700D01*
X907717Y102950D01*
X908300Y103033D01*
X908717Y102950D01*
X909217Y102700D01*
G01X777583Y104700D02*
Y99700D01*
X780917D01*
G01X783600Y103033D02*
X786100Y99700D01*
G01Y103033D02*
X783600Y99700D01*
G01X790450Y99533D02*
X790283Y99617D01*
Y99783D01*
X790450Y99867D01*
X790617Y99783D01*
Y99617D01*
X790450Y99533D01*
G01Y101783D02*
X790283Y101867D01*
Y102033D01*
X790450Y102117D01*
X790617Y102033D01*
Y101867D01*
X790450Y101783D01*
G01X799150Y99700D02*
Y103033D01*
G01Y102117D02*
X799400Y102533D01*
X799817Y102867D01*
X800400Y103033D01*
X800983Y102867D01*
X801400Y102533D01*
X801650Y102117D01*
Y99700D01*
G01Y102117D02*
X801900Y102533D01*
X802317Y102867D01*
X802900Y103033D01*
X803483Y102867D01*
X803900Y102533D01*
X804150Y102033D01*
Y99700D01*
G01X805833Y103033D02*
Y100700D01*
X806167Y100117D01*
X806667Y99783D01*
X807250Y99700D01*
X807833Y99783D01*
X808333Y100117D01*
X808667Y100700D01*
G01Y99700D02*
Y103033D01*
G01X811600Y100283D02*
X812017Y99950D01*
X812600Y99700D01*
X813100D01*
X813600Y99867D01*
X813933Y100117D01*
X814100Y100450D01*
X814017Y100950D01*
X813683Y101200D01*
X812183Y101700D01*
X811850Y102283D01*
X812017Y102700D01*
X812350Y102950D01*
X812850Y103033D01*
X813350Y102950D01*
X813850Y102700D01*
G01X818450Y104700D02*
Y99700D01*
G01X817283Y103033D02*
X819617D01*
G01X828150Y99700D02*
Y104700D01*
G01Y102200D02*
X828567Y102700D01*
X829067Y102950D01*
X829567Y103033D01*
X830317Y102867D01*
X830817Y102533D01*
X831150Y101950D01*
Y101283D01*
X830983Y100617D01*
X830650Y100117D01*
X830067Y99783D01*
X829567Y99700D01*
X829067Y99783D01*
X828567Y100033D01*
X828150Y100450D01*
G01X834000Y101950D02*
X836667D01*
X836417Y102533D01*
X836000Y102867D01*
X835417Y103033D01*
X834833Y102950D01*
X834333Y102700D01*
X834000Y102117D01*
X833833Y101617D01*
Y101117D01*
X834000Y100617D01*
X834417Y100117D01*
X834917Y99783D01*
X835500Y99700D01*
X836083Y99867D01*
X836667Y100367D01*
G01X844950Y99700D02*
Y104700D01*
G01Y102200D02*
X845367Y102700D01*
X845867Y102950D01*
X846367Y103033D01*
X847117Y102867D01*
X847617Y102533D01*
X847950Y101950D01*
Y101283D01*
X847783Y100617D01*
X847450Y100117D01*
X846867Y99783D01*
X846367Y99700D01*
X845867Y99783D01*
X845367Y100033D01*
X844950Y100450D01*
G01X850883Y99700D02*
Y103033D01*
G01Y102367D02*
X851300Y102700D01*
X851717Y102950D01*
X852300Y103033D01*
X852717Y102950D01*
X853217Y102700D01*
G01X857650Y99700D02*
X857150Y99783D01*
X856650Y100117D01*
X856317Y100700D01*
X856150Y101367D01*
X856317Y102033D01*
X856650Y102617D01*
X857150Y102950D01*
X857650Y103033D01*
X858150Y102950D01*
X858650Y102617D01*
X858983Y102033D01*
X859067Y101367D01*
X858983Y100700D01*
X858650Y100117D01*
X858150Y99783D01*
X857650Y99700D01*
G01X861833D02*
Y104700D01*
G01X864500Y103033D02*
X861833Y101117D01*
G01X862917Y101867D02*
X864667Y99700D01*
G01X867600Y101950D02*
X870267D01*
X870017Y102533D01*
X869600Y102867D01*
X869017Y103033D01*
X868433Y102950D01*
X867933Y102700D01*
X867600Y102117D01*
X867433Y101617D01*
Y101117D01*
X867600Y100617D01*
X868017Y100117D01*
X868517Y99783D01*
X869100Y99700D01*
X869683Y99867D01*
X870267Y100367D01*
G01X873033Y99700D02*
Y103033D01*
G01Y102200D02*
X873367Y102617D01*
X873867Y102950D01*
X874533Y103033D01*
X875117Y102950D01*
X875617Y102617D01*
X875867Y102033D01*
Y99700D01*
G01X885650D02*
Y104700D01*
G01X892750Y99700D02*
Y103033D01*
G01Y102450D02*
X892417Y102783D01*
X891917Y102950D01*
X891333Y103033D01*
X890750Y102867D01*
X890250Y102533D01*
X889917Y102033D01*
X889750Y101367D01*
X889917Y100700D01*
X890250Y100200D01*
X890750Y99867D01*
X891333Y99700D01*
X891917Y99783D01*
X892417Y100033D01*
X892750Y100367D01*
G01X895100Y98200D02*
X895600Y98033D01*
X896267Y98200D01*
X896683Y98533D01*
X897017Y98950D01*
X897517Y100283D01*
X898600Y103033D01*
G01X895933D02*
X897517Y100283D01*
G01X901200Y101950D02*
X903867D01*
X903617Y102533D01*
X903200Y102867D01*
X902617Y103033D01*
X902033Y102950D01*
X901533Y102700D01*
X901200Y102117D01*
X901033Y101617D01*
Y101117D01*
X901200Y100617D01*
X901617Y100117D01*
X902117Y99783D01*
X902700Y99700D01*
X903283Y99867D01*
X903867Y100367D01*
G01X906883Y99700D02*
Y103033D01*
G01Y102367D02*
X907300Y102700D01*
X907717Y102950D01*
X908300Y103033D01*
X908717Y102950D01*
X909217Y102700D01*
G01X777167Y123000D02*
Y128000D01*
X778833D01*
X779500Y127750D01*
X780000Y127417D01*
X780417Y126917D01*
X780750Y126333D01*
X780833Y125500D01*
X780750Y124667D01*
X780417Y124083D01*
X780000Y123583D01*
X779500Y123250D01*
X778833Y123000D01*
X777167D01*
G01X783433D02*
Y126333D01*
G01Y125667D02*
X783850Y126000D01*
X784267Y126250D01*
X784850Y126333D01*
X785267Y126250D01*
X785767Y126000D01*
G01X790200Y126333D02*
Y123000D01*
G01Y127667D02*
X790033Y127750D01*
Y127917D01*
X790200Y128000D01*
X790367Y127917D01*
Y127750D01*
X790200Y127667D01*
G01X795800Y123000D02*
Y128000D01*
G01X801400Y123000D02*
Y128000D01*
G01X811017Y123000D02*
Y128000D01*
X814183D01*
G01X813017Y125583D02*
X811017D01*
G01X817033Y123000D02*
Y126333D01*
G01Y125667D02*
X817450Y126000D01*
X817867Y126250D01*
X818450Y126333D01*
X818867Y126250D01*
X819367Y126000D01*
G01X823800Y123000D02*
X823300Y123083D01*
X822800Y123417D01*
X822467Y124000D01*
X822300Y124667D01*
X822467Y125333D01*
X822800Y125917D01*
X823300Y126250D01*
X823800Y126333D01*
X824300Y126250D01*
X824800Y125917D01*
X825133Y125333D01*
X825217Y124667D01*
X825133Y124000D01*
X824800Y123417D01*
X824300Y123083D01*
X823800Y123000D01*
G01X826900D02*
Y126333D01*
G01Y125417D02*
X827150Y125833D01*
X827567Y126167D01*
X828150Y126333D01*
X828733Y126167D01*
X829150Y125833D01*
X829400Y125417D01*
Y123000D01*
G01Y125417D02*
X829650Y125833D01*
X830067Y126167D01*
X830650Y126333D01*
X831233Y126167D01*
X831650Y125833D01*
X831900Y125333D01*
Y123000D01*
G01X838933Y128000D02*
Y123000D01*
X842267D01*
G01X846200D02*
Y128000D01*
X845200Y127000D01*
G01Y123000D02*
X847200D01*
G01X856983Y121333D02*
X856150Y122167D01*
X855733Y123000D01*
Y126333D01*
X856150Y127167D01*
X856983Y128000D01*
G01X863000D02*
Y123000D01*
G01X861083Y128000D02*
X864917D01*
G01X868600Y123000D02*
X867933Y123083D01*
X867350Y123417D01*
X866850Y123917D01*
X866517Y124500D01*
X866350Y125167D01*
Y125833D01*
X866517Y126500D01*
X866850Y127083D01*
X867350Y127583D01*
X867933Y127917D01*
X868600Y128000D01*
X869267Y127917D01*
X869850Y127583D01*
X870350Y127083D01*
X870683Y126500D01*
X870850Y125833D01*
Y125167D01*
X870683Y124500D01*
X870350Y123917D01*
X869850Y123417D01*
X869267Y123083D01*
X868600Y123000D01*
G01X872533D02*
Y128000D01*
X874533D01*
X875200Y127750D01*
X875700Y127167D01*
X875867Y126500D01*
X875700Y125833D01*
X875283Y125333D01*
X874533Y125083D01*
X872533D01*
G01X880217Y121333D02*
X881050Y122167D01*
X881467Y123000D01*
Y126333D01*
X881050Y127167D01*
X880217Y128000D01*
G01X891000D02*
Y123000D01*
G01X889833Y126333D02*
X892167D01*
G01X896600Y123000D02*
X896100Y123083D01*
X895600Y123417D01*
X895267Y124000D01*
X895100Y124667D01*
X895267Y125333D01*
X895600Y125917D01*
X896100Y126250D01*
X896600Y126333D01*
X897100Y126250D01*
X897600Y125917D01*
X897933Y125333D01*
X898017Y124667D01*
X897933Y124000D01*
X897600Y123417D01*
X897100Y123083D01*
X896600Y123000D01*
G01X906133Y128000D02*
Y123000D01*
X909467D01*
G01X912150Y126333D02*
X914650Y123000D01*
G01Y126333D02*
X912150Y123000D01*
G01X827667Y150500D02*
Y155500D01*
X829333D01*
X830000Y155250D01*
X830500Y154917D01*
X830917Y154417D01*
X831250Y153833D01*
X831333Y153000D01*
X831250Y152167D01*
X830917Y151583D01*
X830500Y151083D01*
X830000Y150750D01*
X829333Y150500D01*
X827667D01*
G01X835100D02*
Y155500D01*
X834100Y154500D01*
G01Y150500D02*
X836100D01*
G01X776983Y116310D02*
Y111310D01*
X780317D01*
G01X782833D02*
Y114643D01*
G01Y113810D02*
X783167Y114227D01*
X783667Y114560D01*
X784333Y114643D01*
X784917Y114560D01*
X785417Y114227D01*
X785667Y113643D01*
Y111310D01*
G01X789850Y111143D02*
X789683Y111227D01*
Y111393D01*
X789850Y111477D01*
X790017Y111393D01*
Y111227D01*
X789850Y111143D01*
G01Y113393D02*
X789683Y113477D01*
Y113643D01*
X789850Y113727D01*
X790017Y113643D01*
Y113477D01*
X789850Y113393D01*
G01X802383Y114227D02*
X801800Y114560D01*
X801300Y114643D01*
X800633Y114477D01*
X800133Y114143D01*
X799800Y113560D01*
X799717Y112977D01*
X799800Y112393D01*
X800133Y111893D01*
X800633Y111477D01*
X801300Y111310D01*
X801883Y111477D01*
X802383Y111810D01*
G01X808150Y111310D02*
Y114643D01*
G01Y114060D02*
X807817Y114393D01*
X807317Y114560D01*
X806733Y114643D01*
X806150Y114477D01*
X805650Y114143D01*
X805317Y113643D01*
X805150Y112977D01*
X805317Y112310D01*
X805650Y111810D01*
X806150Y111477D01*
X806733Y111310D01*
X807317Y111393D01*
X807817Y111643D01*
X808150Y111977D01*
G01X810833Y111310D02*
Y114643D01*
G01Y113810D02*
X811167Y114227D01*
X811667Y114560D01*
X812333Y114643D01*
X812917Y114560D01*
X813417Y114227D01*
X813667Y113643D01*
Y111310D01*
G01X817850Y114643D02*
X818683Y115685D01*
Y116310D01*
X818058D01*
Y115685D01*
X818683D01*
G01X823450Y116310D02*
Y111310D01*
G01X822283Y114643D02*
X824617D01*
G01X833150Y111310D02*
Y116310D01*
G01Y113810D02*
X833567Y114310D01*
X834067Y114560D01*
X834567Y114643D01*
X835317Y114477D01*
X835817Y114143D01*
X836150Y113560D01*
Y112893D01*
X835983Y112227D01*
X835650Y111727D01*
X835067Y111393D01*
X834567Y111310D01*
X834067Y111393D01*
X833567Y111643D01*
X833150Y112060D01*
G01X839000Y113560D02*
X841667D01*
X841417Y114143D01*
X841000Y114477D01*
X840417Y114643D01*
X839833Y114560D01*
X839333Y114310D01*
X839000Y113727D01*
X838833Y113227D01*
Y112727D01*
X839000Y112227D01*
X839417Y111727D01*
X839917Y111393D01*
X840500Y111310D01*
X841083Y111477D01*
X841667Y111977D01*
G01X849950Y111310D02*
Y116310D01*
G01Y113810D02*
X850367Y114310D01*
X850867Y114560D01*
X851367Y114643D01*
X852117Y114477D01*
X852617Y114143D01*
X852950Y113560D01*
Y112893D01*
X852783Y112227D01*
X852450Y111727D01*
X851867Y111393D01*
X851367Y111310D01*
X850867Y111393D01*
X850367Y111643D01*
X849950Y112060D01*
G01X855883Y111310D02*
Y114643D01*
G01Y113977D02*
X856300Y114310D01*
X856717Y114560D01*
X857300Y114643D01*
X857717Y114560D01*
X858217Y114310D01*
G01X862650Y111310D02*
X862150Y111393D01*
X861650Y111727D01*
X861317Y112310D01*
X861150Y112977D01*
X861317Y113643D01*
X861650Y114227D01*
X862150Y114560D01*
X862650Y114643D01*
X863150Y114560D01*
X863650Y114227D01*
X863983Y113643D01*
X864067Y112977D01*
X863983Y112310D01*
X863650Y111727D01*
X863150Y111393D01*
X862650Y111310D01*
G01X866833D02*
Y116310D01*
G01X869500Y114643D02*
X866833Y112727D01*
G01X867917Y113477D02*
X869667Y111310D01*
G01X872600Y113560D02*
X875267D01*
X875017Y114143D01*
X874600Y114477D01*
X874017Y114643D01*
X873433Y114560D01*
X872933Y114310D01*
X872600Y113727D01*
X872433Y113227D01*
Y112727D01*
X872600Y112227D01*
X873017Y111727D01*
X873517Y111393D01*
X874100Y111310D01*
X874683Y111477D01*
X875267Y111977D01*
G01X878033Y111310D02*
Y114643D01*
G01Y113810D02*
X878367Y114227D01*
X878867Y114560D01*
X879533Y114643D01*
X880117Y114560D01*
X880617Y114227D01*
X880867Y113643D01*
Y111310D01*
G01X890650D02*
Y116310D01*
G01X897750Y111310D02*
Y114643D01*
G01Y114060D02*
X897417Y114393D01*
X896917Y114560D01*
X896333Y114643D01*
X895750Y114477D01*
X895250Y114143D01*
X894917Y113643D01*
X894750Y112977D01*
X894917Y112310D01*
X895250Y111810D01*
X895750Y111477D01*
X896333Y111310D01*
X896917Y111393D01*
X897417Y111643D01*
X897750Y111977D01*
G01X900100Y109810D02*
X900600Y109643D01*
X901267Y109810D01*
X901683Y110143D01*
X902017Y110560D01*
X902517Y111893D01*
X903600Y114643D01*
G01X900933D02*
X902517Y111893D01*
G01X906200Y113560D02*
X908867D01*
X908617Y114143D01*
X908200Y114477D01*
X907617Y114643D01*
X907033Y114560D01*
X906533Y114310D01*
X906200Y113727D01*
X906033Y113227D01*
Y112727D01*
X906200Y112227D01*
X906617Y111727D01*
X907117Y111393D01*
X907700Y111310D01*
X908283Y111477D01*
X908867Y111977D01*
G01X911883Y111310D02*
Y114643D01*
G01Y113977D02*
X912300Y114310D01*
X912717Y114560D01*
X913300Y114643D01*
X913717Y114560D01*
X914217Y114310D01*
G01X777167Y123000D02*
Y128000D01*
X778833D01*
X779500Y127750D01*
X780000Y127417D01*
X780417Y126917D01*
X780750Y126333D01*
X780833Y125500D01*
X780750Y124667D01*
X780417Y124083D01*
X780000Y123583D01*
X779500Y123250D01*
X778833Y123000D01*
X777167D01*
G01X783433D02*
Y126333D01*
G01Y125667D02*
X783850Y126000D01*
X784267Y126250D01*
X784850Y126333D01*
X785267Y126250D01*
X785767Y126000D01*
G01X790200Y126333D02*
Y123000D01*
G01Y127667D02*
X790033Y127750D01*
Y127917D01*
X790200Y128000D01*
X790367Y127917D01*
Y127750D01*
X790200Y127667D01*
G01X795800Y123000D02*
Y128000D01*
G01X801400Y123000D02*
Y128000D01*
G01X811017Y123000D02*
Y128000D01*
X814183D01*
G01X813017Y125583D02*
X811017D01*
G01X817033Y123000D02*
Y126333D01*
G01Y125667D02*
X817450Y126000D01*
X817867Y126250D01*
X818450Y126333D01*
X818867Y126250D01*
X819367Y126000D01*
G01X823800Y123000D02*
X823300Y123083D01*
X822800Y123417D01*
X822467Y124000D01*
X822300Y124667D01*
X822467Y125333D01*
X822800Y125917D01*
X823300Y126250D01*
X823800Y126333D01*
X824300Y126250D01*
X824800Y125917D01*
X825133Y125333D01*
X825217Y124667D01*
X825133Y124000D01*
X824800Y123417D01*
X824300Y123083D01*
X823800Y123000D01*
G01X826900D02*
Y126333D01*
G01Y125417D02*
X827150Y125833D01*
X827567Y126167D01*
X828150Y126333D01*
X828733Y126167D01*
X829150Y125833D01*
X829400Y125417D01*
Y123000D01*
G01Y125417D02*
X829650Y125833D01*
X830067Y126167D01*
X830650Y126333D01*
X831233Y126167D01*
X831650Y125833D01*
X831900Y125333D01*
Y123000D01*
G01X838933Y128000D02*
Y123000D01*
X842267D01*
G01X846200D02*
Y128000D01*
X845200Y127000D01*
G01Y123000D02*
X847200D01*
G01X856983Y121333D02*
X856150Y122167D01*
X855733Y123000D01*
Y126333D01*
X856150Y127167D01*
X856983Y128000D01*
G01X863000D02*
Y123000D01*
G01X861083Y128000D02*
X864917D01*
G01X868600Y123000D02*
X867933Y123083D01*
X867350Y123417D01*
X866850Y123917D01*
X866517Y124500D01*
X866350Y125167D01*
Y125833D01*
X866517Y126500D01*
X866850Y127083D01*
X867350Y127583D01*
X867933Y127917D01*
X868600Y128000D01*
X869267Y127917D01*
X869850Y127583D01*
X870350Y127083D01*
X870683Y126500D01*
X870850Y125833D01*
Y125167D01*
X870683Y124500D01*
X870350Y123917D01*
X869850Y123417D01*
X869267Y123083D01*
X868600Y123000D01*
G01X872533D02*
Y128000D01*
X874533D01*
X875200Y127750D01*
X875700Y127167D01*
X875867Y126500D01*
X875700Y125833D01*
X875283Y125333D01*
X874533Y125083D01*
X872533D01*
G01X880217Y121333D02*
X881050Y122167D01*
X881467Y123000D01*
Y126333D01*
X881050Y127167D01*
X880217Y128000D01*
G01X891000D02*
Y123000D01*
G01X889833Y126333D02*
X892167D01*
G01X896600Y123000D02*
X896100Y123083D01*
X895600Y123417D01*
X895267Y124000D01*
X895100Y124667D01*
X895267Y125333D01*
X895600Y125917D01*
X896100Y126250D01*
X896600Y126333D01*
X897100Y126250D01*
X897600Y125917D01*
X897933Y125333D01*
X898017Y124667D01*
X897933Y124000D01*
X897600Y123417D01*
X897100Y123083D01*
X896600Y123000D01*
G01X906133Y128000D02*
Y123000D01*
X909467D01*
G01X912150Y126333D02*
X914650Y123000D01*
G01Y126333D02*
X912150Y123000D01*
G01X827667Y150500D02*
Y155500D01*
X829333D01*
X830000Y155250D01*
X830500Y154917D01*
X830917Y154417D01*
X831250Y153833D01*
X831333Y153000D01*
X831250Y152167D01*
X830917Y151583D01*
X830500Y151083D01*
X830000Y150750D01*
X829333Y150500D01*
X827667D01*
G01X835100D02*
Y155500D01*
X834100Y154500D01*
G01Y150500D02*
X836100D01*
G01X776983Y116310D02*
Y111310D01*
X780317D01*
G01X782833D02*
Y114643D01*
G01Y113810D02*
X783167Y114227D01*
X783667Y114560D01*
X784333Y114643D01*
X784917Y114560D01*
X785417Y114227D01*
X785667Y113643D01*
Y111310D01*
G01X789850Y111143D02*
X789683Y111227D01*
Y111393D01*
X789850Y111477D01*
X790017Y111393D01*
Y111227D01*
X789850Y111143D01*
G01Y113393D02*
X789683Y113477D01*
Y113643D01*
X789850Y113727D01*
X790017Y113643D01*
Y113477D01*
X789850Y113393D01*
G01X802383Y114227D02*
X801800Y114560D01*
X801300Y114643D01*
X800633Y114477D01*
X800133Y114143D01*
X799800Y113560D01*
X799717Y112977D01*
X799800Y112393D01*
X800133Y111893D01*
X800633Y111477D01*
X801300Y111310D01*
X801883Y111477D01*
X802383Y111810D01*
G01X808150Y111310D02*
Y114643D01*
G01Y114060D02*
X807817Y114393D01*
X807317Y114560D01*
X806733Y114643D01*
X806150Y114477D01*
X805650Y114143D01*
X805317Y113643D01*
X805150Y112977D01*
X805317Y112310D01*
X805650Y111810D01*
X806150Y111477D01*
X806733Y111310D01*
X807317Y111393D01*
X807817Y111643D01*
X808150Y111977D01*
G01X810833Y111310D02*
Y114643D01*
G01Y113810D02*
X811167Y114227D01*
X811667Y114560D01*
X812333Y114643D01*
X812917Y114560D01*
X813417Y114227D01*
X813667Y113643D01*
Y111310D01*
G01X817850Y114643D02*
X818683Y115685D01*
Y116310D01*
X818058D01*
Y115685D01*
X818683D01*
G01X823450Y116310D02*
Y111310D01*
G01X822283Y114643D02*
X824617D01*
G01X833150Y111310D02*
Y116310D01*
G01Y113810D02*
X833567Y114310D01*
X834067Y114560D01*
X834567Y114643D01*
X835317Y114477D01*
X835817Y114143D01*
X836150Y113560D01*
Y112893D01*
X835983Y112227D01*
X835650Y111727D01*
X835067Y111393D01*
X834567Y111310D01*
X834067Y111393D01*
X833567Y111643D01*
X833150Y112060D01*
G01X839000Y113560D02*
X841667D01*
X841417Y114143D01*
X841000Y114477D01*
X840417Y114643D01*
X839833Y114560D01*
X839333Y114310D01*
X839000Y113727D01*
X838833Y113227D01*
Y112727D01*
X839000Y112227D01*
X839417Y111727D01*
X839917Y111393D01*
X840500Y111310D01*
X841083Y111477D01*
X841667Y111977D01*
G01X849950Y111310D02*
Y116310D01*
G01Y113810D02*
X850367Y114310D01*
X850867Y114560D01*
X851367Y114643D01*
X852117Y114477D01*
X852617Y114143D01*
X852950Y113560D01*
Y112893D01*
X852783Y112227D01*
X852450Y111727D01*
X851867Y111393D01*
X851367Y111310D01*
X850867Y111393D01*
X850367Y111643D01*
X849950Y112060D01*
G01X855883Y111310D02*
Y114643D01*
G01Y113977D02*
X856300Y114310D01*
X856717Y114560D01*
X857300Y114643D01*
X857717Y114560D01*
X858217Y114310D01*
G01X862650Y111310D02*
X862150Y111393D01*
X861650Y111727D01*
X861317Y112310D01*
X861150Y112977D01*
X861317Y113643D01*
X861650Y114227D01*
X862150Y114560D01*
X862650Y114643D01*
X863150Y114560D01*
X863650Y114227D01*
X863983Y113643D01*
X864067Y112977D01*
X863983Y112310D01*
X863650Y111727D01*
X863150Y111393D01*
X862650Y111310D01*
G01X866833D02*
Y116310D01*
G01X869500Y114643D02*
X866833Y112727D01*
G01X867917Y113477D02*
X869667Y111310D01*
G01X872600Y113560D02*
X875267D01*
X875017Y114143D01*
X874600Y114477D01*
X874017Y114643D01*
X873433Y114560D01*
X872933Y114310D01*
X872600Y113727D01*
X872433Y113227D01*
Y112727D01*
X872600Y112227D01*
X873017Y111727D01*
X873517Y111393D01*
X874100Y111310D01*
X874683Y111477D01*
X875267Y111977D01*
G01X878033Y111310D02*
Y114643D01*
G01Y113810D02*
X878367Y114227D01*
X878867Y114560D01*
X879533Y114643D01*
X880117Y114560D01*
X880617Y114227D01*
X880867Y113643D01*
Y111310D01*
G01X890650D02*
Y116310D01*
G01X897750Y111310D02*
Y114643D01*
G01Y114060D02*
X897417Y114393D01*
X896917Y114560D01*
X896333Y114643D01*
X895750Y114477D01*
X895250Y114143D01*
X894917Y113643D01*
X894750Y112977D01*
X894917Y112310D01*
X895250Y111810D01*
X895750Y111477D01*
X896333Y111310D01*
X896917Y111393D01*
X897417Y111643D01*
X897750Y111977D01*
G01X900100Y109810D02*
X900600Y109643D01*
X901267Y109810D01*
X901683Y110143D01*
X902017Y110560D01*
X902517Y111893D01*
X903600Y114643D01*
G01X900933D02*
X902517Y111893D01*
G01X906200Y113560D02*
X908867D01*
X908617Y114143D01*
X908200Y114477D01*
X907617Y114643D01*
X907033Y114560D01*
X906533Y114310D01*
X906200Y113727D01*
X906033Y113227D01*
Y112727D01*
X906200Y112227D01*
X906617Y111727D01*
X907117Y111393D01*
X907700Y111310D01*
X908283Y111477D01*
X908867Y111977D01*
G01X911883Y111310D02*
Y114643D01*
G01Y113977D02*
X912300Y114310D01*
X912717Y114560D01*
X913300Y114643D01*
X913717Y114560D01*
X914217Y114310D01*
G01X825667Y314500D02*
Y319500D01*
X827333D01*
X828000Y319250D01*
X828500Y318917D01*
X828917Y318417D01*
X829250Y317833D01*
X829333Y317000D01*
X829250Y316167D01*
X828917Y315583D01*
X828500Y315083D01*
X828000Y314750D01*
X827333Y314500D01*
X825667D01*
G01X831517Y318667D02*
X832017Y319167D01*
X832600Y319417D01*
X833267Y319500D01*
X834100Y319333D01*
X834683Y318917D01*
X834850Y318417D01*
X834767Y317917D01*
X834433Y317500D01*
X832767Y316667D01*
X832017Y316083D01*
X831517Y315250D01*
X831350Y314500D01*
X834850D01*
G01X825667D02*
Y319500D01*
X827333D01*
X828000Y319250D01*
X828500Y318917D01*
X828917Y318417D01*
X829250Y317833D01*
X829333Y317000D01*
X829250Y316167D01*
X828917Y315583D01*
X828500Y315083D01*
X828000Y314750D01*
X827333Y314500D01*
X825667D01*
G01X831517Y318667D02*
X832017Y319167D01*
X832600Y319417D01*
X833267Y319500D01*
X834100Y319333D01*
X834683Y318917D01*
X834850Y318417D01*
X834767Y317917D01*
X834433Y317500D01*
X832767Y316667D01*
X832017Y316083D01*
X831517Y315250D01*
X831350Y314500D01*
X834850D01*
G01X821590Y376450D02*
Y379783D01*
G01Y379200D02*
X821257Y379533D01*
X820757Y379700D01*
X820173Y379783D01*
X819590Y379617D01*
X819090Y379283D01*
X818757Y378783D01*
X818590Y378117D01*
X818757Y377450D01*
X819090Y376950D01*
X819590Y376617D01*
X820173Y376450D01*
X820757Y376533D01*
X821257Y376783D01*
X821590Y377117D01*
G01X824273Y376450D02*
Y379783D01*
G01Y378950D02*
X824607Y379367D01*
X825107Y379700D01*
X825773Y379783D01*
X826357Y379700D01*
X826857Y379367D01*
X827107Y378783D01*
Y376450D01*
G01X832790Y381450D02*
Y376450D01*
G01Y377200D02*
X832457Y376783D01*
X831957Y376533D01*
X831373Y376450D01*
X830707Y376617D01*
X830207Y377033D01*
X829873Y377533D01*
X829790Y378117D01*
X829873Y378700D01*
X830207Y379200D01*
X830707Y379617D01*
X831373Y379783D01*
X831957Y379700D01*
X832373Y379533D01*
X832790Y379200D01*
G01X843823Y379367D02*
X843240Y379700D01*
X842740Y379783D01*
X842073Y379617D01*
X841573Y379283D01*
X841240Y378700D01*
X841157Y378117D01*
X841240Y377533D01*
X841573Y377033D01*
X842073Y376617D01*
X842740Y376450D01*
X843323Y376617D01*
X843823Y376950D01*
G01X848090Y376450D02*
X847590Y376533D01*
X847090Y376867D01*
X846757Y377450D01*
X846590Y378117D01*
X846757Y378783D01*
X847090Y379367D01*
X847590Y379700D01*
X848090Y379783D01*
X848590Y379700D01*
X849090Y379367D01*
X849423Y378783D01*
X849507Y378117D01*
X849423Y377450D01*
X849090Y376867D01*
X848590Y376533D01*
X848090Y376450D01*
G01X852190Y379783D02*
X853690Y376450D01*
X855190Y379783D01*
G01X858040Y378700D02*
X860707D01*
X860457Y379283D01*
X860040Y379617D01*
X859457Y379783D01*
X858873Y379700D01*
X858373Y379450D01*
X858040Y378867D01*
X857873Y378367D01*
Y377867D01*
X858040Y377367D01*
X858457Y376867D01*
X858957Y376533D01*
X859540Y376450D01*
X860123Y376617D01*
X860707Y377117D01*
G01X863723Y376450D02*
Y379783D01*
G01Y379117D02*
X864140Y379450D01*
X864557Y379700D01*
X865140Y379783D01*
X865557Y379700D01*
X866057Y379450D01*
G01X869240Y378700D02*
X871907D01*
X871657Y379283D01*
X871240Y379617D01*
X870657Y379783D01*
X870073Y379700D01*
X869573Y379450D01*
X869240Y378867D01*
X869073Y378367D01*
Y377867D01*
X869240Y377367D01*
X869657Y376867D01*
X870157Y376533D01*
X870740Y376450D01*
X871323Y376617D01*
X871907Y377117D01*
G01X877590Y381450D02*
Y376450D01*
G01Y377200D02*
X877257Y376783D01*
X876757Y376533D01*
X876173Y376450D01*
X875507Y376617D01*
X875007Y377033D01*
X874673Y377533D01*
X874590Y378117D01*
X874673Y378700D01*
X875007Y379200D01*
X875507Y379617D01*
X876173Y379783D01*
X876757Y379700D01*
X877173Y379533D01*
X877590Y379200D01*
G01X885207Y379783D02*
X886207Y376450D01*
X887290Y379783D01*
X888373Y376450D01*
X889373Y379783D01*
G01X892890D02*
Y376450D01*
G01Y381117D02*
X892723Y381200D01*
Y381367D01*
X892890Y381450D01*
X893057Y381367D01*
Y381200D01*
X892890Y381117D01*
G01X898490Y381450D02*
Y376450D01*
G01X897323Y379783D02*
X899657D01*
G01X902673Y376450D02*
Y381450D01*
G01Y379033D02*
X903090Y379450D01*
X903507Y379700D01*
X904173Y379783D01*
X904673Y379700D01*
X905257Y379367D01*
X905507Y378867D01*
Y376450D01*
G01X916623Y379367D02*
X916040Y379700D01*
X915540Y379783D01*
X914873Y379617D01*
X914373Y379283D01*
X914040Y378700D01*
X913957Y378117D01*
X914040Y377533D01*
X914373Y377033D01*
X914873Y376617D01*
X915540Y376450D01*
X916123Y376617D01*
X916623Y376950D01*
G01X920890Y376450D02*
X920390Y376533D01*
X919890Y376867D01*
X919557Y377450D01*
X919390Y378117D01*
X919557Y378783D01*
X919890Y379367D01*
X920390Y379700D01*
X920890Y379783D01*
X921390Y379700D01*
X921890Y379367D01*
X922223Y378783D01*
X922307Y378117D01*
X922223Y377450D01*
X921890Y376867D01*
X921390Y376533D01*
X920890Y376450D01*
G01X924990Y374783D02*
Y379783D01*
G01Y379033D02*
X925407Y379450D01*
X925823Y379700D01*
X926490Y379783D01*
X927073Y379700D01*
X927657Y379283D01*
X927907Y378700D01*
X927990Y378117D01*
X927907Y377533D01*
X927657Y376950D01*
X927157Y376617D01*
X926490Y376450D01*
X925907Y376533D01*
X925323Y376783D01*
X924990Y377117D01*
G01X930590Y374783D02*
Y379783D01*
G01Y379033D02*
X931007Y379450D01*
X931423Y379700D01*
X932090Y379783D01*
X932673Y379700D01*
X933257Y379283D01*
X933507Y378700D01*
X933590Y378117D01*
X933507Y377533D01*
X933257Y376950D01*
X932757Y376617D01*
X932090Y376450D01*
X931507Y376533D01*
X930923Y376783D01*
X930590Y377117D01*
G01X936440Y378700D02*
X939107D01*
X938857Y379283D01*
X938440Y379617D01*
X937857Y379783D01*
X937273Y379700D01*
X936773Y379450D01*
X936440Y378867D01*
X936273Y378367D01*
Y377867D01*
X936440Y377367D01*
X936857Y376867D01*
X937357Y376533D01*
X937940Y376450D01*
X938523Y376617D01*
X939107Y377117D01*
G01X942123Y376450D02*
Y379783D01*
G01Y379117D02*
X942540Y379450D01*
X942957Y379700D01*
X943540Y379783D01*
X943957Y379700D01*
X944457Y379450D01*
G01X821500Y419500D02*
Y423750D01*
X821667Y424167D01*
X822000Y424417D01*
X822500Y424500D01*
X823000Y424333D01*
X823250Y423917D01*
G01X822250Y422500D02*
X820583D01*
G01X827600Y419500D02*
X827100Y419583D01*
X826600Y419917D01*
X826267Y420500D01*
X826100Y421167D01*
X826267Y421833D01*
X826600Y422417D01*
X827100Y422750D01*
X827600Y422833D01*
X828100Y422750D01*
X828600Y422417D01*
X828933Y421833D01*
X829017Y421167D01*
X828933Y420500D01*
X828600Y419917D01*
X828100Y419583D01*
X827600Y419500D01*
G01X833200D02*
Y424500D01*
G01X838800Y419500D02*
Y424500D01*
G01X844400Y419500D02*
X843900Y419583D01*
X843400Y419917D01*
X843067Y420500D01*
X842900Y421167D01*
X843067Y421833D01*
X843400Y422417D01*
X843900Y422750D01*
X844400Y422833D01*
X844900Y422750D01*
X845400Y422417D01*
X845733Y421833D01*
X845817Y421167D01*
X845733Y420500D01*
X845400Y419917D01*
X844900Y419583D01*
X844400Y419500D01*
G01X847917Y422833D02*
X848917Y419500D01*
X850000Y422833D01*
X851083Y419500D01*
X852083Y422833D01*
G01X861700Y422000D02*
X863367D01*
Y420500D01*
X862867Y420000D01*
X862283Y419667D01*
X861450Y419500D01*
X860617Y419667D01*
X860033Y420000D01*
X859533Y420500D01*
X859200Y421083D01*
X859033Y421750D01*
Y422333D01*
X859200Y422833D01*
X859533Y423417D01*
X860033Y423917D01*
X860533Y424250D01*
X861200Y424500D01*
X861783D01*
X862450Y424333D01*
X862950Y424000D01*
G01X865550Y421750D02*
X868217D01*
X867967Y422333D01*
X867550Y422667D01*
X866967Y422833D01*
X866383Y422750D01*
X865883Y422500D01*
X865550Y421917D01*
X865383Y421417D01*
Y420917D01*
X865550Y420417D01*
X865967Y419917D01*
X866467Y419583D01*
X867050Y419500D01*
X867633Y419667D01*
X868217Y420167D01*
G01X871233Y419500D02*
Y422833D01*
G01Y422167D02*
X871650Y422500D01*
X872067Y422750D01*
X872650Y422833D01*
X873067Y422750D01*
X873567Y422500D01*
G01X876500Y419500D02*
Y424500D01*
G01Y422000D02*
X876917Y422500D01*
X877417Y422750D01*
X877917Y422833D01*
X878667Y422667D01*
X879167Y422333D01*
X879500Y421750D01*
Y421083D01*
X879333Y420417D01*
X879000Y419917D01*
X878417Y419583D01*
X877917Y419500D01*
X877417Y419583D01*
X876917Y419833D01*
X876500Y420250D01*
G01X882350Y421750D02*
X885017D01*
X884767Y422333D01*
X884350Y422667D01*
X883767Y422833D01*
X883183Y422750D01*
X882683Y422500D01*
X882350Y421917D01*
X882183Y421417D01*
Y420917D01*
X882350Y420417D01*
X882767Y419917D01*
X883267Y419583D01*
X883850Y419500D01*
X884433Y419667D01*
X885017Y420167D01*
G01X888033Y419500D02*
Y422833D01*
G01Y422167D02*
X888450Y422500D01*
X888867Y422750D01*
X889450Y422833D01*
X889867Y422750D01*
X890367Y422500D01*
G01X901900Y419500D02*
Y422833D01*
G01Y422250D02*
X901567Y422583D01*
X901067Y422750D01*
X900483Y422833D01*
X899900Y422667D01*
X899400Y422333D01*
X899067Y421833D01*
X898900Y421167D01*
X899067Y420500D01*
X899400Y420000D01*
X899900Y419667D01*
X900483Y419500D01*
X901067Y419583D01*
X901567Y419833D01*
X901900Y420167D01*
G01X904583Y419500D02*
Y422833D01*
G01Y422000D02*
X904917Y422417D01*
X905417Y422750D01*
X906083Y422833D01*
X906667Y422750D01*
X907167Y422417D01*
X907417Y421833D01*
Y419500D01*
G01X913100Y424500D02*
Y419500D01*
G01Y420250D02*
X912767Y419833D01*
X912267Y419583D01*
X911683Y419500D01*
X911017Y419667D01*
X910517Y420083D01*
X910183Y420583D01*
X910100Y421167D01*
X910183Y421750D01*
X910517Y422250D01*
X911017Y422667D01*
X911683Y422833D01*
X912267Y422750D01*
X912683Y422583D01*
X913100Y422250D01*
G01X921300Y417833D02*
Y422833D01*
G01Y422083D02*
X921717Y422500D01*
X922133Y422750D01*
X922800Y422833D01*
X923383Y422750D01*
X923967Y422333D01*
X924217Y421750D01*
X924300Y421167D01*
X924217Y420583D01*
X923967Y420000D01*
X923467Y419667D01*
X922800Y419500D01*
X922217Y419583D01*
X921633Y419833D01*
X921300Y420167D01*
G01X928400Y419500D02*
Y424500D01*
G01X932583Y422833D02*
Y420500D01*
X932917Y419917D01*
X933417Y419583D01*
X934000Y419500D01*
X934583Y419583D01*
X935083Y419917D01*
X935417Y420500D01*
G01Y419500D02*
Y422833D01*
G01X938433Y418250D02*
X939017Y417917D01*
X939683Y417833D01*
X940267Y417917D01*
X940767Y418333D01*
X941100Y418917D01*
Y422833D01*
G01Y422167D02*
X940767Y422500D01*
X940267Y422750D01*
X939683Y422833D01*
X939017Y422667D01*
X938600Y422333D01*
X938267Y421750D01*
X938100Y421167D01*
X938183Y420667D01*
X938517Y420083D01*
X939017Y419667D01*
X939683Y419500D01*
X940183Y419583D01*
X940767Y419917D01*
X941100Y420250D01*
G01X948717Y422833D02*
X949717Y419500D01*
X950800Y422833D01*
X951883Y419500D01*
X952883Y422833D01*
G01X956400D02*
Y419500D01*
G01Y424167D02*
X956233Y424250D01*
Y424417D01*
X956400Y424500D01*
X956567Y424417D01*
Y424250D01*
X956400Y424167D01*
G01X962000Y424500D02*
Y419500D01*
G01X960833Y422833D02*
X963167D01*
G01X966183Y419500D02*
Y424500D01*
G01Y422083D02*
X966600Y422500D01*
X967017Y422750D01*
X967683Y422833D01*
X968183Y422750D01*
X968767Y422417D01*
X969017Y421917D01*
Y419500D01*
G01X977633D02*
Y422833D01*
G01Y422167D02*
X978050Y422500D01*
X978467Y422750D01*
X979050Y422833D01*
X979467Y422750D01*
X979967Y422500D01*
G01X983150Y421750D02*
X985817D01*
X985567Y422333D01*
X985150Y422667D01*
X984567Y422833D01*
X983983Y422750D01*
X983483Y422500D01*
X983150Y421917D01*
X982983Y421417D01*
Y420917D01*
X983150Y420417D01*
X983567Y419917D01*
X984067Y419583D01*
X984650Y419500D01*
X985233Y419667D01*
X985817Y420167D01*
G01X988750Y420083D02*
X989167Y419750D01*
X989750Y419500D01*
X990250D01*
X990750Y419667D01*
X991083Y419917D01*
X991250Y420250D01*
X991167Y420750D01*
X990833Y421000D01*
X989333Y421500D01*
X989000Y422083D01*
X989167Y422500D01*
X989500Y422750D01*
X990000Y422833D01*
X990500Y422750D01*
X991000Y422500D01*
G01X995600Y422833D02*
Y419500D01*
G01Y424167D02*
X995433Y424250D01*
Y424417D01*
X995600Y424500D01*
X995767Y424417D01*
Y424250D01*
X995600Y424167D01*
G01X999783Y419500D02*
Y422833D01*
G01Y422000D02*
X1000117Y422417D01*
X1000617Y422750D01*
X1001283Y422833D01*
X1001867Y422750D01*
X1002367Y422417D01*
X1002617Y421833D01*
Y419500D01*
G01X819590Y389810D02*
Y394060D01*
X819757Y394477D01*
X820090Y394727D01*
X820590Y394810D01*
X821090Y394643D01*
X821340Y394227D01*
G01X820340Y392810D02*
X818673D01*
G01X825690Y389810D02*
X825190Y389893D01*
X824690Y390227D01*
X824357Y390810D01*
X824190Y391477D01*
X824357Y392143D01*
X824690Y392727D01*
X825190Y393060D01*
X825690Y393143D01*
X826190Y393060D01*
X826690Y392727D01*
X827023Y392143D01*
X827107Y391477D01*
X827023Y390810D01*
X826690Y390227D01*
X826190Y389893D01*
X825690Y389810D01*
G01X831290D02*
Y394810D01*
G01X836890Y389810D02*
Y394810D01*
G01X842490Y389810D02*
X841990Y389893D01*
X841490Y390227D01*
X841157Y390810D01*
X840990Y391477D01*
X841157Y392143D01*
X841490Y392727D01*
X841990Y393060D01*
X842490Y393143D01*
X842990Y393060D01*
X843490Y392727D01*
X843823Y392143D01*
X843907Y391477D01*
X843823Y390810D01*
X843490Y390227D01*
X842990Y389893D01*
X842490Y389810D01*
G01X846007Y393143D02*
X847007Y389810D01*
X848090Y393143D01*
X849173Y389810D01*
X850173Y393143D01*
G01X859790Y392310D02*
X861457D01*
Y390810D01*
X860957Y390310D01*
X860373Y389977D01*
X859540Y389810D01*
X858707Y389977D01*
X858123Y390310D01*
X857623Y390810D01*
X857290Y391393D01*
X857123Y392060D01*
Y392643D01*
X857290Y393143D01*
X857623Y393727D01*
X858123Y394227D01*
X858623Y394560D01*
X859290Y394810D01*
X859873D01*
X860540Y394643D01*
X861040Y394310D01*
G01X863640Y392060D02*
X866307D01*
X866057Y392643D01*
X865640Y392977D01*
X865057Y393143D01*
X864473Y393060D01*
X863973Y392810D01*
X863640Y392227D01*
X863473Y391727D01*
Y391227D01*
X863640Y390727D01*
X864057Y390227D01*
X864557Y389893D01*
X865140Y389810D01*
X865723Y389977D01*
X866307Y390477D01*
G01X869323Y389810D02*
Y393143D01*
G01Y392477D02*
X869740Y392810D01*
X870157Y393060D01*
X870740Y393143D01*
X871157Y393060D01*
X871657Y392810D01*
G01X874590Y389810D02*
Y394810D01*
G01Y392310D02*
X875007Y392810D01*
X875507Y393060D01*
X876007Y393143D01*
X876757Y392977D01*
X877257Y392643D01*
X877590Y392060D01*
Y391393D01*
X877423Y390727D01*
X877090Y390227D01*
X876507Y389893D01*
X876007Y389810D01*
X875507Y389893D01*
X875007Y390143D01*
X874590Y390560D01*
G01X880440Y392060D02*
X883107D01*
X882857Y392643D01*
X882440Y392977D01*
X881857Y393143D01*
X881273Y393060D01*
X880773Y392810D01*
X880440Y392227D01*
X880273Y391727D01*
Y391227D01*
X880440Y390727D01*
X880857Y390227D01*
X881357Y389893D01*
X881940Y389810D01*
X882523Y389977D01*
X883107Y390477D01*
G01X886123Y389810D02*
Y393143D01*
G01Y392477D02*
X886540Y392810D01*
X886957Y393060D01*
X887540Y393143D01*
X887957Y393060D01*
X888457Y392810D01*
G01X899990Y389810D02*
Y393143D01*
G01Y392560D02*
X899657Y392893D01*
X899157Y393060D01*
X898573Y393143D01*
X897990Y392977D01*
X897490Y392643D01*
X897157Y392143D01*
X896990Y391477D01*
X897157Y390810D01*
X897490Y390310D01*
X897990Y389977D01*
X898573Y389810D01*
X899157Y389893D01*
X899657Y390143D01*
X899990Y390477D01*
G01X902673Y389810D02*
Y393143D01*
G01Y392310D02*
X903007Y392727D01*
X903507Y393060D01*
X904173Y393143D01*
X904757Y393060D01*
X905257Y392727D01*
X905507Y392143D01*
Y389810D01*
G01X911190Y394810D02*
Y389810D01*
G01Y390560D02*
X910857Y390143D01*
X910357Y389893D01*
X909773Y389810D01*
X909107Y389977D01*
X908607Y390393D01*
X908273Y390893D01*
X908190Y391477D01*
X908273Y392060D01*
X908607Y392560D01*
X909107Y392977D01*
X909773Y393143D01*
X910357Y393060D01*
X910773Y392893D01*
X911190Y392560D01*
G01X919390Y388143D02*
Y393143D01*
G01Y392393D02*
X919807Y392810D01*
X920223Y393060D01*
X920890Y393143D01*
X921473Y393060D01*
X922057Y392643D01*
X922307Y392060D01*
X922390Y391477D01*
X922307Y390893D01*
X922057Y390310D01*
X921557Y389977D01*
X920890Y389810D01*
X920307Y389893D01*
X919723Y390143D01*
X919390Y390477D01*
G01X926490Y389810D02*
Y394810D01*
G01X930673Y393143D02*
Y390810D01*
X931007Y390227D01*
X931507Y389893D01*
X932090Y389810D01*
X932673Y389893D01*
X933173Y390227D01*
X933507Y390810D01*
G01Y389810D02*
Y393143D01*
G01X936523Y388560D02*
X937107Y388227D01*
X937773Y388143D01*
X938357Y388227D01*
X938857Y388643D01*
X939190Y389227D01*
Y393143D01*
G01Y392477D02*
X938857Y392810D01*
X938357Y393060D01*
X937773Y393143D01*
X937107Y392977D01*
X936690Y392643D01*
X936357Y392060D01*
X936190Y391477D01*
X936273Y390977D01*
X936607Y390393D01*
X937107Y389977D01*
X937773Y389810D01*
X938273Y389893D01*
X938857Y390227D01*
X939190Y390560D01*
G01X946807Y393143D02*
X947807Y389810D01*
X948890Y393143D01*
X949973Y389810D01*
X950973Y393143D01*
G01X954490D02*
Y389810D01*
G01Y394477D02*
X954323Y394560D01*
Y394727D01*
X954490Y394810D01*
X954657Y394727D01*
Y394560D01*
X954490Y394477D01*
G01X960090Y394810D02*
Y389810D01*
G01X958923Y393143D02*
X961257D01*
G01X964273Y389810D02*
Y394810D01*
G01Y392393D02*
X964690Y392810D01*
X965107Y393060D01*
X965773Y393143D01*
X966273Y393060D01*
X966857Y392727D01*
X967107Y392227D01*
Y389810D01*
G01X975723D02*
Y393143D01*
G01Y392477D02*
X976140Y392810D01*
X976557Y393060D01*
X977140Y393143D01*
X977557Y393060D01*
X978057Y392810D01*
G01X981240Y392060D02*
X983907D01*
X983657Y392643D01*
X983240Y392977D01*
X982657Y393143D01*
X982073Y393060D01*
X981573Y392810D01*
X981240Y392227D01*
X981073Y391727D01*
Y391227D01*
X981240Y390727D01*
X981657Y390227D01*
X982157Y389893D01*
X982740Y389810D01*
X983323Y389977D01*
X983907Y390477D01*
G01X986840Y390393D02*
X987257Y390060D01*
X987840Y389810D01*
X988340D01*
X988840Y389977D01*
X989173Y390227D01*
X989340Y390560D01*
X989257Y391060D01*
X988923Y391310D01*
X987423Y391810D01*
X987090Y392393D01*
X987257Y392810D01*
X987590Y393060D01*
X988090Y393143D01*
X988590Y393060D01*
X989090Y392810D01*
G01X993690Y393143D02*
Y389810D01*
G01Y394477D02*
X993523Y394560D01*
Y394727D01*
X993690Y394810D01*
X993857Y394727D01*
Y394560D01*
X993690Y394477D01*
G01X997873Y389810D02*
Y393143D01*
G01Y392310D02*
X998207Y392727D01*
X998707Y393060D01*
X999373Y393143D01*
X999957Y393060D01*
X1000457Y392727D01*
X1000707Y392143D01*
Y389810D01*
G01X812000Y604500D02*
Y366000D01*
G01X821590Y376450D02*
Y379783D01*
G01Y379200D02*
X821257Y379533D01*
X820757Y379700D01*
X820173Y379783D01*
X819590Y379617D01*
X819090Y379283D01*
X818757Y378783D01*
X818590Y378117D01*
X818757Y377450D01*
X819090Y376950D01*
X819590Y376617D01*
X820173Y376450D01*
X820757Y376533D01*
X821257Y376783D01*
X821590Y377117D01*
G01X824273Y376450D02*
Y379783D01*
G01Y378950D02*
X824607Y379367D01*
X825107Y379700D01*
X825773Y379783D01*
X826357Y379700D01*
X826857Y379367D01*
X827107Y378783D01*
Y376450D01*
G01X832790Y381450D02*
Y376450D01*
G01Y377200D02*
X832457Y376783D01*
X831957Y376533D01*
X831373Y376450D01*
X830707Y376617D01*
X830207Y377033D01*
X829873Y377533D01*
X829790Y378117D01*
X829873Y378700D01*
X830207Y379200D01*
X830707Y379617D01*
X831373Y379783D01*
X831957Y379700D01*
X832373Y379533D01*
X832790Y379200D01*
G01X843823Y379367D02*
X843240Y379700D01*
X842740Y379783D01*
X842073Y379617D01*
X841573Y379283D01*
X841240Y378700D01*
X841157Y378117D01*
X841240Y377533D01*
X841573Y377033D01*
X842073Y376617D01*
X842740Y376450D01*
X843323Y376617D01*
X843823Y376950D01*
G01X848090Y376450D02*
X847590Y376533D01*
X847090Y376867D01*
X846757Y377450D01*
X846590Y378117D01*
X846757Y378783D01*
X847090Y379367D01*
X847590Y379700D01*
X848090Y379783D01*
X848590Y379700D01*
X849090Y379367D01*
X849423Y378783D01*
X849507Y378117D01*
X849423Y377450D01*
X849090Y376867D01*
X848590Y376533D01*
X848090Y376450D01*
G01X852190Y379783D02*
X853690Y376450D01*
X855190Y379783D01*
G01X858040Y378700D02*
X860707D01*
X860457Y379283D01*
X860040Y379617D01*
X859457Y379783D01*
X858873Y379700D01*
X858373Y379450D01*
X858040Y378867D01*
X857873Y378367D01*
Y377867D01*
X858040Y377367D01*
X858457Y376867D01*
X858957Y376533D01*
X859540Y376450D01*
X860123Y376617D01*
X860707Y377117D01*
G01X863723Y376450D02*
Y379783D01*
G01Y379117D02*
X864140Y379450D01*
X864557Y379700D01*
X865140Y379783D01*
X865557Y379700D01*
X866057Y379450D01*
G01X869240Y378700D02*
X871907D01*
X871657Y379283D01*
X871240Y379617D01*
X870657Y379783D01*
X870073Y379700D01*
X869573Y379450D01*
X869240Y378867D01*
X869073Y378367D01*
Y377867D01*
X869240Y377367D01*
X869657Y376867D01*
X870157Y376533D01*
X870740Y376450D01*
X871323Y376617D01*
X871907Y377117D01*
G01X877590Y381450D02*
Y376450D01*
G01Y377200D02*
X877257Y376783D01*
X876757Y376533D01*
X876173Y376450D01*
X875507Y376617D01*
X875007Y377033D01*
X874673Y377533D01*
X874590Y378117D01*
X874673Y378700D01*
X875007Y379200D01*
X875507Y379617D01*
X876173Y379783D01*
X876757Y379700D01*
X877173Y379533D01*
X877590Y379200D01*
G01X885207Y379783D02*
X886207Y376450D01*
X887290Y379783D01*
X888373Y376450D01*
X889373Y379783D01*
G01X892890D02*
Y376450D01*
G01Y381117D02*
X892723Y381200D01*
Y381367D01*
X892890Y381450D01*
X893057Y381367D01*
Y381200D01*
X892890Y381117D01*
G01X898490Y381450D02*
Y376450D01*
G01X897323Y379783D02*
X899657D01*
G01X902673Y376450D02*
Y381450D01*
G01Y379033D02*
X903090Y379450D01*
X903507Y379700D01*
X904173Y379783D01*
X904673Y379700D01*
X905257Y379367D01*
X905507Y378867D01*
Y376450D01*
G01X916623Y379367D02*
X916040Y379700D01*
X915540Y379783D01*
X914873Y379617D01*
X914373Y379283D01*
X914040Y378700D01*
X913957Y378117D01*
X914040Y377533D01*
X914373Y377033D01*
X914873Y376617D01*
X915540Y376450D01*
X916123Y376617D01*
X916623Y376950D01*
G01X920890Y376450D02*
X920390Y376533D01*
X919890Y376867D01*
X919557Y377450D01*
X919390Y378117D01*
X919557Y378783D01*
X919890Y379367D01*
X920390Y379700D01*
X920890Y379783D01*
X921390Y379700D01*
X921890Y379367D01*
X922223Y378783D01*
X922307Y378117D01*
X922223Y377450D01*
X921890Y376867D01*
X921390Y376533D01*
X920890Y376450D01*
G01X924990Y374783D02*
Y379783D01*
G01Y379033D02*
X925407Y379450D01*
X925823Y379700D01*
X926490Y379783D01*
X927073Y379700D01*
X927657Y379283D01*
X927907Y378700D01*
X927990Y378117D01*
X927907Y377533D01*
X927657Y376950D01*
X927157Y376617D01*
X926490Y376450D01*
X925907Y376533D01*
X925323Y376783D01*
X924990Y377117D01*
G01X930590Y374783D02*
Y379783D01*
G01Y379033D02*
X931007Y379450D01*
X931423Y379700D01*
X932090Y379783D01*
X932673Y379700D01*
X933257Y379283D01*
X933507Y378700D01*
X933590Y378117D01*
X933507Y377533D01*
X933257Y376950D01*
X932757Y376617D01*
X932090Y376450D01*
X931507Y376533D01*
X930923Y376783D01*
X930590Y377117D01*
G01X936440Y378700D02*
X939107D01*
X938857Y379283D01*
X938440Y379617D01*
X937857Y379783D01*
X937273Y379700D01*
X936773Y379450D01*
X936440Y378867D01*
X936273Y378367D01*
Y377867D01*
X936440Y377367D01*
X936857Y376867D01*
X937357Y376533D01*
X937940Y376450D01*
X938523Y376617D01*
X939107Y377117D01*
G01X942123Y376450D02*
Y379783D01*
G01Y379117D02*
X942540Y379450D01*
X942957Y379700D01*
X943540Y379783D01*
X943957Y379700D01*
X944457Y379450D01*
G01X821500Y419500D02*
Y423750D01*
X821667Y424167D01*
X822000Y424417D01*
X822500Y424500D01*
X823000Y424333D01*
X823250Y423917D01*
G01X822250Y422500D02*
X820583D01*
G01X827600Y419500D02*
X827100Y419583D01*
X826600Y419917D01*
X826267Y420500D01*
X826100Y421167D01*
X826267Y421833D01*
X826600Y422417D01*
X827100Y422750D01*
X827600Y422833D01*
X828100Y422750D01*
X828600Y422417D01*
X828933Y421833D01*
X829017Y421167D01*
X828933Y420500D01*
X828600Y419917D01*
X828100Y419583D01*
X827600Y419500D01*
G01X833200D02*
Y424500D01*
G01X838800Y419500D02*
Y424500D01*
G01X844400Y419500D02*
X843900Y419583D01*
X843400Y419917D01*
X843067Y420500D01*
X842900Y421167D01*
X843067Y421833D01*
X843400Y422417D01*
X843900Y422750D01*
X844400Y422833D01*
X844900Y422750D01*
X845400Y422417D01*
X845733Y421833D01*
X845817Y421167D01*
X845733Y420500D01*
X845400Y419917D01*
X844900Y419583D01*
X844400Y419500D01*
G01X847917Y422833D02*
X848917Y419500D01*
X850000Y422833D01*
X851083Y419500D01*
X852083Y422833D01*
G01X861700Y422000D02*
X863367D01*
Y420500D01*
X862867Y420000D01*
X862283Y419667D01*
X861450Y419500D01*
X860617Y419667D01*
X860033Y420000D01*
X859533Y420500D01*
X859200Y421083D01*
X859033Y421750D01*
Y422333D01*
X859200Y422833D01*
X859533Y423417D01*
X860033Y423917D01*
X860533Y424250D01*
X861200Y424500D01*
X861783D01*
X862450Y424333D01*
X862950Y424000D01*
G01X865550Y421750D02*
X868217D01*
X867967Y422333D01*
X867550Y422667D01*
X866967Y422833D01*
X866383Y422750D01*
X865883Y422500D01*
X865550Y421917D01*
X865383Y421417D01*
Y420917D01*
X865550Y420417D01*
X865967Y419917D01*
X866467Y419583D01*
X867050Y419500D01*
X867633Y419667D01*
X868217Y420167D01*
G01X871233Y419500D02*
Y422833D01*
G01Y422167D02*
X871650Y422500D01*
X872067Y422750D01*
X872650Y422833D01*
X873067Y422750D01*
X873567Y422500D01*
G01X876500Y419500D02*
Y424500D01*
G01Y422000D02*
X876917Y422500D01*
X877417Y422750D01*
X877917Y422833D01*
X878667Y422667D01*
X879167Y422333D01*
X879500Y421750D01*
Y421083D01*
X879333Y420417D01*
X879000Y419917D01*
X878417Y419583D01*
X877917Y419500D01*
X877417Y419583D01*
X876917Y419833D01*
X876500Y420250D01*
G01X882350Y421750D02*
X885017D01*
X884767Y422333D01*
X884350Y422667D01*
X883767Y422833D01*
X883183Y422750D01*
X882683Y422500D01*
X882350Y421917D01*
X882183Y421417D01*
Y420917D01*
X882350Y420417D01*
X882767Y419917D01*
X883267Y419583D01*
X883850Y419500D01*
X884433Y419667D01*
X885017Y420167D01*
G01X888033Y419500D02*
Y422833D01*
G01Y422167D02*
X888450Y422500D01*
X888867Y422750D01*
X889450Y422833D01*
X889867Y422750D01*
X890367Y422500D01*
G01X901900Y419500D02*
Y422833D01*
G01Y422250D02*
X901567Y422583D01*
X901067Y422750D01*
X900483Y422833D01*
X899900Y422667D01*
X899400Y422333D01*
X899067Y421833D01*
X898900Y421167D01*
X899067Y420500D01*
X899400Y420000D01*
X899900Y419667D01*
X900483Y419500D01*
X901067Y419583D01*
X901567Y419833D01*
X901900Y420167D01*
G01X904583Y419500D02*
Y422833D01*
G01Y422000D02*
X904917Y422417D01*
X905417Y422750D01*
X906083Y422833D01*
X906667Y422750D01*
X907167Y422417D01*
X907417Y421833D01*
Y419500D01*
G01X913100Y424500D02*
Y419500D01*
G01Y420250D02*
X912767Y419833D01*
X912267Y419583D01*
X911683Y419500D01*
X911017Y419667D01*
X910517Y420083D01*
X910183Y420583D01*
X910100Y421167D01*
X910183Y421750D01*
X910517Y422250D01*
X911017Y422667D01*
X911683Y422833D01*
X912267Y422750D01*
X912683Y422583D01*
X913100Y422250D01*
G01X921300Y417833D02*
Y422833D01*
G01Y422083D02*
X921717Y422500D01*
X922133Y422750D01*
X922800Y422833D01*
X923383Y422750D01*
X923967Y422333D01*
X924217Y421750D01*
X924300Y421167D01*
X924217Y420583D01*
X923967Y420000D01*
X923467Y419667D01*
X922800Y419500D01*
X922217Y419583D01*
X921633Y419833D01*
X921300Y420167D01*
G01X928400Y419500D02*
Y424500D01*
G01X932583Y422833D02*
Y420500D01*
X932917Y419917D01*
X933417Y419583D01*
X934000Y419500D01*
X934583Y419583D01*
X935083Y419917D01*
X935417Y420500D01*
G01Y419500D02*
Y422833D01*
G01X938433Y418250D02*
X939017Y417917D01*
X939683Y417833D01*
X940267Y417917D01*
X940767Y418333D01*
X941100Y418917D01*
Y422833D01*
G01Y422167D02*
X940767Y422500D01*
X940267Y422750D01*
X939683Y422833D01*
X939017Y422667D01*
X938600Y422333D01*
X938267Y421750D01*
X938100Y421167D01*
X938183Y420667D01*
X938517Y420083D01*
X939017Y419667D01*
X939683Y419500D01*
X940183Y419583D01*
X940767Y419917D01*
X941100Y420250D01*
G01X948717Y422833D02*
X949717Y419500D01*
X950800Y422833D01*
X951883Y419500D01*
X952883Y422833D01*
G01X956400D02*
Y419500D01*
G01Y424167D02*
X956233Y424250D01*
Y424417D01*
X956400Y424500D01*
X956567Y424417D01*
Y424250D01*
X956400Y424167D01*
G01X962000Y424500D02*
Y419500D01*
G01X960833Y422833D02*
X963167D01*
G01X966183Y419500D02*
Y424500D01*
G01Y422083D02*
X966600Y422500D01*
X967017Y422750D01*
X967683Y422833D01*
X968183Y422750D01*
X968767Y422417D01*
X969017Y421917D01*
Y419500D01*
G01X977633D02*
Y422833D01*
G01Y422167D02*
X978050Y422500D01*
X978467Y422750D01*
X979050Y422833D01*
X979467Y422750D01*
X979967Y422500D01*
G01X983150Y421750D02*
X985817D01*
X985567Y422333D01*
X985150Y422667D01*
X984567Y422833D01*
X983983Y422750D01*
X983483Y422500D01*
X983150Y421917D01*
X982983Y421417D01*
Y420917D01*
X983150Y420417D01*
X983567Y419917D01*
X984067Y419583D01*
X984650Y419500D01*
X985233Y419667D01*
X985817Y420167D01*
G01X988750Y420083D02*
X989167Y419750D01*
X989750Y419500D01*
X990250D01*
X990750Y419667D01*
X991083Y419917D01*
X991250Y420250D01*
X991167Y420750D01*
X990833Y421000D01*
X989333Y421500D01*
X989000Y422083D01*
X989167Y422500D01*
X989500Y422750D01*
X990000Y422833D01*
X990500Y422750D01*
X991000Y422500D01*
G01X995600Y422833D02*
Y419500D01*
G01Y424167D02*
X995433Y424250D01*
Y424417D01*
X995600Y424500D01*
X995767Y424417D01*
Y424250D01*
X995600Y424167D01*
G01X999783Y419500D02*
Y422833D01*
G01Y422000D02*
X1000117Y422417D01*
X1000617Y422750D01*
X1001283Y422833D01*
X1001867Y422750D01*
X1002367Y422417D01*
X1002617Y421833D01*
Y419500D01*
G01X819590Y389810D02*
Y394060D01*
X819757Y394477D01*
X820090Y394727D01*
X820590Y394810D01*
X821090Y394643D01*
X821340Y394227D01*
G01X820340Y392810D02*
X818673D01*
G01X825690Y389810D02*
X825190Y389893D01*
X824690Y390227D01*
X824357Y390810D01*
X824190Y391477D01*
X824357Y392143D01*
X824690Y392727D01*
X825190Y393060D01*
X825690Y393143D01*
X826190Y393060D01*
X826690Y392727D01*
X827023Y392143D01*
X827107Y391477D01*
X827023Y390810D01*
X826690Y390227D01*
X826190Y389893D01*
X825690Y389810D01*
G01X831290D02*
Y394810D01*
G01X836890Y389810D02*
Y394810D01*
G01X842490Y389810D02*
X841990Y389893D01*
X841490Y390227D01*
X841157Y390810D01*
X840990Y391477D01*
X841157Y392143D01*
X841490Y392727D01*
X841990Y393060D01*
X842490Y393143D01*
X842990Y393060D01*
X843490Y392727D01*
X843823Y392143D01*
X843907Y391477D01*
X843823Y390810D01*
X843490Y390227D01*
X842990Y389893D01*
X842490Y389810D01*
G01X846007Y393143D02*
X847007Y389810D01*
X848090Y393143D01*
X849173Y389810D01*
X850173Y393143D01*
G01X859790Y392310D02*
X861457D01*
Y390810D01*
X860957Y390310D01*
X860373Y389977D01*
X859540Y389810D01*
X858707Y389977D01*
X858123Y390310D01*
X857623Y390810D01*
X857290Y391393D01*
X857123Y392060D01*
Y392643D01*
X857290Y393143D01*
X857623Y393727D01*
X858123Y394227D01*
X858623Y394560D01*
X859290Y394810D01*
X859873D01*
X860540Y394643D01*
X861040Y394310D01*
G01X863640Y392060D02*
X866307D01*
X866057Y392643D01*
X865640Y392977D01*
X865057Y393143D01*
X864473Y393060D01*
X863973Y392810D01*
X863640Y392227D01*
X863473Y391727D01*
Y391227D01*
X863640Y390727D01*
X864057Y390227D01*
X864557Y389893D01*
X865140Y389810D01*
X865723Y389977D01*
X866307Y390477D01*
G01X869323Y389810D02*
Y393143D01*
G01Y392477D02*
X869740Y392810D01*
X870157Y393060D01*
X870740Y393143D01*
X871157Y393060D01*
X871657Y392810D01*
G01X874590Y389810D02*
Y394810D01*
G01Y392310D02*
X875007Y392810D01*
X875507Y393060D01*
X876007Y393143D01*
X876757Y392977D01*
X877257Y392643D01*
X877590Y392060D01*
Y391393D01*
X877423Y390727D01*
X877090Y390227D01*
X876507Y389893D01*
X876007Y389810D01*
X875507Y389893D01*
X875007Y390143D01*
X874590Y390560D01*
G01X880440Y392060D02*
X883107D01*
X882857Y392643D01*
X882440Y392977D01*
X881857Y393143D01*
X881273Y393060D01*
X880773Y392810D01*
X880440Y392227D01*
X880273Y391727D01*
Y391227D01*
X880440Y390727D01*
X880857Y390227D01*
X881357Y389893D01*
X881940Y389810D01*
X882523Y389977D01*
X883107Y390477D01*
G01X886123Y389810D02*
Y393143D01*
G01Y392477D02*
X886540Y392810D01*
X886957Y393060D01*
X887540Y393143D01*
X887957Y393060D01*
X888457Y392810D01*
G01X899990Y389810D02*
Y393143D01*
G01Y392560D02*
X899657Y392893D01*
X899157Y393060D01*
X898573Y393143D01*
X897990Y392977D01*
X897490Y392643D01*
X897157Y392143D01*
X896990Y391477D01*
X897157Y390810D01*
X897490Y390310D01*
X897990Y389977D01*
X898573Y389810D01*
X899157Y389893D01*
X899657Y390143D01*
X899990Y390477D01*
G01X902673Y389810D02*
Y393143D01*
G01Y392310D02*
X903007Y392727D01*
X903507Y393060D01*
X904173Y393143D01*
X904757Y393060D01*
X905257Y392727D01*
X905507Y392143D01*
Y389810D01*
G01X911190Y394810D02*
Y389810D01*
G01Y390560D02*
X910857Y390143D01*
X910357Y389893D01*
X909773Y389810D01*
X909107Y389977D01*
X908607Y390393D01*
X908273Y390893D01*
X908190Y391477D01*
X908273Y392060D01*
X908607Y392560D01*
X909107Y392977D01*
X909773Y393143D01*
X910357Y393060D01*
X910773Y392893D01*
X911190Y392560D01*
G01X919390Y388143D02*
Y393143D01*
G01Y392393D02*
X919807Y392810D01*
X920223Y393060D01*
X920890Y393143D01*
X921473Y393060D01*
X922057Y392643D01*
X922307Y392060D01*
X922390Y391477D01*
X922307Y390893D01*
X922057Y390310D01*
X921557Y389977D01*
X920890Y389810D01*
X920307Y389893D01*
X919723Y390143D01*
X919390Y390477D01*
G01X926490Y389810D02*
Y394810D01*
G01X930673Y393143D02*
Y390810D01*
X931007Y390227D01*
X931507Y389893D01*
X932090Y389810D01*
X932673Y389893D01*
X933173Y390227D01*
X933507Y390810D01*
G01Y389810D02*
Y393143D01*
G01X936523Y388560D02*
X937107Y388227D01*
X937773Y388143D01*
X938357Y388227D01*
X938857Y388643D01*
X939190Y389227D01*
Y393143D01*
G01Y392477D02*
X938857Y392810D01*
X938357Y393060D01*
X937773Y393143D01*
X937107Y392977D01*
X936690Y392643D01*
X936357Y392060D01*
X936190Y391477D01*
X936273Y390977D01*
X936607Y390393D01*
X937107Y389977D01*
X937773Y389810D01*
X938273Y389893D01*
X938857Y390227D01*
X939190Y390560D01*
G01X946807Y393143D02*
X947807Y389810D01*
X948890Y393143D01*
X949973Y389810D01*
X950973Y393143D01*
G01X954490D02*
Y389810D01*
G01Y394477D02*
X954323Y394560D01*
Y394727D01*
X954490Y394810D01*
X954657Y394727D01*
Y394560D01*
X954490Y394477D01*
G01X960090Y394810D02*
Y389810D01*
G01X958923Y393143D02*
X961257D01*
G01X964273Y389810D02*
Y394810D01*
G01Y392393D02*
X964690Y392810D01*
X965107Y393060D01*
X965773Y393143D01*
X966273Y393060D01*
X966857Y392727D01*
X967107Y392227D01*
Y389810D01*
G01X975723D02*
Y393143D01*
G01Y392477D02*
X976140Y392810D01*
X976557Y393060D01*
X977140Y393143D01*
X977557Y393060D01*
X978057Y392810D01*
G01X981240Y392060D02*
X983907D01*
X983657Y392643D01*
X983240Y392977D01*
X982657Y393143D01*
X982073Y393060D01*
X981573Y392810D01*
X981240Y392227D01*
X981073Y391727D01*
Y391227D01*
X981240Y390727D01*
X981657Y390227D01*
X982157Y389893D01*
X982740Y389810D01*
X983323Y389977D01*
X983907Y390477D01*
G01X986840Y390393D02*
X987257Y390060D01*
X987840Y389810D01*
X988340D01*
X988840Y389977D01*
X989173Y390227D01*
X989340Y390560D01*
X989257Y391060D01*
X988923Y391310D01*
X987423Y391810D01*
X987090Y392393D01*
X987257Y392810D01*
X987590Y393060D01*
X988090Y393143D01*
X988590Y393060D01*
X989090Y392810D01*
G01X993690Y393143D02*
Y389810D01*
G01Y394477D02*
X993523Y394560D01*
Y394727D01*
X993690Y394810D01*
X993857Y394727D01*
Y394560D01*
X993690Y394477D01*
G01X997873Y389810D02*
Y393143D01*
G01Y392310D02*
X998207Y392727D01*
X998707Y393060D01*
X999373Y393143D01*
X999957Y393060D01*
X1000457Y392727D01*
X1000707Y392143D01*
Y389810D01*
G01X812000Y604500D02*
Y366000D01*
G01X823500Y455500D02*
Y458833D01*
G01Y458250D02*
X823167Y458583D01*
X822667Y458750D01*
X822083Y458833D01*
X821500Y458667D01*
X821000Y458333D01*
X820667Y457833D01*
X820500Y457167D01*
X820667Y456500D01*
X821000Y456000D01*
X821500Y455667D01*
X822083Y455500D01*
X822667Y455583D01*
X823167Y455833D01*
X823500Y456167D01*
G01X826183Y455500D02*
Y458833D01*
G01Y458000D02*
X826517Y458417D01*
X827017Y458750D01*
X827683Y458833D01*
X828267Y458750D01*
X828767Y458417D01*
X829017Y457833D01*
Y455500D01*
G01X834700Y460500D02*
Y455500D01*
G01Y456250D02*
X834367Y455833D01*
X833867Y455583D01*
X833283Y455500D01*
X832617Y455667D01*
X832117Y456083D01*
X831783Y456583D01*
X831700Y457167D01*
X831783Y457750D01*
X832117Y458250D01*
X832617Y458667D01*
X833283Y458833D01*
X833867Y458750D01*
X834283Y458583D01*
X834700Y458250D01*
G01X842900Y455500D02*
Y460500D01*
G01Y458000D02*
X843317Y458500D01*
X843817Y458750D01*
X844317Y458833D01*
X845067Y458667D01*
X845567Y458333D01*
X845900Y457750D01*
Y457083D01*
X845733Y456417D01*
X845400Y455917D01*
X844817Y455583D01*
X844317Y455500D01*
X843817Y455583D01*
X843317Y455833D01*
X842900Y456250D01*
G01X850000Y455500D02*
X849500Y455583D01*
X849000Y455917D01*
X848667Y456500D01*
X848500Y457167D01*
X848667Y457833D01*
X849000Y458417D01*
X849500Y458750D01*
X850000Y458833D01*
X850500Y458750D01*
X851000Y458417D01*
X851333Y457833D01*
X851417Y457167D01*
X851333Y456500D01*
X851000Y455917D01*
X850500Y455583D01*
X850000Y455500D01*
G01X855600Y460500D02*
Y455500D01*
G01X854433Y458833D02*
X856767D01*
G01X861200Y460500D02*
Y455500D01*
G01X860033Y458833D02*
X862367D01*
G01X866800Y455500D02*
X866300Y455583D01*
X865800Y455917D01*
X865467Y456500D01*
X865300Y457167D01*
X865467Y457833D01*
X865800Y458417D01*
X866300Y458750D01*
X866800Y458833D01*
X867300Y458750D01*
X867800Y458417D01*
X868133Y457833D01*
X868217Y457167D01*
X868133Y456500D01*
X867800Y455917D01*
X867300Y455583D01*
X866800Y455500D01*
G01X869900D02*
Y458833D01*
G01Y457917D02*
X870150Y458333D01*
X870567Y458667D01*
X871150Y458833D01*
X871733Y458667D01*
X872150Y458333D01*
X872400Y457917D01*
Y455500D01*
G01Y457917D02*
X872650Y458333D01*
X873067Y458667D01*
X873650Y458833D01*
X874233Y458667D01*
X874650Y458333D01*
X874900Y457833D01*
Y455500D01*
G01X882350Y456083D02*
X882767Y455750D01*
X883350Y455500D01*
X883850D01*
X884350Y455667D01*
X884683Y455917D01*
X884850Y456250D01*
X884767Y456750D01*
X884433Y457000D01*
X882933Y457500D01*
X882600Y458083D01*
X882767Y458500D01*
X883100Y458750D01*
X883600Y458833D01*
X884100Y458750D01*
X884600Y458500D01*
G01X889200Y458833D02*
Y455500D01*
G01Y460167D02*
X889033Y460250D01*
Y460417D01*
X889200Y460500D01*
X889367Y460417D01*
Y460250D01*
X889200Y460167D01*
G01X896300Y460500D02*
Y455500D01*
G01Y456250D02*
X895967Y455833D01*
X895467Y455583D01*
X894883Y455500D01*
X894217Y455667D01*
X893717Y456083D01*
X893383Y456583D01*
X893300Y457167D01*
X893383Y457750D01*
X893717Y458250D01*
X894217Y458667D01*
X894883Y458833D01*
X895467Y458750D01*
X895883Y458583D01*
X896300Y458250D01*
G01X899150Y457750D02*
X901817D01*
X901567Y458333D01*
X901150Y458667D01*
X900567Y458833D01*
X899983Y458750D01*
X899483Y458500D01*
X899150Y457917D01*
X898983Y457417D01*
Y456917D01*
X899150Y456417D01*
X899567Y455917D01*
X900067Y455583D01*
X900650Y455500D01*
X901233Y455667D01*
X901817Y456167D01*
G01X819917Y470833D02*
X820917Y467500D01*
X822000Y470833D01*
X823083Y467500D01*
X824083Y470833D01*
G01X827600D02*
Y467500D01*
G01Y472167D02*
X827433Y472250D01*
Y472417D01*
X827600Y472500D01*
X827767Y472417D01*
Y472250D01*
X827600Y472167D01*
G01X833200Y472500D02*
Y467500D01*
G01X832033Y470833D02*
X834367D01*
G01X837383Y467500D02*
Y472500D01*
G01Y470083D02*
X837800Y470500D01*
X838217Y470750D01*
X838883Y470833D01*
X839383Y470750D01*
X839967Y470417D01*
X840217Y469917D01*
Y467500D01*
G01X844400D02*
X843900Y467583D01*
X843400Y467917D01*
X843067Y468500D01*
X842900Y469167D01*
X843067Y469833D01*
X843400Y470417D01*
X843900Y470750D01*
X844400Y470833D01*
X844900Y470750D01*
X845400Y470417D01*
X845733Y469833D01*
X845817Y469167D01*
X845733Y468500D01*
X845400Y467917D01*
X844900Y467583D01*
X844400Y467500D01*
G01X848583Y470833D02*
Y468500D01*
X848917Y467917D01*
X849417Y467583D01*
X850000Y467500D01*
X850583Y467583D01*
X851083Y467917D01*
X851417Y468500D01*
G01Y467500D02*
Y470833D01*
G01X855600Y472500D02*
Y467500D01*
G01X854433Y470833D02*
X856767D01*
G01X865550Y468083D02*
X865967Y467750D01*
X866550Y467500D01*
X867050D01*
X867550Y467667D01*
X867883Y467917D01*
X868050Y468250D01*
X867967Y468750D01*
X867633Y469000D01*
X866133Y469500D01*
X865800Y470083D01*
X865967Y470500D01*
X866300Y470750D01*
X866800Y470833D01*
X867300Y470750D01*
X867800Y470500D01*
G01X872400Y467500D02*
X871900Y467583D01*
X871400Y467917D01*
X871067Y468500D01*
X870900Y469167D01*
X871067Y469833D01*
X871400Y470417D01*
X871900Y470750D01*
X872400Y470833D01*
X872900Y470750D01*
X873400Y470417D01*
X873733Y469833D01*
X873817Y469167D01*
X873733Y468500D01*
X873400Y467917D01*
X872900Y467583D01*
X872400Y467500D01*
G01X878000D02*
Y472500D01*
G01X885100D02*
Y467500D01*
G01Y468250D02*
X884767Y467833D01*
X884267Y467583D01*
X883683Y467500D01*
X883017Y467667D01*
X882517Y468083D01*
X882183Y468583D01*
X882100Y469167D01*
X882183Y469750D01*
X882517Y470250D01*
X883017Y470667D01*
X883683Y470833D01*
X884267Y470750D01*
X884683Y470583D01*
X885100Y470250D01*
G01X887950Y469750D02*
X890617D01*
X890367Y470333D01*
X889950Y470667D01*
X889367Y470833D01*
X888783Y470750D01*
X888283Y470500D01*
X887950Y469917D01*
X887783Y469417D01*
Y468917D01*
X887950Y468417D01*
X888367Y467917D01*
X888867Y467583D01*
X889450Y467500D01*
X890033Y467667D01*
X890617Y468167D01*
G01X893633Y467500D02*
Y470833D01*
G01Y470167D02*
X894050Y470500D01*
X894467Y470750D01*
X895050Y470833D01*
X895467Y470750D01*
X895967Y470500D01*
G01X903500Y467500D02*
Y470833D01*
G01Y469917D02*
X903750Y470333D01*
X904167Y470667D01*
X904750Y470833D01*
X905333Y470667D01*
X905750Y470333D01*
X906000Y469917D01*
Y467500D01*
G01Y469917D02*
X906250Y470333D01*
X906667Y470667D01*
X907250Y470833D01*
X907833Y470667D01*
X908250Y470333D01*
X908500Y469833D01*
Y467500D01*
G01X913100D02*
Y470833D01*
G01Y470250D02*
X912767Y470583D01*
X912267Y470750D01*
X911683Y470833D01*
X911100Y470667D01*
X910600Y470333D01*
X910267Y469833D01*
X910100Y469167D01*
X910267Y468500D01*
X910600Y468000D01*
X911100Y467667D01*
X911683Y467500D01*
X912267Y467583D01*
X912767Y467833D01*
X913100Y468167D01*
G01X915950Y468083D02*
X916367Y467750D01*
X916950Y467500D01*
X917450D01*
X917950Y467667D01*
X918283Y467917D01*
X918450Y468250D01*
X918367Y468750D01*
X918033Y469000D01*
X916533Y469500D01*
X916200Y470083D01*
X916367Y470500D01*
X916700Y470750D01*
X917200Y470833D01*
X917700Y470750D01*
X918200Y470500D01*
G01X921383Y467500D02*
Y472500D01*
G01X924050Y470833D02*
X921383Y468917D01*
G01X922467Y469667D02*
X924217Y467500D01*
G01X932500Y465833D02*
Y470833D01*
G01Y470083D02*
X932917Y470500D01*
X933333Y470750D01*
X934000Y470833D01*
X934583Y470750D01*
X935167Y470333D01*
X935417Y469750D01*
X935500Y469167D01*
X935417Y468583D01*
X935167Y468000D01*
X934667Y467667D01*
X934000Y467500D01*
X933417Y467583D01*
X932833Y467833D01*
X932500Y468167D01*
G01X941100Y467500D02*
Y470833D01*
G01Y470250D02*
X940767Y470583D01*
X940267Y470750D01*
X939683Y470833D01*
X939100Y470667D01*
X938600Y470333D01*
X938267Y469833D01*
X938100Y469167D01*
X938267Y468500D01*
X938600Y468000D01*
X939100Y467667D01*
X939683Y467500D01*
X940267Y467583D01*
X940767Y467833D01*
X941100Y468167D01*
G01X946700Y472500D02*
Y467500D01*
G01Y468250D02*
X946367Y467833D01*
X945867Y467583D01*
X945283Y467500D01*
X944617Y467667D01*
X944117Y468083D01*
X943783Y468583D01*
X943700Y469167D01*
X943783Y469750D01*
X944117Y470250D01*
X944617Y470667D01*
X945283Y470833D01*
X945867Y470750D01*
X946283Y470583D01*
X946700Y470250D01*
G01X956400Y467500D02*
X955900Y467583D01*
X955400Y467917D01*
X955067Y468500D01*
X954900Y469167D01*
X955067Y469833D01*
X955400Y470417D01*
X955900Y470750D01*
X956400Y470833D01*
X956900Y470750D01*
X957400Y470417D01*
X957733Y469833D01*
X957817Y469167D01*
X957733Y468500D01*
X957400Y467917D01*
X956900Y467583D01*
X956400Y467500D01*
G01X960583D02*
Y470833D01*
G01Y470000D02*
X960917Y470417D01*
X961417Y470750D01*
X962083Y470833D01*
X962667Y470750D01*
X963167Y470417D01*
X963417Y469833D01*
Y467500D01*
G01X973200Y472500D02*
Y467500D01*
G01X972033Y470833D02*
X974367D01*
G01X978800Y467500D02*
X978300Y467583D01*
X977800Y467917D01*
X977467Y468500D01*
X977300Y469167D01*
X977467Y469833D01*
X977800Y470417D01*
X978300Y470750D01*
X978800Y470833D01*
X979300Y470750D01*
X979800Y470417D01*
X980133Y469833D01*
X980217Y469167D01*
X980133Y468500D01*
X979800Y467917D01*
X979300Y467583D01*
X978800Y467500D01*
G01X982900Y465833D02*
Y470833D01*
G01Y470083D02*
X983317Y470500D01*
X983733Y470750D01*
X984400Y470833D01*
X984983Y470750D01*
X985567Y470333D01*
X985817Y469750D01*
X985900Y469167D01*
X985817Y468583D01*
X985567Y468000D01*
X985067Y467667D01*
X984400Y467500D01*
X983817Y467583D01*
X983233Y467833D01*
X982900Y468167D01*
G01X821500Y440500D02*
Y444750D01*
X821667Y445167D01*
X822000Y445417D01*
X822500Y445500D01*
X823000Y445333D01*
X823250Y444917D01*
G01X822250Y443500D02*
X820583D01*
G01X827600Y440500D02*
X827100Y440583D01*
X826600Y440917D01*
X826267Y441500D01*
X826100Y442167D01*
X826267Y442833D01*
X826600Y443417D01*
X827100Y443750D01*
X827600Y443833D01*
X828100Y443750D01*
X828600Y443417D01*
X828933Y442833D01*
X829017Y442167D01*
X828933Y441500D01*
X828600Y440917D01*
X828100Y440583D01*
X827600Y440500D01*
G01X833200D02*
Y445500D01*
G01X838800Y440500D02*
Y445500D01*
G01X844400Y440500D02*
X843900Y440583D01*
X843400Y440917D01*
X843067Y441500D01*
X842900Y442167D01*
X843067Y442833D01*
X843400Y443417D01*
X843900Y443750D01*
X844400Y443833D01*
X844900Y443750D01*
X845400Y443417D01*
X845733Y442833D01*
X845817Y442167D01*
X845733Y441500D01*
X845400Y440917D01*
X844900Y440583D01*
X844400Y440500D01*
G01X847917Y443833D02*
X848917Y440500D01*
X850000Y443833D01*
X851083Y440500D01*
X852083Y443833D01*
G01X861700Y443000D02*
X863367D01*
Y441500D01*
X862867Y441000D01*
X862283Y440667D01*
X861450Y440500D01*
X860617Y440667D01*
X860033Y441000D01*
X859533Y441500D01*
X859200Y442083D01*
X859033Y442750D01*
Y443333D01*
X859200Y443833D01*
X859533Y444417D01*
X860033Y444917D01*
X860533Y445250D01*
X861200Y445500D01*
X861783D01*
X862450Y445333D01*
X862950Y445000D01*
G01X865550Y442750D02*
X868217D01*
X867967Y443333D01*
X867550Y443667D01*
X866967Y443833D01*
X866383Y443750D01*
X865883Y443500D01*
X865550Y442917D01*
X865383Y442417D01*
Y441917D01*
X865550Y441417D01*
X865967Y440917D01*
X866467Y440583D01*
X867050Y440500D01*
X867633Y440667D01*
X868217Y441167D01*
G01X871233Y440500D02*
Y443833D01*
G01Y443167D02*
X871650Y443500D01*
X872067Y443750D01*
X872650Y443833D01*
X873067Y443750D01*
X873567Y443500D01*
G01X876500Y440500D02*
Y445500D01*
G01Y443000D02*
X876917Y443500D01*
X877417Y443750D01*
X877917Y443833D01*
X878667Y443667D01*
X879167Y443333D01*
X879500Y442750D01*
Y442083D01*
X879333Y441417D01*
X879000Y440917D01*
X878417Y440583D01*
X877917Y440500D01*
X877417Y440583D01*
X876917Y440833D01*
X876500Y441250D01*
G01X882350Y442750D02*
X885017D01*
X884767Y443333D01*
X884350Y443667D01*
X883767Y443833D01*
X883183Y443750D01*
X882683Y443500D01*
X882350Y442917D01*
X882183Y442417D01*
Y441917D01*
X882350Y441417D01*
X882767Y440917D01*
X883267Y440583D01*
X883850Y440500D01*
X884433Y440667D01*
X885017Y441167D01*
G01X888033Y440500D02*
Y443833D01*
G01Y443167D02*
X888450Y443500D01*
X888867Y443750D01*
X889450Y443833D01*
X889867Y443750D01*
X890367Y443500D01*
G01X823500Y455500D02*
Y458833D01*
G01Y458250D02*
X823167Y458583D01*
X822667Y458750D01*
X822083Y458833D01*
X821500Y458667D01*
X821000Y458333D01*
X820667Y457833D01*
X820500Y457167D01*
X820667Y456500D01*
X821000Y456000D01*
X821500Y455667D01*
X822083Y455500D01*
X822667Y455583D01*
X823167Y455833D01*
X823500Y456167D01*
G01X826183Y455500D02*
Y458833D01*
G01Y458000D02*
X826517Y458417D01*
X827017Y458750D01*
X827683Y458833D01*
X828267Y458750D01*
X828767Y458417D01*
X829017Y457833D01*
Y455500D01*
G01X834700Y460500D02*
Y455500D01*
G01Y456250D02*
X834367Y455833D01*
X833867Y455583D01*
X833283Y455500D01*
X832617Y455667D01*
X832117Y456083D01*
X831783Y456583D01*
X831700Y457167D01*
X831783Y457750D01*
X832117Y458250D01*
X832617Y458667D01*
X833283Y458833D01*
X833867Y458750D01*
X834283Y458583D01*
X834700Y458250D01*
G01X842900Y455500D02*
Y460500D01*
G01Y458000D02*
X843317Y458500D01*
X843817Y458750D01*
X844317Y458833D01*
X845067Y458667D01*
X845567Y458333D01*
X845900Y457750D01*
Y457083D01*
X845733Y456417D01*
X845400Y455917D01*
X844817Y455583D01*
X844317Y455500D01*
X843817Y455583D01*
X843317Y455833D01*
X842900Y456250D01*
G01X850000Y455500D02*
X849500Y455583D01*
X849000Y455917D01*
X848667Y456500D01*
X848500Y457167D01*
X848667Y457833D01*
X849000Y458417D01*
X849500Y458750D01*
X850000Y458833D01*
X850500Y458750D01*
X851000Y458417D01*
X851333Y457833D01*
X851417Y457167D01*
X851333Y456500D01*
X851000Y455917D01*
X850500Y455583D01*
X850000Y455500D01*
G01X855600Y460500D02*
Y455500D01*
G01X854433Y458833D02*
X856767D01*
G01X861200Y460500D02*
Y455500D01*
G01X860033Y458833D02*
X862367D01*
G01X866800Y455500D02*
X866300Y455583D01*
X865800Y455917D01*
X865467Y456500D01*
X865300Y457167D01*
X865467Y457833D01*
X865800Y458417D01*
X866300Y458750D01*
X866800Y458833D01*
X867300Y458750D01*
X867800Y458417D01*
X868133Y457833D01*
X868217Y457167D01*
X868133Y456500D01*
X867800Y455917D01*
X867300Y455583D01*
X866800Y455500D01*
G01X869900D02*
Y458833D01*
G01Y457917D02*
X870150Y458333D01*
X870567Y458667D01*
X871150Y458833D01*
X871733Y458667D01*
X872150Y458333D01*
X872400Y457917D01*
Y455500D01*
G01Y457917D02*
X872650Y458333D01*
X873067Y458667D01*
X873650Y458833D01*
X874233Y458667D01*
X874650Y458333D01*
X874900Y457833D01*
Y455500D01*
G01X882350Y456083D02*
X882767Y455750D01*
X883350Y455500D01*
X883850D01*
X884350Y455667D01*
X884683Y455917D01*
X884850Y456250D01*
X884767Y456750D01*
X884433Y457000D01*
X882933Y457500D01*
X882600Y458083D01*
X882767Y458500D01*
X883100Y458750D01*
X883600Y458833D01*
X884100Y458750D01*
X884600Y458500D01*
G01X889200Y458833D02*
Y455500D01*
G01Y460167D02*
X889033Y460250D01*
Y460417D01*
X889200Y460500D01*
X889367Y460417D01*
Y460250D01*
X889200Y460167D01*
G01X896300Y460500D02*
Y455500D01*
G01Y456250D02*
X895967Y455833D01*
X895467Y455583D01*
X894883Y455500D01*
X894217Y455667D01*
X893717Y456083D01*
X893383Y456583D01*
X893300Y457167D01*
X893383Y457750D01*
X893717Y458250D01*
X894217Y458667D01*
X894883Y458833D01*
X895467Y458750D01*
X895883Y458583D01*
X896300Y458250D01*
G01X899150Y457750D02*
X901817D01*
X901567Y458333D01*
X901150Y458667D01*
X900567Y458833D01*
X899983Y458750D01*
X899483Y458500D01*
X899150Y457917D01*
X898983Y457417D01*
Y456917D01*
X899150Y456417D01*
X899567Y455917D01*
X900067Y455583D01*
X900650Y455500D01*
X901233Y455667D01*
X901817Y456167D01*
G01X819917Y470833D02*
X820917Y467500D01*
X822000Y470833D01*
X823083Y467500D01*
X824083Y470833D01*
G01X827600D02*
Y467500D01*
G01Y472167D02*
X827433Y472250D01*
Y472417D01*
X827600Y472500D01*
X827767Y472417D01*
Y472250D01*
X827600Y472167D01*
G01X833200Y472500D02*
Y467500D01*
G01X832033Y470833D02*
X834367D01*
G01X837383Y467500D02*
Y472500D01*
G01Y470083D02*
X837800Y470500D01*
X838217Y470750D01*
X838883Y470833D01*
X839383Y470750D01*
X839967Y470417D01*
X840217Y469917D01*
Y467500D01*
G01X844400D02*
X843900Y467583D01*
X843400Y467917D01*
X843067Y468500D01*
X842900Y469167D01*
X843067Y469833D01*
X843400Y470417D01*
X843900Y470750D01*
X844400Y470833D01*
X844900Y470750D01*
X845400Y470417D01*
X845733Y469833D01*
X845817Y469167D01*
X845733Y468500D01*
X845400Y467917D01*
X844900Y467583D01*
X844400Y467500D01*
G01X848583Y470833D02*
Y468500D01*
X848917Y467917D01*
X849417Y467583D01*
X850000Y467500D01*
X850583Y467583D01*
X851083Y467917D01*
X851417Y468500D01*
G01Y467500D02*
Y470833D01*
G01X855600Y472500D02*
Y467500D01*
G01X854433Y470833D02*
X856767D01*
G01X865550Y468083D02*
X865967Y467750D01*
X866550Y467500D01*
X867050D01*
X867550Y467667D01*
X867883Y467917D01*
X868050Y468250D01*
X867967Y468750D01*
X867633Y469000D01*
X866133Y469500D01*
X865800Y470083D01*
X865967Y470500D01*
X866300Y470750D01*
X866800Y470833D01*
X867300Y470750D01*
X867800Y470500D01*
G01X872400Y467500D02*
X871900Y467583D01*
X871400Y467917D01*
X871067Y468500D01*
X870900Y469167D01*
X871067Y469833D01*
X871400Y470417D01*
X871900Y470750D01*
X872400Y470833D01*
X872900Y470750D01*
X873400Y470417D01*
X873733Y469833D01*
X873817Y469167D01*
X873733Y468500D01*
X873400Y467917D01*
X872900Y467583D01*
X872400Y467500D01*
G01X878000D02*
Y472500D01*
G01X885100D02*
Y467500D01*
G01Y468250D02*
X884767Y467833D01*
X884267Y467583D01*
X883683Y467500D01*
X883017Y467667D01*
X882517Y468083D01*
X882183Y468583D01*
X882100Y469167D01*
X882183Y469750D01*
X882517Y470250D01*
X883017Y470667D01*
X883683Y470833D01*
X884267Y470750D01*
X884683Y470583D01*
X885100Y470250D01*
G01X887950Y469750D02*
X890617D01*
X890367Y470333D01*
X889950Y470667D01*
X889367Y470833D01*
X888783Y470750D01*
X888283Y470500D01*
X887950Y469917D01*
X887783Y469417D01*
Y468917D01*
X887950Y468417D01*
X888367Y467917D01*
X888867Y467583D01*
X889450Y467500D01*
X890033Y467667D01*
X890617Y468167D01*
G01X893633Y467500D02*
Y470833D01*
G01Y470167D02*
X894050Y470500D01*
X894467Y470750D01*
X895050Y470833D01*
X895467Y470750D01*
X895967Y470500D01*
G01X903500Y467500D02*
Y470833D01*
G01Y469917D02*
X903750Y470333D01*
X904167Y470667D01*
X904750Y470833D01*
X905333Y470667D01*
X905750Y470333D01*
X906000Y469917D01*
Y467500D01*
G01Y469917D02*
X906250Y470333D01*
X906667Y470667D01*
X907250Y470833D01*
X907833Y470667D01*
X908250Y470333D01*
X908500Y469833D01*
Y467500D01*
G01X913100D02*
Y470833D01*
G01Y470250D02*
X912767Y470583D01*
X912267Y470750D01*
X911683Y470833D01*
X911100Y470667D01*
X910600Y470333D01*
X910267Y469833D01*
X910100Y469167D01*
X910267Y468500D01*
X910600Y468000D01*
X911100Y467667D01*
X911683Y467500D01*
X912267Y467583D01*
X912767Y467833D01*
X913100Y468167D01*
G01X915950Y468083D02*
X916367Y467750D01*
X916950Y467500D01*
X917450D01*
X917950Y467667D01*
X918283Y467917D01*
X918450Y468250D01*
X918367Y468750D01*
X918033Y469000D01*
X916533Y469500D01*
X916200Y470083D01*
X916367Y470500D01*
X916700Y470750D01*
X917200Y470833D01*
X917700Y470750D01*
X918200Y470500D01*
G01X921383Y467500D02*
Y472500D01*
G01X924050Y470833D02*
X921383Y468917D01*
G01X922467Y469667D02*
X924217Y467500D01*
G01X932500Y465833D02*
Y470833D01*
G01Y470083D02*
X932917Y470500D01*
X933333Y470750D01*
X934000Y470833D01*
X934583Y470750D01*
X935167Y470333D01*
X935417Y469750D01*
X935500Y469167D01*
X935417Y468583D01*
X935167Y468000D01*
X934667Y467667D01*
X934000Y467500D01*
X933417Y467583D01*
X932833Y467833D01*
X932500Y468167D01*
G01X941100Y467500D02*
Y470833D01*
G01Y470250D02*
X940767Y470583D01*
X940267Y470750D01*
X939683Y470833D01*
X939100Y470667D01*
X938600Y470333D01*
X938267Y469833D01*
X938100Y469167D01*
X938267Y468500D01*
X938600Y468000D01*
X939100Y467667D01*
X939683Y467500D01*
X940267Y467583D01*
X940767Y467833D01*
X941100Y468167D01*
G01X946700Y472500D02*
Y467500D01*
G01Y468250D02*
X946367Y467833D01*
X945867Y467583D01*
X945283Y467500D01*
X944617Y467667D01*
X944117Y468083D01*
X943783Y468583D01*
X943700Y469167D01*
X943783Y469750D01*
X944117Y470250D01*
X944617Y470667D01*
X945283Y470833D01*
X945867Y470750D01*
X946283Y470583D01*
X946700Y470250D01*
G01X956400Y467500D02*
X955900Y467583D01*
X955400Y467917D01*
X955067Y468500D01*
X954900Y469167D01*
X955067Y469833D01*
X955400Y470417D01*
X955900Y470750D01*
X956400Y470833D01*
X956900Y470750D01*
X957400Y470417D01*
X957733Y469833D01*
X957817Y469167D01*
X957733Y468500D01*
X957400Y467917D01*
X956900Y467583D01*
X956400Y467500D01*
G01X960583D02*
Y470833D01*
G01Y470000D02*
X960917Y470417D01*
X961417Y470750D01*
X962083Y470833D01*
X962667Y470750D01*
X963167Y470417D01*
X963417Y469833D01*
Y467500D01*
G01X973200Y472500D02*
Y467500D01*
G01X972033Y470833D02*
X974367D01*
G01X978800Y467500D02*
X978300Y467583D01*
X977800Y467917D01*
X977467Y468500D01*
X977300Y469167D01*
X977467Y469833D01*
X977800Y470417D01*
X978300Y470750D01*
X978800Y470833D01*
X979300Y470750D01*
X979800Y470417D01*
X980133Y469833D01*
X980217Y469167D01*
X980133Y468500D01*
X979800Y467917D01*
X979300Y467583D01*
X978800Y467500D01*
G01X982900Y465833D02*
Y470833D01*
G01Y470083D02*
X983317Y470500D01*
X983733Y470750D01*
X984400Y470833D01*
X984983Y470750D01*
X985567Y470333D01*
X985817Y469750D01*
X985900Y469167D01*
X985817Y468583D01*
X985567Y468000D01*
X985067Y467667D01*
X984400Y467500D01*
X983817Y467583D01*
X983233Y467833D01*
X982900Y468167D01*
G01X821500Y440500D02*
Y444750D01*
X821667Y445167D01*
X822000Y445417D01*
X822500Y445500D01*
X823000Y445333D01*
X823250Y444917D01*
G01X822250Y443500D02*
X820583D01*
G01X827600Y440500D02*
X827100Y440583D01*
X826600Y440917D01*
X826267Y441500D01*
X826100Y442167D01*
X826267Y442833D01*
X826600Y443417D01*
X827100Y443750D01*
X827600Y443833D01*
X828100Y443750D01*
X828600Y443417D01*
X828933Y442833D01*
X829017Y442167D01*
X828933Y441500D01*
X828600Y440917D01*
X828100Y440583D01*
X827600Y440500D01*
G01X833200D02*
Y445500D01*
G01X838800Y440500D02*
Y445500D01*
G01X844400Y440500D02*
X843900Y440583D01*
X843400Y440917D01*
X843067Y441500D01*
X842900Y442167D01*
X843067Y442833D01*
X843400Y443417D01*
X843900Y443750D01*
X844400Y443833D01*
X844900Y443750D01*
X845400Y443417D01*
X845733Y442833D01*
X845817Y442167D01*
X845733Y441500D01*
X845400Y440917D01*
X844900Y440583D01*
X844400Y440500D01*
G01X847917Y443833D02*
X848917Y440500D01*
X850000Y443833D01*
X851083Y440500D01*
X852083Y443833D01*
G01X861700Y443000D02*
X863367D01*
Y441500D01*
X862867Y441000D01*
X862283Y440667D01*
X861450Y440500D01*
X860617Y440667D01*
X860033Y441000D01*
X859533Y441500D01*
X859200Y442083D01*
X859033Y442750D01*
Y443333D01*
X859200Y443833D01*
X859533Y444417D01*
X860033Y444917D01*
X860533Y445250D01*
X861200Y445500D01*
X861783D01*
X862450Y445333D01*
X862950Y445000D01*
G01X865550Y442750D02*
X868217D01*
X867967Y443333D01*
X867550Y443667D01*
X866967Y443833D01*
X866383Y443750D01*
X865883Y443500D01*
X865550Y442917D01*
X865383Y442417D01*
Y441917D01*
X865550Y441417D01*
X865967Y440917D01*
X866467Y440583D01*
X867050Y440500D01*
X867633Y440667D01*
X868217Y441167D01*
G01X871233Y440500D02*
Y443833D01*
G01Y443167D02*
X871650Y443500D01*
X872067Y443750D01*
X872650Y443833D01*
X873067Y443750D01*
X873567Y443500D01*
G01X876500Y440500D02*
Y445500D01*
G01Y443000D02*
X876917Y443500D01*
X877417Y443750D01*
X877917Y443833D01*
X878667Y443667D01*
X879167Y443333D01*
X879500Y442750D01*
Y442083D01*
X879333Y441417D01*
X879000Y440917D01*
X878417Y440583D01*
X877917Y440500D01*
X877417Y440583D01*
X876917Y440833D01*
X876500Y441250D01*
G01X882350Y442750D02*
X885017D01*
X884767Y443333D01*
X884350Y443667D01*
X883767Y443833D01*
X883183Y443750D01*
X882683Y443500D01*
X882350Y442917D01*
X882183Y442417D01*
Y441917D01*
X882350Y441417D01*
X882767Y440917D01*
X883267Y440583D01*
X883850Y440500D01*
X884433Y440667D01*
X885017Y441167D01*
G01X888033Y440500D02*
Y443833D01*
G01Y443167D02*
X888450Y443500D01*
X888867Y443750D01*
X889450Y443833D01*
X889867Y443750D01*
X890367Y443500D01*
G01X822000Y569000D02*
Y574000D01*
X821000Y573000D01*
G01Y569000D02*
X823000D01*
G01X827600Y568833D02*
X827433Y568917D01*
Y569083D01*
X827600Y569167D01*
X827767Y569083D01*
Y568917D01*
X827600Y568833D01*
G01X833200Y569000D02*
X832533Y569083D01*
X831950Y569417D01*
X831450Y569917D01*
X831117Y570500D01*
X830950Y571167D01*
Y571833D01*
X831117Y572500D01*
X831450Y573083D01*
X831950Y573583D01*
X832533Y573917D01*
X833200Y574000D01*
X833867Y573917D01*
X834450Y573583D01*
X834950Y573083D01*
X835283Y572500D01*
X835450Y571833D01*
Y571167D01*
X835283Y570500D01*
X834950Y569917D01*
X834450Y569417D01*
X833867Y569083D01*
X833200Y569000D01*
G01X837383D02*
Y572333D01*
G01Y571500D02*
X837717Y571917D01*
X838217Y572250D01*
X838883Y572333D01*
X839467Y572250D01*
X839967Y571917D01*
X840217Y571333D01*
Y569000D01*
G01X843150Y571250D02*
X845817D01*
X845567Y571833D01*
X845150Y572167D01*
X844567Y572333D01*
X843983Y572250D01*
X843483Y572000D01*
X843150Y571417D01*
X842983Y570917D01*
Y570417D01*
X843150Y569917D01*
X843567Y569417D01*
X844067Y569083D01*
X844650Y569000D01*
X845233Y569167D01*
X845817Y569667D01*
G01X854350Y569583D02*
X854767Y569250D01*
X855350Y569000D01*
X855850D01*
X856350Y569167D01*
X856683Y569417D01*
X856850Y569750D01*
X856767Y570250D01*
X856433Y570500D01*
X854933Y571000D01*
X854600Y571583D01*
X854767Y572000D01*
X855100Y572250D01*
X855600Y572333D01*
X856100Y572250D01*
X856600Y572000D01*
G01X861200Y572333D02*
Y569000D01*
G01Y573667D02*
X861033Y573750D01*
Y573917D01*
X861200Y574000D01*
X861367Y573917D01*
Y573750D01*
X861200Y573667D01*
G01X868300Y574000D02*
Y569000D01*
G01Y569750D02*
X867967Y569333D01*
X867467Y569083D01*
X866883Y569000D01*
X866217Y569167D01*
X865717Y569583D01*
X865383Y570083D01*
X865300Y570667D01*
X865383Y571250D01*
X865717Y571750D01*
X866217Y572167D01*
X866883Y572333D01*
X867467Y572250D01*
X867883Y572083D01*
X868300Y571750D01*
G01X871150Y571250D02*
X873817D01*
X873567Y571833D01*
X873150Y572167D01*
X872567Y572333D01*
X871983Y572250D01*
X871483Y572000D01*
X871150Y571417D01*
X870983Y570917D01*
Y570417D01*
X871150Y569917D01*
X871567Y569417D01*
X872067Y569083D01*
X872650Y569000D01*
X873233Y569167D01*
X873817Y569667D01*
G01X881517Y572333D02*
X882517Y569000D01*
X883600Y572333D01*
X884683Y569000D01*
X885683Y572333D01*
G01X889200D02*
Y569000D01*
G01Y573667D02*
X889033Y573750D01*
Y573917D01*
X889200Y574000D01*
X889367Y573917D01*
Y573750D01*
X889200Y573667D01*
G01X894800Y574000D02*
Y569000D01*
G01X893633Y572333D02*
X895967D01*
G01X898983Y569000D02*
Y574000D01*
G01Y571583D02*
X899400Y572000D01*
X899817Y572250D01*
X900483Y572333D01*
X900983Y572250D01*
X901567Y571917D01*
X901817Y571417D01*
Y569000D01*
G01X910350Y569583D02*
X910767Y569250D01*
X911350Y569000D01*
X911850D01*
X912350Y569167D01*
X912683Y569417D01*
X912850Y569750D01*
X912767Y570250D01*
X912433Y570500D01*
X910933Y571000D01*
X910600Y571583D01*
X910767Y572000D01*
X911100Y572250D01*
X911600Y572333D01*
X912100Y572250D01*
X912600Y572000D01*
G01X917200Y569000D02*
X916700Y569083D01*
X916200Y569417D01*
X915867Y570000D01*
X915700Y570667D01*
X915867Y571333D01*
X916200Y571917D01*
X916700Y572250D01*
X917200Y572333D01*
X917700Y572250D01*
X918200Y571917D01*
X918533Y571333D01*
X918617Y570667D01*
X918533Y570000D01*
X918200Y569417D01*
X917700Y569083D01*
X917200Y569000D01*
G01X922800D02*
Y574000D01*
G01X929900D02*
Y569000D01*
G01Y569750D02*
X929567Y569333D01*
X929067Y569083D01*
X928483Y569000D01*
X927817Y569167D01*
X927317Y569583D01*
X926983Y570083D01*
X926900Y570667D01*
X926983Y571250D01*
X927317Y571750D01*
X927817Y572167D01*
X928483Y572333D01*
X929067Y572250D01*
X929483Y572083D01*
X929900Y571750D01*
G01X932750Y571250D02*
X935417D01*
X935167Y571833D01*
X934750Y572167D01*
X934167Y572333D01*
X933583Y572250D01*
X933083Y572000D01*
X932750Y571417D01*
X932583Y570917D01*
Y570417D01*
X932750Y569917D01*
X933167Y569417D01*
X933667Y569083D01*
X934250Y569000D01*
X934833Y569167D01*
X935417Y569667D01*
G01X938433Y569000D02*
Y572333D01*
G01Y571667D02*
X938850Y572000D01*
X939267Y572250D01*
X939850Y572333D01*
X940267Y572250D01*
X940767Y572000D01*
G01X948300Y569000D02*
Y572333D01*
G01Y571417D02*
X948550Y571833D01*
X948967Y572167D01*
X949550Y572333D01*
X950133Y572167D01*
X950550Y571833D01*
X950800Y571417D01*
Y569000D01*
G01Y571417D02*
X951050Y571833D01*
X951467Y572167D01*
X952050Y572333D01*
X952633Y572167D01*
X953050Y571833D01*
X953300Y571333D01*
Y569000D01*
G01X957900D02*
Y572333D01*
G01Y571750D02*
X957567Y572083D01*
X957067Y572250D01*
X956483Y572333D01*
X955900Y572167D01*
X955400Y571833D01*
X955067Y571333D01*
X954900Y570667D01*
X955067Y570000D01*
X955400Y569500D01*
X955900Y569167D01*
X956483Y569000D01*
X957067Y569083D01*
X957567Y569333D01*
X957900Y569667D01*
G01X960750Y569583D02*
X961167Y569250D01*
X961750Y569000D01*
X962250D01*
X962750Y569167D01*
X963083Y569417D01*
X963250Y569750D01*
X963167Y570250D01*
X962833Y570500D01*
X961333Y571000D01*
X961000Y571583D01*
X961167Y572000D01*
X961500Y572250D01*
X962000Y572333D01*
X962500Y572250D01*
X963000Y572000D01*
G01X966183Y569000D02*
Y574000D01*
G01X968850Y572333D02*
X966183Y570417D01*
G01X967267Y571167D02*
X969017Y569000D01*
G01X977300Y567333D02*
Y572333D01*
G01Y571583D02*
X977717Y572000D01*
X978133Y572250D01*
X978800Y572333D01*
X979383Y572250D01*
X979967Y571833D01*
X980217Y571250D01*
X980300Y570667D01*
X980217Y570083D01*
X979967Y569500D01*
X979467Y569167D01*
X978800Y569000D01*
X978217Y569083D01*
X977633Y569333D01*
X977300Y569667D01*
G01X985900Y569000D02*
Y572333D01*
G01Y571750D02*
X985567Y572083D01*
X985067Y572250D01*
X984483Y572333D01*
X983900Y572167D01*
X983400Y571833D01*
X983067Y571333D01*
X982900Y570667D01*
X983067Y570000D01*
X983400Y569500D01*
X983900Y569167D01*
X984483Y569000D01*
X985067Y569083D01*
X985567Y569333D01*
X985900Y569667D01*
G01X991500Y574000D02*
Y569000D01*
G01Y569750D02*
X991167Y569333D01*
X990667Y569083D01*
X990083Y569000D01*
X989417Y569167D01*
X988917Y569583D01*
X988583Y570083D01*
X988500Y570667D01*
X988583Y571250D01*
X988917Y571750D01*
X989417Y572167D01*
X990083Y572333D01*
X990667Y572250D01*
X991083Y572083D01*
X991500Y571750D01*
G01X822000Y569000D02*
Y574000D01*
X821000Y573000D01*
G01Y569000D02*
X823000D01*
G01X827600Y568833D02*
X827433Y568917D01*
Y569083D01*
X827600Y569167D01*
X827767Y569083D01*
Y568917D01*
X827600Y568833D01*
G01X833200Y569000D02*
X832533Y569083D01*
X831950Y569417D01*
X831450Y569917D01*
X831117Y570500D01*
X830950Y571167D01*
Y571833D01*
X831117Y572500D01*
X831450Y573083D01*
X831950Y573583D01*
X832533Y573917D01*
X833200Y574000D01*
X833867Y573917D01*
X834450Y573583D01*
X834950Y573083D01*
X835283Y572500D01*
X835450Y571833D01*
Y571167D01*
X835283Y570500D01*
X834950Y569917D01*
X834450Y569417D01*
X833867Y569083D01*
X833200Y569000D01*
G01X837383D02*
Y572333D01*
G01Y571500D02*
X837717Y571917D01*
X838217Y572250D01*
X838883Y572333D01*
X839467Y572250D01*
X839967Y571917D01*
X840217Y571333D01*
Y569000D01*
G01X843150Y571250D02*
X845817D01*
X845567Y571833D01*
X845150Y572167D01*
X844567Y572333D01*
X843983Y572250D01*
X843483Y572000D01*
X843150Y571417D01*
X842983Y570917D01*
Y570417D01*
X843150Y569917D01*
X843567Y569417D01*
X844067Y569083D01*
X844650Y569000D01*
X845233Y569167D01*
X845817Y569667D01*
G01X854350Y569583D02*
X854767Y569250D01*
X855350Y569000D01*
X855850D01*
X856350Y569167D01*
X856683Y569417D01*
X856850Y569750D01*
X856767Y570250D01*
X856433Y570500D01*
X854933Y571000D01*
X854600Y571583D01*
X854767Y572000D01*
X855100Y572250D01*
X855600Y572333D01*
X856100Y572250D01*
X856600Y572000D01*
G01X861200Y572333D02*
Y569000D01*
G01Y573667D02*
X861033Y573750D01*
Y573917D01*
X861200Y574000D01*
X861367Y573917D01*
Y573750D01*
X861200Y573667D01*
G01X868300Y574000D02*
Y569000D01*
G01Y569750D02*
X867967Y569333D01*
X867467Y569083D01*
X866883Y569000D01*
X866217Y569167D01*
X865717Y569583D01*
X865383Y570083D01*
X865300Y570667D01*
X865383Y571250D01*
X865717Y571750D01*
X866217Y572167D01*
X866883Y572333D01*
X867467Y572250D01*
X867883Y572083D01*
X868300Y571750D01*
G01X871150Y571250D02*
X873817D01*
X873567Y571833D01*
X873150Y572167D01*
X872567Y572333D01*
X871983Y572250D01*
X871483Y572000D01*
X871150Y571417D01*
X870983Y570917D01*
Y570417D01*
X871150Y569917D01*
X871567Y569417D01*
X872067Y569083D01*
X872650Y569000D01*
X873233Y569167D01*
X873817Y569667D01*
G01X881517Y572333D02*
X882517Y569000D01*
X883600Y572333D01*
X884683Y569000D01*
X885683Y572333D01*
G01X889200D02*
Y569000D01*
G01Y573667D02*
X889033Y573750D01*
Y573917D01*
X889200Y574000D01*
X889367Y573917D01*
Y573750D01*
X889200Y573667D01*
G01X894800Y574000D02*
Y569000D01*
G01X893633Y572333D02*
X895967D01*
G01X898983Y569000D02*
Y574000D01*
G01Y571583D02*
X899400Y572000D01*
X899817Y572250D01*
X900483Y572333D01*
X900983Y572250D01*
X901567Y571917D01*
X901817Y571417D01*
Y569000D01*
G01X910350Y569583D02*
X910767Y569250D01*
X911350Y569000D01*
X911850D01*
X912350Y569167D01*
X912683Y569417D01*
X912850Y569750D01*
X912767Y570250D01*
X912433Y570500D01*
X910933Y571000D01*
X910600Y571583D01*
X910767Y572000D01*
X911100Y572250D01*
X911600Y572333D01*
X912100Y572250D01*
X912600Y572000D01*
G01X917200Y569000D02*
X916700Y569083D01*
X916200Y569417D01*
X915867Y570000D01*
X915700Y570667D01*
X915867Y571333D01*
X916200Y571917D01*
X916700Y572250D01*
X917200Y572333D01*
X917700Y572250D01*
X918200Y571917D01*
X918533Y571333D01*
X918617Y570667D01*
X918533Y570000D01*
X918200Y569417D01*
X917700Y569083D01*
X917200Y569000D01*
G01X922800D02*
Y574000D01*
G01X929900D02*
Y569000D01*
G01Y569750D02*
X929567Y569333D01*
X929067Y569083D01*
X928483Y569000D01*
X927817Y569167D01*
X927317Y569583D01*
X926983Y570083D01*
X926900Y570667D01*
X926983Y571250D01*
X927317Y571750D01*
X927817Y572167D01*
X928483Y572333D01*
X929067Y572250D01*
X929483Y572083D01*
X929900Y571750D01*
G01X932750Y571250D02*
X935417D01*
X935167Y571833D01*
X934750Y572167D01*
X934167Y572333D01*
X933583Y572250D01*
X933083Y572000D01*
X932750Y571417D01*
X932583Y570917D01*
Y570417D01*
X932750Y569917D01*
X933167Y569417D01*
X933667Y569083D01*
X934250Y569000D01*
X934833Y569167D01*
X935417Y569667D01*
G01X938433Y569000D02*
Y572333D01*
G01Y571667D02*
X938850Y572000D01*
X939267Y572250D01*
X939850Y572333D01*
X940267Y572250D01*
X940767Y572000D01*
G01X948300Y569000D02*
Y572333D01*
G01Y571417D02*
X948550Y571833D01*
X948967Y572167D01*
X949550Y572333D01*
X950133Y572167D01*
X950550Y571833D01*
X950800Y571417D01*
Y569000D01*
G01Y571417D02*
X951050Y571833D01*
X951467Y572167D01*
X952050Y572333D01*
X952633Y572167D01*
X953050Y571833D01*
X953300Y571333D01*
Y569000D01*
G01X957900D02*
Y572333D01*
G01Y571750D02*
X957567Y572083D01*
X957067Y572250D01*
X956483Y572333D01*
X955900Y572167D01*
X955400Y571833D01*
X955067Y571333D01*
X954900Y570667D01*
X955067Y570000D01*
X955400Y569500D01*
X955900Y569167D01*
X956483Y569000D01*
X957067Y569083D01*
X957567Y569333D01*
X957900Y569667D01*
G01X960750Y569583D02*
X961167Y569250D01*
X961750Y569000D01*
X962250D01*
X962750Y569167D01*
X963083Y569417D01*
X963250Y569750D01*
X963167Y570250D01*
X962833Y570500D01*
X961333Y571000D01*
X961000Y571583D01*
X961167Y572000D01*
X961500Y572250D01*
X962000Y572333D01*
X962500Y572250D01*
X963000Y572000D01*
G01X966183Y569000D02*
Y574000D01*
G01X968850Y572333D02*
X966183Y570417D01*
G01X967267Y571167D02*
X969017Y569000D01*
G01X977300Y567333D02*
Y572333D01*
G01Y571583D02*
X977717Y572000D01*
X978133Y572250D01*
X978800Y572333D01*
X979383Y572250D01*
X979967Y571833D01*
X980217Y571250D01*
X980300Y570667D01*
X980217Y570083D01*
X979967Y569500D01*
X979467Y569167D01*
X978800Y569000D01*
X978217Y569083D01*
X977633Y569333D01*
X977300Y569667D01*
G01X985900Y569000D02*
Y572333D01*
G01Y571750D02*
X985567Y572083D01*
X985067Y572250D01*
X984483Y572333D01*
X983900Y572167D01*
X983400Y571833D01*
X983067Y571333D01*
X982900Y570667D01*
X983067Y570000D01*
X983400Y569500D01*
X983900Y569167D01*
X984483Y569000D01*
X985067Y569083D01*
X985567Y569333D01*
X985900Y569667D01*
G01X991500Y574000D02*
Y569000D01*
G01Y569750D02*
X991167Y569333D01*
X990667Y569083D01*
X990083Y569000D01*
X989417Y569167D01*
X988917Y569583D01*
X988583Y570083D01*
X988500Y570667D01*
X988583Y571250D01*
X988917Y571750D01*
X989417Y572167D01*
X990083Y572333D01*
X990667Y572250D01*
X991083Y572083D01*
X991500Y571750D01*
G01X794500Y674500D02*
Y669500D01*
G01X793333Y672833D02*
X795667D01*
G01X798683Y669500D02*
Y674500D01*
G01Y672083D02*
X799100Y672500D01*
X799517Y672750D01*
X800183Y672833D01*
X800683Y672750D01*
X801267Y672417D01*
X801517Y671917D01*
Y669500D01*
G01X805700Y672833D02*
Y669500D01*
G01Y674167D02*
X805533Y674250D01*
Y674417D01*
X805700Y674500D01*
X805867Y674417D01*
Y674250D01*
X805700Y674167D01*
G01X812633Y672417D02*
X812050Y672750D01*
X811550Y672833D01*
X810883Y672667D01*
X810383Y672333D01*
X810050Y671750D01*
X809967Y671167D01*
X810050Y670583D01*
X810383Y670083D01*
X810883Y669667D01*
X811550Y669500D01*
X812133Y669667D01*
X812633Y670000D01*
G01X815483Y669500D02*
Y674500D01*
G01X818150Y672833D02*
X815483Y670917D01*
G01X816567Y671667D02*
X818317Y669500D01*
G01X821083D02*
Y672833D01*
G01Y672000D02*
X821417Y672417D01*
X821917Y672750D01*
X822583Y672833D01*
X823167Y672750D01*
X823667Y672417D01*
X823917Y671833D01*
Y669500D01*
G01X826850Y671750D02*
X829517D01*
X829267Y672333D01*
X828850Y672667D01*
X828267Y672833D01*
X827683Y672750D01*
X827183Y672500D01*
X826850Y671917D01*
X826683Y671417D01*
Y670917D01*
X826850Y670417D01*
X827267Y669917D01*
X827767Y669583D01*
X828350Y669500D01*
X828933Y669667D01*
X829517Y670167D01*
G01X832450Y670083D02*
X832867Y669750D01*
X833450Y669500D01*
X833950D01*
X834450Y669667D01*
X834783Y669917D01*
X834950Y670250D01*
X834867Y670750D01*
X834533Y671000D01*
X833033Y671500D01*
X832700Y672083D01*
X832867Y672500D01*
X833200Y672750D01*
X833700Y672833D01*
X834200Y672750D01*
X834700Y672500D01*
G01X838050Y670083D02*
X838467Y669750D01*
X839050Y669500D01*
X839550D01*
X840050Y669667D01*
X840383Y669917D01*
X840550Y670250D01*
X840467Y670750D01*
X840133Y671000D01*
X838633Y671500D01*
X838300Y672083D01*
X838467Y672500D01*
X838800Y672750D01*
X839300Y672833D01*
X839800Y672750D01*
X840300Y672500D01*
G01X809000Y686500D02*
Y691500D01*
G01Y689000D02*
X809417Y689500D01*
X809917Y689750D01*
X810417Y689833D01*
X811167Y689667D01*
X811667Y689333D01*
X812000Y688750D01*
Y688083D01*
X811833Y687417D01*
X811500Y686917D01*
X810917Y686583D01*
X810417Y686500D01*
X809917Y686583D01*
X809417Y686833D01*
X809000Y687250D01*
G01X816100Y686500D02*
X815600Y686583D01*
X815100Y686917D01*
X814767Y687500D01*
X814600Y688167D01*
X814767Y688833D01*
X815100Y689417D01*
X815600Y689750D01*
X816100Y689833D01*
X816600Y689750D01*
X817100Y689417D01*
X817433Y688833D01*
X817517Y688167D01*
X817433Y687500D01*
X817100Y686917D01*
X816600Y686583D01*
X816100Y686500D01*
G01X823200D02*
Y689833D01*
G01Y689250D02*
X822867Y689583D01*
X822367Y689750D01*
X821783Y689833D01*
X821200Y689667D01*
X820700Y689333D01*
X820367Y688833D01*
X820200Y688167D01*
X820367Y687500D01*
X820700Y687000D01*
X821200Y686667D01*
X821783Y686500D01*
X822367Y686583D01*
X822867Y686833D01*
X823200Y687167D01*
G01X826133Y686500D02*
Y689833D01*
G01Y689167D02*
X826550Y689500D01*
X826967Y689750D01*
X827550Y689833D01*
X827967Y689750D01*
X828467Y689500D01*
G01X834400Y691500D02*
Y686500D01*
G01Y687250D02*
X834067Y686833D01*
X833567Y686583D01*
X832983Y686500D01*
X832317Y686667D01*
X831817Y687083D01*
X831483Y687583D01*
X831400Y688167D01*
X831483Y688750D01*
X831817Y689250D01*
X832317Y689667D01*
X832983Y689833D01*
X833567Y689750D01*
X833983Y689583D01*
X834400Y689250D01*
G01X794500Y674500D02*
Y669500D01*
G01X793333Y672833D02*
X795667D01*
G01X798683Y669500D02*
Y674500D01*
G01Y672083D02*
X799100Y672500D01*
X799517Y672750D01*
X800183Y672833D01*
X800683Y672750D01*
X801267Y672417D01*
X801517Y671917D01*
Y669500D01*
G01X805700Y672833D02*
Y669500D01*
G01Y674167D02*
X805533Y674250D01*
Y674417D01*
X805700Y674500D01*
X805867Y674417D01*
Y674250D01*
X805700Y674167D01*
G01X812633Y672417D02*
X812050Y672750D01*
X811550Y672833D01*
X810883Y672667D01*
X810383Y672333D01*
X810050Y671750D01*
X809967Y671167D01*
X810050Y670583D01*
X810383Y670083D01*
X810883Y669667D01*
X811550Y669500D01*
X812133Y669667D01*
X812633Y670000D01*
G01X815483Y669500D02*
Y674500D01*
G01X818150Y672833D02*
X815483Y670917D01*
G01X816567Y671667D02*
X818317Y669500D01*
G01X821083D02*
Y672833D01*
G01Y672000D02*
X821417Y672417D01*
X821917Y672750D01*
X822583Y672833D01*
X823167Y672750D01*
X823667Y672417D01*
X823917Y671833D01*
Y669500D01*
G01X826850Y671750D02*
X829517D01*
X829267Y672333D01*
X828850Y672667D01*
X828267Y672833D01*
X827683Y672750D01*
X827183Y672500D01*
X826850Y671917D01*
X826683Y671417D01*
Y670917D01*
X826850Y670417D01*
X827267Y669917D01*
X827767Y669583D01*
X828350Y669500D01*
X828933Y669667D01*
X829517Y670167D01*
G01X832450Y670083D02*
X832867Y669750D01*
X833450Y669500D01*
X833950D01*
X834450Y669667D01*
X834783Y669917D01*
X834950Y670250D01*
X834867Y670750D01*
X834533Y671000D01*
X833033Y671500D01*
X832700Y672083D01*
X832867Y672500D01*
X833200Y672750D01*
X833700Y672833D01*
X834200Y672750D01*
X834700Y672500D01*
G01X838050Y670083D02*
X838467Y669750D01*
X839050Y669500D01*
X839550D01*
X840050Y669667D01*
X840383Y669917D01*
X840550Y670250D01*
X840467Y670750D01*
X840133Y671000D01*
X838633Y671500D01*
X838300Y672083D01*
X838467Y672500D01*
X838800Y672750D01*
X839300Y672833D01*
X839800Y672750D01*
X840300Y672500D01*
G01X809000Y686500D02*
Y691500D01*
G01Y689000D02*
X809417Y689500D01*
X809917Y689750D01*
X810417Y689833D01*
X811167Y689667D01*
X811667Y689333D01*
X812000Y688750D01*
Y688083D01*
X811833Y687417D01*
X811500Y686917D01*
X810917Y686583D01*
X810417Y686500D01*
X809917Y686583D01*
X809417Y686833D01*
X809000Y687250D01*
G01X816100Y686500D02*
X815600Y686583D01*
X815100Y686917D01*
X814767Y687500D01*
X814600Y688167D01*
X814767Y688833D01*
X815100Y689417D01*
X815600Y689750D01*
X816100Y689833D01*
X816600Y689750D01*
X817100Y689417D01*
X817433Y688833D01*
X817517Y688167D01*
X817433Y687500D01*
X817100Y686917D01*
X816600Y686583D01*
X816100Y686500D01*
G01X823200D02*
Y689833D01*
G01Y689250D02*
X822867Y689583D01*
X822367Y689750D01*
X821783Y689833D01*
X821200Y689667D01*
X820700Y689333D01*
X820367Y688833D01*
X820200Y688167D01*
X820367Y687500D01*
X820700Y687000D01*
X821200Y686667D01*
X821783Y686500D01*
X822367Y686583D01*
X822867Y686833D01*
X823200Y687167D01*
G01X826133Y686500D02*
Y689833D01*
G01Y689167D02*
X826550Y689500D01*
X826967Y689750D01*
X827550Y689833D01*
X827967Y689750D01*
X828467Y689500D01*
G01X834400Y691500D02*
Y686500D01*
G01Y687250D02*
X834067Y686833D01*
X833567Y686583D01*
X832983Y686500D01*
X832317Y686667D01*
X831817Y687083D01*
X831483Y687583D01*
X831400Y688167D01*
X831483Y688750D01*
X831817Y689250D01*
X832317Y689667D01*
X832983Y689833D01*
X833567Y689750D01*
X833983Y689583D01*
X834400Y689250D01*
G01X798500Y795500D02*
Y790500D01*
G01X796583Y795500D02*
X800417D01*
G01X802017Y793833D02*
X803017Y790500D01*
X804100Y793833D01*
X805183Y790500D01*
X806183Y793833D01*
G01X809700D02*
Y790500D01*
G01Y795167D02*
X809533Y795250D01*
Y795417D01*
X809700Y795500D01*
X809867Y795417D01*
Y795250D01*
X809700Y795167D01*
G01X814050Y791083D02*
X814467Y790750D01*
X815050Y790500D01*
X815550D01*
X816050Y790667D01*
X816383Y790917D01*
X816550Y791250D01*
X816467Y791750D01*
X816133Y792000D01*
X814633Y792500D01*
X814300Y793083D01*
X814467Y793500D01*
X814800Y793750D01*
X815300Y793833D01*
X815800Y793750D01*
X816300Y793500D01*
G01X820900Y795500D02*
Y790500D01*
G01X819733Y793833D02*
X822067D01*
G01X833600Y790500D02*
Y793833D01*
G01Y793250D02*
X833267Y793583D01*
X832767Y793750D01*
X832183Y793833D01*
X831600Y793667D01*
X831100Y793333D01*
X830767Y792833D01*
X830600Y792167D01*
X830767Y791500D01*
X831100Y791000D01*
X831600Y790667D01*
X832183Y790500D01*
X832767Y790583D01*
X833267Y790833D01*
X833600Y791167D01*
G01X836283Y790500D02*
Y793833D01*
G01Y793000D02*
X836617Y793417D01*
X837117Y793750D01*
X837783Y793833D01*
X838367Y793750D01*
X838867Y793417D01*
X839117Y792833D01*
Y790500D01*
G01X844800Y795500D02*
Y790500D01*
G01Y791250D02*
X844467Y790833D01*
X843967Y790583D01*
X843383Y790500D01*
X842717Y790667D01*
X842217Y791083D01*
X841883Y791583D01*
X841800Y792167D01*
X841883Y792750D01*
X842217Y793250D01*
X842717Y793667D01*
X843383Y793833D01*
X843967Y793750D01*
X844383Y793583D01*
X844800Y793250D01*
G01X853000Y790500D02*
Y795500D01*
G01Y793000D02*
X853417Y793500D01*
X853917Y793750D01*
X854417Y793833D01*
X855167Y793667D01*
X855667Y793333D01*
X856000Y792750D01*
Y792083D01*
X855833Y791417D01*
X855500Y790917D01*
X854917Y790583D01*
X854417Y790500D01*
X853917Y790583D01*
X853417Y790833D01*
X853000Y791250D01*
G01X860100Y790500D02*
X859600Y790583D01*
X859100Y790917D01*
X858767Y791500D01*
X858600Y792167D01*
X858767Y792833D01*
X859100Y793417D01*
X859600Y793750D01*
X860100Y793833D01*
X860600Y793750D01*
X861100Y793417D01*
X861433Y792833D01*
X861517Y792167D01*
X861433Y791500D01*
X861100Y790917D01*
X860600Y790583D01*
X860100Y790500D01*
G01X863617Y793833D02*
X864617Y790500D01*
X865700Y793833D01*
X866783Y790500D01*
X867783Y793833D01*
G01X788000Y850610D02*
Y782110D01*
G01Y805500D02*
X1343000D01*
G01X798500Y795500D02*
Y790500D01*
G01X796583Y795500D02*
X800417D01*
G01X802017Y793833D02*
X803017Y790500D01*
X804100Y793833D01*
X805183Y790500D01*
X806183Y793833D01*
G01X809700D02*
Y790500D01*
G01Y795167D02*
X809533Y795250D01*
Y795417D01*
X809700Y795500D01*
X809867Y795417D01*
Y795250D01*
X809700Y795167D01*
G01X814050Y791083D02*
X814467Y790750D01*
X815050Y790500D01*
X815550D01*
X816050Y790667D01*
X816383Y790917D01*
X816550Y791250D01*
X816467Y791750D01*
X816133Y792000D01*
X814633Y792500D01*
X814300Y793083D01*
X814467Y793500D01*
X814800Y793750D01*
X815300Y793833D01*
X815800Y793750D01*
X816300Y793500D01*
G01X820900Y795500D02*
Y790500D01*
G01X819733Y793833D02*
X822067D01*
G01X833600Y790500D02*
Y793833D01*
G01Y793250D02*
X833267Y793583D01*
X832767Y793750D01*
X832183Y793833D01*
X831600Y793667D01*
X831100Y793333D01*
X830767Y792833D01*
X830600Y792167D01*
X830767Y791500D01*
X831100Y791000D01*
X831600Y790667D01*
X832183Y790500D01*
X832767Y790583D01*
X833267Y790833D01*
X833600Y791167D01*
G01X836283Y790500D02*
Y793833D01*
G01Y793000D02*
X836617Y793417D01*
X837117Y793750D01*
X837783Y793833D01*
X838367Y793750D01*
X838867Y793417D01*
X839117Y792833D01*
Y790500D01*
G01X844800Y795500D02*
Y790500D01*
G01Y791250D02*
X844467Y790833D01*
X843967Y790583D01*
X843383Y790500D01*
X842717Y790667D01*
X842217Y791083D01*
X841883Y791583D01*
X841800Y792167D01*
X841883Y792750D01*
X842217Y793250D01*
X842717Y793667D01*
X843383Y793833D01*
X843967Y793750D01*
X844383Y793583D01*
X844800Y793250D01*
G01X853000Y790500D02*
Y795500D01*
G01Y793000D02*
X853417Y793500D01*
X853917Y793750D01*
X854417Y793833D01*
X855167Y793667D01*
X855667Y793333D01*
X856000Y792750D01*
Y792083D01*
X855833Y791417D01*
X855500Y790917D01*
X854917Y790583D01*
X854417Y790500D01*
X853917Y790583D01*
X853417Y790833D01*
X853000Y791250D01*
G01X860100Y790500D02*
X859600Y790583D01*
X859100Y790917D01*
X858767Y791500D01*
X858600Y792167D01*
X858767Y792833D01*
X859100Y793417D01*
X859600Y793750D01*
X860100Y793833D01*
X860600Y793750D01*
X861100Y793417D01*
X861433Y792833D01*
X861517Y792167D01*
X861433Y791500D01*
X861100Y790917D01*
X860600Y790583D01*
X860100Y790500D01*
G01X863617Y793833D02*
X864617Y790500D01*
X865700Y793833D01*
X866783Y790500D01*
X867783Y793833D01*
G01X788000Y850610D02*
Y782110D01*
G01Y805500D02*
X1343000D01*
G01X796833Y826500D02*
Y831500D01*
X798917D01*
X799583Y831250D01*
X800000Y830917D01*
X800167Y830250D01*
X800000Y829583D01*
X799500Y829167D01*
X798917Y828917D01*
X796833D01*
G01X798917D02*
X800167Y826500D01*
G01X804100D02*
X803600Y826583D01*
X803100Y826917D01*
X802767Y827500D01*
X802600Y828167D01*
X802767Y828833D01*
X803100Y829417D01*
X803600Y829750D01*
X804100Y829833D01*
X804600Y829750D01*
X805100Y829417D01*
X805433Y828833D01*
X805517Y828167D01*
X805433Y827500D01*
X805100Y826917D01*
X804600Y826583D01*
X804100Y826500D01*
G01X808283Y829833D02*
Y827500D01*
X808617Y826917D01*
X809117Y826583D01*
X809700Y826500D01*
X810283Y826583D01*
X810783Y826917D01*
X811117Y827500D01*
G01Y826500D02*
Y829833D01*
G01X815300Y831500D02*
Y826500D01*
G01X814133Y829833D02*
X816467D01*
G01X820900D02*
Y826500D01*
G01Y831167D02*
X820733Y831250D01*
Y831417D01*
X820900Y831500D01*
X821067Y831417D01*
Y831250D01*
X820900Y831167D01*
G01X825083Y826500D02*
Y829833D01*
G01Y829000D02*
X825417Y829417D01*
X825917Y829750D01*
X826583Y829833D01*
X827167Y829750D01*
X827667Y829417D01*
X827917Y828833D01*
Y826500D01*
G01X830933Y825250D02*
X831517Y824917D01*
X832183Y824833D01*
X832767Y824917D01*
X833267Y825333D01*
X833600Y825917D01*
Y829833D01*
G01Y829167D02*
X833267Y829500D01*
X832767Y829750D01*
X832183Y829833D01*
X831517Y829667D01*
X831100Y829333D01*
X830767Y828750D01*
X830600Y828167D01*
X830683Y827667D01*
X831017Y827083D01*
X831517Y826667D01*
X832183Y826500D01*
X832683Y826583D01*
X833267Y826917D01*
X833600Y827250D01*
G01X843300Y831500D02*
Y826500D01*
G01X842133Y829833D02*
X844467D01*
G01X848900Y826500D02*
X848400Y826583D01*
X847900Y826917D01*
X847567Y827500D01*
X847400Y828167D01*
X847567Y828833D01*
X847900Y829417D01*
X848400Y829750D01*
X848900Y829833D01*
X849400Y829750D01*
X849900Y829417D01*
X850233Y828833D01*
X850317Y828167D01*
X850233Y827500D01*
X849900Y826917D01*
X849400Y826583D01*
X848900Y826500D01*
G01X854500D02*
Y831500D01*
G01X858850Y828750D02*
X861517D01*
X861267Y829333D01*
X860850Y829667D01*
X860267Y829833D01*
X859683Y829750D01*
X859183Y829500D01*
X858850Y828917D01*
X858683Y828417D01*
Y827917D01*
X858850Y827417D01*
X859267Y826917D01*
X859767Y826583D01*
X860350Y826500D01*
X860933Y826667D01*
X861517Y827167D01*
G01X864533Y826500D02*
Y829833D01*
G01Y829167D02*
X864950Y829500D01*
X865367Y829750D01*
X865950Y829833D01*
X866367Y829750D01*
X866867Y829500D01*
G01X872800Y826500D02*
Y829833D01*
G01Y829250D02*
X872467Y829583D01*
X871967Y829750D01*
X871383Y829833D01*
X870800Y829667D01*
X870300Y829333D01*
X869967Y828833D01*
X869800Y828167D01*
X869967Y827500D01*
X870300Y827000D01*
X870800Y826667D01*
X871383Y826500D01*
X871967Y826583D01*
X872467Y826833D01*
X872800Y827167D01*
G01X875483Y826500D02*
Y829833D01*
G01Y829000D02*
X875817Y829417D01*
X876317Y829750D01*
X876983Y829833D01*
X877567Y829750D01*
X878067Y829417D01*
X878317Y828833D01*
Y826500D01*
G01X883833Y829417D02*
X883250Y829750D01*
X882750Y829833D01*
X882083Y829667D01*
X881583Y829333D01*
X881250Y828750D01*
X881167Y828167D01*
X881250Y827583D01*
X881583Y827083D01*
X882083Y826667D01*
X882750Y826500D01*
X883333Y826667D01*
X883833Y827000D01*
G01X886850Y828750D02*
X889517D01*
X889267Y829333D01*
X888850Y829667D01*
X888267Y829833D01*
X887683Y829750D01*
X887183Y829500D01*
X886850Y828917D01*
X886683Y828417D01*
Y827917D01*
X886850Y827417D01*
X887267Y826917D01*
X887767Y826583D01*
X888350Y826500D01*
X888933Y826667D01*
X889517Y827167D01*
G01X796833Y826500D02*
Y831500D01*
X798917D01*
X799583Y831250D01*
X800000Y830917D01*
X800167Y830250D01*
X800000Y829583D01*
X799500Y829167D01*
X798917Y828917D01*
X796833D01*
G01X798917D02*
X800167Y826500D01*
G01X804100D02*
X803600Y826583D01*
X803100Y826917D01*
X802767Y827500D01*
X802600Y828167D01*
X802767Y828833D01*
X803100Y829417D01*
X803600Y829750D01*
X804100Y829833D01*
X804600Y829750D01*
X805100Y829417D01*
X805433Y828833D01*
X805517Y828167D01*
X805433Y827500D01*
X805100Y826917D01*
X804600Y826583D01*
X804100Y826500D01*
G01X808283Y829833D02*
Y827500D01*
X808617Y826917D01*
X809117Y826583D01*
X809700Y826500D01*
X810283Y826583D01*
X810783Y826917D01*
X811117Y827500D01*
G01Y826500D02*
Y829833D01*
G01X815300Y831500D02*
Y826500D01*
G01X814133Y829833D02*
X816467D01*
G01X820900D02*
Y826500D01*
G01Y831167D02*
X820733Y831250D01*
Y831417D01*
X820900Y831500D01*
X821067Y831417D01*
Y831250D01*
X820900Y831167D01*
G01X825083Y826500D02*
Y829833D01*
G01Y829000D02*
X825417Y829417D01*
X825917Y829750D01*
X826583Y829833D01*
X827167Y829750D01*
X827667Y829417D01*
X827917Y828833D01*
Y826500D01*
G01X830933Y825250D02*
X831517Y824917D01*
X832183Y824833D01*
X832767Y824917D01*
X833267Y825333D01*
X833600Y825917D01*
Y829833D01*
G01Y829167D02*
X833267Y829500D01*
X832767Y829750D01*
X832183Y829833D01*
X831517Y829667D01*
X831100Y829333D01*
X830767Y828750D01*
X830600Y828167D01*
X830683Y827667D01*
X831017Y827083D01*
X831517Y826667D01*
X832183Y826500D01*
X832683Y826583D01*
X833267Y826917D01*
X833600Y827250D01*
G01X843300Y831500D02*
Y826500D01*
G01X842133Y829833D02*
X844467D01*
G01X848900Y826500D02*
X848400Y826583D01*
X847900Y826917D01*
X847567Y827500D01*
X847400Y828167D01*
X847567Y828833D01*
X847900Y829417D01*
X848400Y829750D01*
X848900Y829833D01*
X849400Y829750D01*
X849900Y829417D01*
X850233Y828833D01*
X850317Y828167D01*
X850233Y827500D01*
X849900Y826917D01*
X849400Y826583D01*
X848900Y826500D01*
G01X854500D02*
Y831500D01*
G01X858850Y828750D02*
X861517D01*
X861267Y829333D01*
X860850Y829667D01*
X860267Y829833D01*
X859683Y829750D01*
X859183Y829500D01*
X858850Y828917D01*
X858683Y828417D01*
Y827917D01*
X858850Y827417D01*
X859267Y826917D01*
X859767Y826583D01*
X860350Y826500D01*
X860933Y826667D01*
X861517Y827167D01*
G01X864533Y826500D02*
Y829833D01*
G01Y829167D02*
X864950Y829500D01*
X865367Y829750D01*
X865950Y829833D01*
X866367Y829750D01*
X866867Y829500D01*
G01X872800Y826500D02*
Y829833D01*
G01Y829250D02*
X872467Y829583D01*
X871967Y829750D01*
X871383Y829833D01*
X870800Y829667D01*
X870300Y829333D01*
X869967Y828833D01*
X869800Y828167D01*
X869967Y827500D01*
X870300Y827000D01*
X870800Y826667D01*
X871383Y826500D01*
X871967Y826583D01*
X872467Y826833D01*
X872800Y827167D01*
G01X875483Y826500D02*
Y829833D01*
G01Y829000D02*
X875817Y829417D01*
X876317Y829750D01*
X876983Y829833D01*
X877567Y829750D01*
X878067Y829417D01*
X878317Y828833D01*
Y826500D01*
G01X883833Y829417D02*
X883250Y829750D01*
X882750Y829833D01*
X882083Y829667D01*
X881583Y829333D01*
X881250Y828750D01*
X881167Y828167D01*
X881250Y827583D01*
X881583Y827083D01*
X882083Y826667D01*
X882750Y826500D01*
X883333Y826667D01*
X883833Y827000D01*
G01X886850Y828750D02*
X889517D01*
X889267Y829333D01*
X888850Y829667D01*
X888267Y829833D01*
X887683Y829750D01*
X887183Y829500D01*
X886850Y828917D01*
X886683Y828417D01*
Y827917D01*
X886850Y827417D01*
X887267Y826917D01*
X887767Y826583D01*
X888350Y826500D01*
X888933Y826667D01*
X889517Y827167D01*
G01X909000Y67500D02*
Y72500D01*
X905917Y68917D01*
X910083D01*
G01X911767Y68250D02*
X912267Y67833D01*
X912850Y67583D01*
X913600Y67500D01*
X914350Y67667D01*
X914933Y68000D01*
X915350Y68583D01*
X915433Y69250D01*
X915267Y69917D01*
X914850Y70333D01*
X914267Y70667D01*
X913683Y70750D01*
X913100Y70667D01*
X912350Y70333D01*
X912600Y72500D01*
X914850D01*
G01X909000Y67500D02*
Y72500D01*
X905917Y68917D01*
X910083D01*
G01X911767Y68250D02*
X912267Y67833D01*
X912850Y67583D01*
X913600Y67500D01*
X914350Y67667D01*
X914933Y68000D01*
X915350Y68583D01*
X915433Y69250D01*
X915267Y69917D01*
X914850Y70333D01*
X914267Y70667D01*
X913683Y70750D01*
X913100Y70667D01*
X912350Y70333D01*
X912600Y72500D01*
X914850D01*
G01X868250Y152000D02*
Y157000D01*
G01X871750D02*
Y152000D01*
G01Y154500D02*
X868250D01*
G01X875600Y152000D02*
X874933Y152083D01*
X874350Y152417D01*
X873850Y152917D01*
X873517Y153500D01*
X873350Y154167D01*
Y154833D01*
X873517Y155500D01*
X873850Y156083D01*
X874350Y156583D01*
X874933Y156917D01*
X875600Y157000D01*
X876267Y156917D01*
X876850Y156583D01*
X877350Y156083D01*
X877683Y155500D01*
X877850Y154833D01*
Y154167D01*
X877683Y153500D01*
X877350Y152917D01*
X876850Y152417D01*
X876267Y152083D01*
X875600Y152000D01*
G01X879533Y157000D02*
Y152000D01*
X882867D01*
G01X888467D02*
X885133D01*
Y157000D01*
X888467D01*
G01X887133Y154583D02*
X885133D01*
G01X912300Y152000D02*
Y155333D01*
G01Y154417D02*
X912550Y154833D01*
X912967Y155167D01*
X913550Y155333D01*
X914133Y155167D01*
X914550Y154833D01*
X914800Y154417D01*
Y152000D01*
G01Y154417D02*
X915050Y154833D01*
X915467Y155167D01*
X916050Y155333D01*
X916633Y155167D01*
X917050Y154833D01*
X917300Y154333D01*
Y152000D01*
G01X920400Y155333D02*
Y152000D01*
G01Y156667D02*
X920233Y156750D01*
Y156917D01*
X920400Y157000D01*
X920567Y156917D01*
Y156750D01*
X920400Y156667D01*
G01X926000Y152000D02*
Y157000D01*
G01X930350Y152583D02*
X930767Y152250D01*
X931350Y152000D01*
X931850D01*
X932350Y152167D01*
X932683Y152417D01*
X932850Y152750D01*
X932767Y153250D01*
X932433Y153500D01*
X930933Y154000D01*
X930600Y154583D01*
X930767Y155000D01*
X931100Y155250D01*
X931600Y155333D01*
X932100Y155250D01*
X932600Y155000D01*
G01X936783Y150333D02*
X935950Y151167D01*
X935533Y152000D01*
Y155333D01*
X935950Y156167D01*
X936783Y157000D01*
G01X941133Y152000D02*
Y157000D01*
X943133D01*
X943800Y156750D01*
X944300Y156167D01*
X944467Y155500D01*
X944300Y154833D01*
X943883Y154333D01*
X943133Y154083D01*
X941133D01*
G01X948400Y157000D02*
Y152000D01*
G01X946483Y157000D02*
X950317D01*
G01X952250Y152000D02*
Y157000D01*
G01X955750D02*
Y152000D01*
G01Y154500D02*
X952250D01*
G01X960017Y150333D02*
X960850Y151167D01*
X961267Y152000D01*
Y155333D01*
X960850Y156167D01*
X960017Y157000D01*
G01X868250Y152000D02*
Y157000D01*
G01X871750D02*
Y152000D01*
G01Y154500D02*
X868250D01*
G01X875600Y152000D02*
X874933Y152083D01*
X874350Y152417D01*
X873850Y152917D01*
X873517Y153500D01*
X873350Y154167D01*
Y154833D01*
X873517Y155500D01*
X873850Y156083D01*
X874350Y156583D01*
X874933Y156917D01*
X875600Y157000D01*
X876267Y156917D01*
X876850Y156583D01*
X877350Y156083D01*
X877683Y155500D01*
X877850Y154833D01*
Y154167D01*
X877683Y153500D01*
X877350Y152917D01*
X876850Y152417D01*
X876267Y152083D01*
X875600Y152000D01*
G01X879533Y157000D02*
Y152000D01*
X882867D01*
G01X888467D02*
X885133D01*
Y157000D01*
X888467D01*
G01X887133Y154583D02*
X885133D01*
G01X912300Y152000D02*
Y155333D01*
G01Y154417D02*
X912550Y154833D01*
X912967Y155167D01*
X913550Y155333D01*
X914133Y155167D01*
X914550Y154833D01*
X914800Y154417D01*
Y152000D01*
G01Y154417D02*
X915050Y154833D01*
X915467Y155167D01*
X916050Y155333D01*
X916633Y155167D01*
X917050Y154833D01*
X917300Y154333D01*
Y152000D01*
G01X920400Y155333D02*
Y152000D01*
G01Y156667D02*
X920233Y156750D01*
Y156917D01*
X920400Y157000D01*
X920567Y156917D01*
Y156750D01*
X920400Y156667D01*
G01X926000Y152000D02*
Y157000D01*
G01X930350Y152583D02*
X930767Y152250D01*
X931350Y152000D01*
X931850D01*
X932350Y152167D01*
X932683Y152417D01*
X932850Y152750D01*
X932767Y153250D01*
X932433Y153500D01*
X930933Y154000D01*
X930600Y154583D01*
X930767Y155000D01*
X931100Y155250D01*
X931600Y155333D01*
X932100Y155250D01*
X932600Y155000D01*
G01X936783Y150333D02*
X935950Y151167D01*
X935533Y152000D01*
Y155333D01*
X935950Y156167D01*
X936783Y157000D01*
G01X941133Y152000D02*
Y157000D01*
X943133D01*
X943800Y156750D01*
X944300Y156167D01*
X944467Y155500D01*
X944300Y154833D01*
X943883Y154333D01*
X943133Y154083D01*
X941133D01*
G01X948400Y157000D02*
Y152000D01*
G01X946483Y157000D02*
X950317D01*
G01X952250Y152000D02*
Y157000D01*
G01X955750D02*
Y152000D01*
G01Y154500D02*
X952250D01*
G01X960017Y150333D02*
X960850Y151167D01*
X961267Y152000D01*
Y155333D01*
X960850Y156167D01*
X960017Y157000D01*
G01X900833Y214500D02*
Y209500D01*
X904167D01*
G01X906683D02*
Y212833D01*
G01Y212000D02*
X907017Y212417D01*
X907517Y212750D01*
X908183Y212833D01*
X908767Y212750D01*
X909267Y212417D01*
X909517Y211833D01*
Y209500D01*
G01X902833Y255500D02*
Y250500D01*
X906167D01*
G01X908850Y253833D02*
X911350Y250500D01*
G01Y253833D02*
X908850Y250500D01*
G01X900833Y214500D02*
Y209500D01*
X904167D01*
G01X906683D02*
Y212833D01*
G01Y212000D02*
X907017Y212417D01*
X907517Y212750D01*
X908183Y212833D01*
X908767Y212750D01*
X909267Y212417D01*
X909517Y211833D01*
Y209500D01*
G01X902833Y255500D02*
Y250500D01*
X906167D01*
G01X908850Y253833D02*
X911350Y250500D01*
G01Y253833D02*
X908850Y250500D01*
G01X868167Y308167D02*
X868500Y308417D01*
X868750Y308833D01*
X868917Y309417D01*
X868750Y309917D01*
X868417Y310250D01*
X867833Y310500D01*
X865583D01*
Y305500D01*
X868333D01*
X868917Y305833D01*
X869250Y306333D01*
X869417Y306917D01*
X869250Y307500D01*
X868750Y308000D01*
X868167Y308167D01*
X865583D01*
G01X871017Y305500D02*
X873100Y310500D01*
X875183Y305500D01*
G01X874433Y307250D02*
X871767D01*
G01X880533Y310083D02*
X880033Y310333D01*
X879450Y310500D01*
X878783D01*
X878033Y310250D01*
X877450Y309833D01*
X877033Y309333D01*
X876700Y308500D01*
X876617Y307750D01*
X876783Y307000D01*
X877033Y306500D01*
X877533Y306000D01*
X878117Y305667D01*
X878700Y305500D01*
X879283D01*
X879867Y305667D01*
X880367Y305917D01*
X880783Y306250D01*
G01X882467Y305500D02*
Y310500D01*
G01X885633D02*
X882467Y307417D01*
G01X886133Y305500D02*
X883883Y308833D01*
G01X893667Y305500D02*
Y310500D01*
X895333D01*
X896000Y310250D01*
X896500Y309917D01*
X896917Y309417D01*
X897250Y308833D01*
X897333Y308000D01*
X897250Y307167D01*
X896917Y306583D01*
X896500Y306083D01*
X896000Y305750D01*
X895333Y305500D01*
X893667D01*
G01X899433D02*
Y310500D01*
X901517D01*
X902183Y310250D01*
X902600Y309917D01*
X902767Y309250D01*
X902600Y308583D01*
X902100Y308167D01*
X901517Y307917D01*
X899433D01*
G01X901517D02*
X902767Y305500D01*
G01X905700Y310500D02*
X907700D01*
G01X906700D02*
Y305500D01*
G01X905700D02*
X907700D01*
G01X910633Y310500D02*
Y305500D01*
X913967D01*
G01X916233Y310500D02*
Y305500D01*
X919567D01*
G01X943400D02*
Y308833D01*
G01Y307917D02*
X943650Y308333D01*
X944067Y308667D01*
X944650Y308833D01*
X945233Y308667D01*
X945650Y308333D01*
X945900Y307917D01*
Y305500D01*
G01Y307917D02*
X946150Y308333D01*
X946567Y308667D01*
X947150Y308833D01*
X947733Y308667D01*
X948150Y308333D01*
X948400Y307833D01*
Y305500D01*
G01X951500Y308833D02*
Y305500D01*
G01Y310167D02*
X951333Y310250D01*
Y310417D01*
X951500Y310500D01*
X951667Y310417D01*
Y310250D01*
X951500Y310167D01*
G01X957100Y305500D02*
Y310500D01*
G01X961450Y306083D02*
X961867Y305750D01*
X962450Y305500D01*
X962950D01*
X963450Y305667D01*
X963783Y305917D01*
X963950Y306250D01*
X963867Y306750D01*
X963533Y307000D01*
X962033Y307500D01*
X961700Y308083D01*
X961867Y308500D01*
X962200Y308750D01*
X962700Y308833D01*
X963200Y308750D01*
X963700Y308500D01*
G01X967883Y303833D02*
X967050Y304667D01*
X966633Y305500D01*
Y308833D01*
X967050Y309667D01*
X967883Y310500D01*
G01X971983Y305500D02*
Y310500D01*
X975817Y305500D01*
Y310500D01*
G01X977833Y305500D02*
Y310500D01*
X979833D01*
X980500Y310250D01*
X981000Y309667D01*
X981167Y309000D01*
X981000Y308333D01*
X980583Y307833D01*
X979833Y307583D01*
X977833D01*
G01X985100Y310500D02*
Y305500D01*
G01X983183Y310500D02*
X987017D01*
G01X988950Y305500D02*
Y310500D01*
G01X992450D02*
Y305500D01*
G01Y308000D02*
X988950D01*
G01X996717Y303833D02*
X997550Y304667D01*
X997967Y305500D01*
Y308833D01*
X997550Y309667D01*
X996717Y310500D01*
G01X868167Y308167D02*
X868500Y308417D01*
X868750Y308833D01*
X868917Y309417D01*
X868750Y309917D01*
X868417Y310250D01*
X867833Y310500D01*
X865583D01*
Y305500D01*
X868333D01*
X868917Y305833D01*
X869250Y306333D01*
X869417Y306917D01*
X869250Y307500D01*
X868750Y308000D01*
X868167Y308167D01*
X865583D01*
G01X871017Y305500D02*
X873100Y310500D01*
X875183Y305500D01*
G01X874433Y307250D02*
X871767D01*
G01X880533Y310083D02*
X880033Y310333D01*
X879450Y310500D01*
X878783D01*
X878033Y310250D01*
X877450Y309833D01*
X877033Y309333D01*
X876700Y308500D01*
X876617Y307750D01*
X876783Y307000D01*
X877033Y306500D01*
X877533Y306000D01*
X878117Y305667D01*
X878700Y305500D01*
X879283D01*
X879867Y305667D01*
X880367Y305917D01*
X880783Y306250D01*
G01X882467Y305500D02*
Y310500D01*
G01X885633D02*
X882467Y307417D01*
G01X886133Y305500D02*
X883883Y308833D01*
G01X893667Y305500D02*
Y310500D01*
X895333D01*
X896000Y310250D01*
X896500Y309917D01*
X896917Y309417D01*
X897250Y308833D01*
X897333Y308000D01*
X897250Y307167D01*
X896917Y306583D01*
X896500Y306083D01*
X896000Y305750D01*
X895333Y305500D01*
X893667D01*
G01X899433D02*
Y310500D01*
X901517D01*
X902183Y310250D01*
X902600Y309917D01*
X902767Y309250D01*
X902600Y308583D01*
X902100Y308167D01*
X901517Y307917D01*
X899433D01*
G01X901517D02*
X902767Y305500D01*
G01X905700Y310500D02*
X907700D01*
G01X906700D02*
Y305500D01*
G01X905700D02*
X907700D01*
G01X910633Y310500D02*
Y305500D01*
X913967D01*
G01X916233Y310500D02*
Y305500D01*
X919567D01*
G01X943400D02*
Y308833D01*
G01Y307917D02*
X943650Y308333D01*
X944067Y308667D01*
X944650Y308833D01*
X945233Y308667D01*
X945650Y308333D01*
X945900Y307917D01*
Y305500D01*
G01Y307917D02*
X946150Y308333D01*
X946567Y308667D01*
X947150Y308833D01*
X947733Y308667D01*
X948150Y308333D01*
X948400Y307833D01*
Y305500D01*
G01X951500Y308833D02*
Y305500D01*
G01Y310167D02*
X951333Y310250D01*
Y310417D01*
X951500Y310500D01*
X951667Y310417D01*
Y310250D01*
X951500Y310167D01*
G01X957100Y305500D02*
Y310500D01*
G01X961450Y306083D02*
X961867Y305750D01*
X962450Y305500D01*
X962950D01*
X963450Y305667D01*
X963783Y305917D01*
X963950Y306250D01*
X963867Y306750D01*
X963533Y307000D01*
X962033Y307500D01*
X961700Y308083D01*
X961867Y308500D01*
X962200Y308750D01*
X962700Y308833D01*
X963200Y308750D01*
X963700Y308500D01*
G01X967883Y303833D02*
X967050Y304667D01*
X966633Y305500D01*
Y308833D01*
X967050Y309667D01*
X967883Y310500D01*
G01X971983Y305500D02*
Y310500D01*
X975817Y305500D01*
Y310500D01*
G01X977833Y305500D02*
Y310500D01*
X979833D01*
X980500Y310250D01*
X981000Y309667D01*
X981167Y309000D01*
X981000Y308333D01*
X980583Y307833D01*
X979833Y307583D01*
X977833D01*
G01X985100Y310500D02*
Y305500D01*
G01X983183Y310500D02*
X987017D01*
G01X988950Y305500D02*
Y310500D01*
G01X992450D02*
Y305500D01*
G01Y308000D02*
X988950D01*
G01X996717Y303833D02*
X997550Y304667D01*
X997967Y305500D01*
Y308833D01*
X997550Y309667D01*
X996717Y310500D01*
G01X889267Y349073D02*
X892933Y352740D01*
G01X891100Y353407D02*
Y348407D01*
G01X892933Y349073D02*
X889267Y352740D01*
G01X888600Y350907D02*
X893600D01*
G01X896283Y347573D02*
X895450Y348407D01*
X895033Y349240D01*
Y352573D01*
X895450Y353407D01*
X896283Y354240D01*
G01X900467Y349990D02*
X900967Y349573D01*
X901550Y349323D01*
X902300Y349240D01*
X903050Y349407D01*
X903633Y349740D01*
X904050Y350323D01*
X904133Y350990D01*
X903967Y351657D01*
X903550Y352073D01*
X902967Y352407D01*
X902383Y352490D01*
X901800Y352407D01*
X901050Y352073D01*
X901300Y354240D01*
X903550D01*
G01X907900Y349073D02*
X907733Y349157D01*
Y349323D01*
X907900Y349407D01*
X908067Y349323D01*
Y349157D01*
X907900Y349073D01*
G01X913500Y349240D02*
Y354240D01*
X912500Y353240D01*
G01Y349240D02*
X914500D01*
G01X919517Y347573D02*
X920350Y348407D01*
X920767Y349240D01*
Y352573D01*
X920350Y353407D01*
X919517Y354240D01*
G01X889267Y349073D02*
X892933Y352740D01*
G01X891100Y353407D02*
Y348407D01*
G01X892933Y349073D02*
X889267Y352740D01*
G01X888600Y350907D02*
X893600D01*
G01X896283Y347573D02*
X895450Y348407D01*
X895033Y349240D01*
Y352573D01*
X895450Y353407D01*
X896283Y354240D01*
G01X900467Y349990D02*
X900967Y349573D01*
X901550Y349323D01*
X902300Y349240D01*
X903050Y349407D01*
X903633Y349740D01*
X904050Y350323D01*
X904133Y350990D01*
X903967Y351657D01*
X903550Y352073D01*
X902967Y352407D01*
X902383Y352490D01*
X901800Y352407D01*
X901050Y352073D01*
X901300Y354240D01*
X903550D01*
G01X907900Y349073D02*
X907733Y349157D01*
Y349323D01*
X907900Y349407D01*
X908067Y349323D01*
Y349157D01*
X907900Y349073D01*
G01X913500Y349240D02*
Y354240D01*
X912500Y353240D01*
G01Y349240D02*
X914500D01*
G01X919517Y347573D02*
X920350Y348407D01*
X920767Y349240D01*
Y352573D01*
X920350Y353407D01*
X919517Y354240D01*
G01X829750Y542583D02*
X830167Y542250D01*
X830750Y542000D01*
X831250D01*
X831750Y542167D01*
X832083Y542417D01*
X832250Y542750D01*
X832167Y543250D01*
X831833Y543500D01*
X830333Y544000D01*
X830000Y544583D01*
X830167Y545000D01*
X830500Y545250D01*
X831000Y545333D01*
X831500Y545250D01*
X832000Y545000D01*
G01X836600Y542000D02*
X836100Y542083D01*
X835600Y542417D01*
X835267Y543000D01*
X835100Y543667D01*
X835267Y544333D01*
X835600Y544917D01*
X836100Y545250D01*
X836600Y545333D01*
X837100Y545250D01*
X837600Y544917D01*
X837933Y544333D01*
X838017Y543667D01*
X837933Y543000D01*
X837600Y542417D01*
X837100Y542083D01*
X836600Y542000D01*
G01X842200D02*
Y547000D01*
G01X849300D02*
Y542000D01*
G01Y542750D02*
X848967Y542333D01*
X848467Y542083D01*
X847883Y542000D01*
X847217Y542167D01*
X846717Y542583D01*
X846383Y543083D01*
X846300Y543667D01*
X846383Y544250D01*
X846717Y544750D01*
X847217Y545167D01*
X847883Y545333D01*
X848467Y545250D01*
X848883Y545083D01*
X849300Y544750D01*
G01X852150Y544250D02*
X854817D01*
X854567Y544833D01*
X854150Y545167D01*
X853567Y545333D01*
X852983Y545250D01*
X852483Y545000D01*
X852150Y544417D01*
X851983Y543917D01*
Y543417D01*
X852150Y542917D01*
X852567Y542417D01*
X853067Y542083D01*
X853650Y542000D01*
X854233Y542167D01*
X854817Y542667D01*
G01X857833Y542000D02*
Y545333D01*
G01Y544667D02*
X858250Y545000D01*
X858667Y545250D01*
X859250Y545333D01*
X859667Y545250D01*
X860167Y545000D01*
G01X867700Y542000D02*
Y545333D01*
G01Y544417D02*
X867950Y544833D01*
X868367Y545167D01*
X868950Y545333D01*
X869533Y545167D01*
X869950Y544833D01*
X870200Y544417D01*
Y542000D01*
G01Y544417D02*
X870450Y544833D01*
X870867Y545167D01*
X871450Y545333D01*
X872033Y545167D01*
X872450Y544833D01*
X872700Y544333D01*
Y542000D01*
G01X877300D02*
Y545333D01*
G01Y544750D02*
X876967Y545083D01*
X876467Y545250D01*
X875883Y545333D01*
X875300Y545167D01*
X874800Y544833D01*
X874467Y544333D01*
X874300Y543667D01*
X874467Y543000D01*
X874800Y542500D01*
X875300Y542167D01*
X875883Y542000D01*
X876467Y542083D01*
X876967Y542333D01*
X877300Y542667D01*
G01X880150Y542583D02*
X880567Y542250D01*
X881150Y542000D01*
X881650D01*
X882150Y542167D01*
X882483Y542417D01*
X882650Y542750D01*
X882567Y543250D01*
X882233Y543500D01*
X880733Y544000D01*
X880400Y544583D01*
X880567Y545000D01*
X880900Y545250D01*
X881400Y545333D01*
X881900Y545250D01*
X882400Y545000D01*
G01X885583Y542000D02*
Y547000D01*
G01X888250Y545333D02*
X885583Y543417D01*
G01X886667Y544167D02*
X888417Y542000D01*
G01X896700Y540333D02*
Y545333D01*
G01Y544583D02*
X897117Y545000D01*
X897533Y545250D01*
X898200Y545333D01*
X898783Y545250D01*
X899367Y544833D01*
X899617Y544250D01*
X899700Y543667D01*
X899617Y543083D01*
X899367Y542500D01*
X898867Y542167D01*
X898200Y542000D01*
X897617Y542083D01*
X897033Y542333D01*
X896700Y542667D01*
G01X905300Y542000D02*
Y545333D01*
G01Y544750D02*
X904967Y545083D01*
X904467Y545250D01*
X903883Y545333D01*
X903300Y545167D01*
X902800Y544833D01*
X902467Y544333D01*
X902300Y543667D01*
X902467Y543000D01*
X902800Y542500D01*
X903300Y542167D01*
X903883Y542000D01*
X904467Y542083D01*
X904967Y542333D01*
X905300Y542667D01*
G01X910900Y547000D02*
Y542000D01*
G01Y542750D02*
X910567Y542333D01*
X910067Y542083D01*
X909483Y542000D01*
X908817Y542167D01*
X908317Y542583D01*
X907983Y543083D01*
X907900Y543667D01*
X907983Y544250D01*
X908317Y544750D01*
X908817Y545167D01*
X909483Y545333D01*
X910067Y545250D01*
X910483Y545083D01*
X910900Y544750D01*
G01X829917Y563333D02*
X830917Y560000D01*
X832000Y563333D01*
X833083Y560000D01*
X834083Y563333D01*
G01X836183Y560000D02*
Y565000D01*
G01Y562583D02*
X836600Y563000D01*
X837017Y563250D01*
X837683Y563333D01*
X838183Y563250D01*
X838767Y562917D01*
X839017Y562417D01*
Y560000D01*
G01X843200Y563333D02*
Y560000D01*
G01Y564667D02*
X843033Y564750D01*
Y564917D01*
X843200Y565000D01*
X843367Y564917D01*
Y564750D01*
X843200Y564667D01*
G01X850133Y562917D02*
X849550Y563250D01*
X849050Y563333D01*
X848383Y563167D01*
X847883Y562833D01*
X847550Y562250D01*
X847467Y561667D01*
X847550Y561083D01*
X847883Y560583D01*
X848383Y560167D01*
X849050Y560000D01*
X849633Y560167D01*
X850133Y560500D01*
G01X852983Y560000D02*
Y565000D01*
G01Y562583D02*
X853400Y563000D01*
X853817Y563250D01*
X854483Y563333D01*
X854983Y563250D01*
X855567Y562917D01*
X855817Y562417D01*
Y560000D01*
G01X864350Y560583D02*
X864767Y560250D01*
X865350Y560000D01*
X865850D01*
X866350Y560167D01*
X866683Y560417D01*
X866850Y560750D01*
X866767Y561250D01*
X866433Y561500D01*
X864933Y562000D01*
X864600Y562583D01*
X864767Y563000D01*
X865100Y563250D01*
X865600Y563333D01*
X866100Y563250D01*
X866600Y563000D01*
G01X871200Y563333D02*
Y560000D01*
G01Y564667D02*
X871033Y564750D01*
Y564917D01*
X871200Y565000D01*
X871367Y564917D01*
Y564750D01*
X871200Y564667D01*
G01X875550Y563333D02*
X878050D01*
X875550Y560000D01*
X878050D01*
G01X881150Y562250D02*
X883817D01*
X883567Y562833D01*
X883150Y563167D01*
X882567Y563333D01*
X881983Y563250D01*
X881483Y563000D01*
X881150Y562417D01*
X880983Y561917D01*
Y561417D01*
X881150Y560917D01*
X881567Y560417D01*
X882067Y560083D01*
X882650Y560000D01*
X883233Y560167D01*
X883817Y560667D01*
G01X893600Y563333D02*
Y560000D01*
G01Y564667D02*
X893433Y564750D01*
Y564917D01*
X893600Y565000D01*
X893767Y564917D01*
Y564750D01*
X893600Y564667D01*
G01X897950Y560583D02*
X898367Y560250D01*
X898950Y560000D01*
X899450D01*
X899950Y560167D01*
X900283Y560417D01*
X900450Y560750D01*
X900367Y561250D01*
X900033Y561500D01*
X898533Y562000D01*
X898200Y562583D01*
X898367Y563000D01*
X898700Y563250D01*
X899200Y563333D01*
X899700Y563250D01*
X900200Y563000D01*
G01X908900Y560000D02*
Y565000D01*
G01Y562500D02*
X909317Y563000D01*
X909817Y563250D01*
X910317Y563333D01*
X911067Y563167D01*
X911567Y562833D01*
X911900Y562250D01*
Y561583D01*
X911733Y560917D01*
X911400Y560417D01*
X910817Y560083D01*
X910317Y560000D01*
X909817Y560083D01*
X909317Y560333D01*
X908900Y560750D01*
G01X916000Y563333D02*
Y560000D01*
G01Y564667D02*
X915833Y564750D01*
Y564917D01*
X916000Y565000D01*
X916167Y564917D01*
Y564750D01*
X916000Y564667D01*
G01X920433Y558750D02*
X921017Y558417D01*
X921683Y558333D01*
X922267Y558417D01*
X922767Y558833D01*
X923100Y559417D01*
Y563333D01*
G01Y562667D02*
X922767Y563000D01*
X922267Y563250D01*
X921683Y563333D01*
X921017Y563167D01*
X920600Y562833D01*
X920267Y562250D01*
X920100Y561667D01*
X920183Y561167D01*
X920517Y560583D01*
X921017Y560167D01*
X921683Y560000D01*
X922183Y560083D01*
X922767Y560417D01*
X923100Y560750D01*
G01X926033Y558750D02*
X926617Y558417D01*
X927283Y558333D01*
X927867Y558417D01*
X928367Y558833D01*
X928700Y559417D01*
Y563333D01*
G01Y562667D02*
X928367Y563000D01*
X927867Y563250D01*
X927283Y563333D01*
X926617Y563167D01*
X926200Y562833D01*
X925867Y562250D01*
X925700Y561667D01*
X925783Y561167D01*
X926117Y560583D01*
X926617Y560167D01*
X927283Y560000D01*
X927783Y560083D01*
X928367Y560417D01*
X928700Y560750D01*
G01X931550Y562250D02*
X934217D01*
X933967Y562833D01*
X933550Y563167D01*
X932967Y563333D01*
X932383Y563250D01*
X931883Y563000D01*
X931550Y562417D01*
X931383Y561917D01*
Y561417D01*
X931550Y560917D01*
X931967Y560417D01*
X932467Y560083D01*
X933050Y560000D01*
X933633Y560167D01*
X934217Y560667D01*
G01X937233Y560000D02*
Y563333D01*
G01Y562667D02*
X937650Y563000D01*
X938067Y563250D01*
X938650Y563333D01*
X939067Y563250D01*
X939567Y563000D01*
G01X949600Y565000D02*
Y560000D01*
G01X948433Y563333D02*
X950767D01*
G01X953783Y560000D02*
Y565000D01*
G01Y562583D02*
X954200Y563000D01*
X954617Y563250D01*
X955283Y563333D01*
X955783Y563250D01*
X956367Y562917D01*
X956617Y562417D01*
Y560000D01*
G01X962300D02*
Y563333D01*
G01Y562750D02*
X961967Y563083D01*
X961467Y563250D01*
X960883Y563333D01*
X960300Y563167D01*
X959800Y562833D01*
X959467Y562333D01*
X959300Y561667D01*
X959467Y561000D01*
X959800Y560500D01*
X960300Y560167D01*
X960883Y560000D01*
X961467Y560083D01*
X961967Y560333D01*
X962300Y560667D01*
G01X964983Y560000D02*
Y563333D01*
G01Y562500D02*
X965317Y562917D01*
X965817Y563250D01*
X966483Y563333D01*
X967067Y563250D01*
X967567Y562917D01*
X967817Y562333D01*
Y560000D01*
G01X979100D02*
Y563333D01*
G01Y562750D02*
X978767Y563083D01*
X978267Y563250D01*
X977683Y563333D01*
X977100Y563167D01*
X976600Y562833D01*
X976267Y562333D01*
X976100Y561667D01*
X976267Y561000D01*
X976600Y560500D01*
X977100Y560167D01*
X977683Y560000D01*
X978267Y560083D01*
X978767Y560333D01*
X979100Y560667D01*
G01X981783Y560000D02*
Y563333D01*
G01Y562500D02*
X982117Y562917D01*
X982617Y563250D01*
X983283Y563333D01*
X983867Y563250D01*
X984367Y562917D01*
X984617Y562333D01*
Y560000D01*
G01X987383D02*
Y563333D01*
G01Y562500D02*
X987717Y562917D01*
X988217Y563250D01*
X988883Y563333D01*
X989467Y563250D01*
X989967Y562917D01*
X990217Y562333D01*
Y560000D01*
G01X992983Y563333D02*
Y561000D01*
X993317Y560417D01*
X993817Y560083D01*
X994400Y560000D01*
X994983Y560083D01*
X995483Y560417D01*
X995817Y561000D01*
G01Y560000D02*
Y563333D01*
G01X1001500Y560000D02*
Y563333D01*
G01Y562750D02*
X1001167Y563083D01*
X1000667Y563250D01*
X1000083Y563333D01*
X999500Y563167D01*
X999000Y562833D01*
X998667Y562333D01*
X998500Y561667D01*
X998667Y561000D01*
X999000Y560500D01*
X999500Y560167D01*
X1000083Y560000D01*
X1000667Y560083D01*
X1001167Y560333D01*
X1001500Y560667D01*
G01X1005600Y560000D02*
Y565000D01*
G01X894000Y556000D02*
Y551000D01*
G01X892833Y554333D02*
X895167D01*
G01X898183Y551000D02*
Y556000D01*
G01Y553583D02*
X898600Y554000D01*
X899017Y554250D01*
X899683Y554333D01*
X900183Y554250D01*
X900767Y553917D01*
X901017Y553417D01*
Y551000D01*
G01X903950Y553250D02*
X906617D01*
X906367Y553833D01*
X905950Y554167D01*
X905367Y554333D01*
X904783Y554250D01*
X904283Y554000D01*
X903950Y553417D01*
X903783Y552917D01*
Y552417D01*
X903950Y551917D01*
X904367Y551417D01*
X904867Y551083D01*
X905450Y551000D01*
X906033Y551167D01*
X906617Y551667D01*
G01X916400Y551000D02*
X915900Y551083D01*
X915400Y551417D01*
X915067Y552000D01*
X914900Y552667D01*
X915067Y553333D01*
X915400Y553917D01*
X915900Y554250D01*
X916400Y554333D01*
X916900Y554250D01*
X917400Y553917D01*
X917733Y553333D01*
X917817Y552667D01*
X917733Y552000D01*
X917400Y551417D01*
X916900Y551083D01*
X916400Y551000D01*
G01X922000Y556000D02*
Y551000D01*
G01X920833Y554333D02*
X923167D01*
G01X926183Y551000D02*
Y556000D01*
G01Y553583D02*
X926600Y554000D01*
X927017Y554250D01*
X927683Y554333D01*
X928183Y554250D01*
X928767Y553917D01*
X929017Y553417D01*
Y551000D01*
G01X931950Y553250D02*
X934617D01*
X934367Y553833D01*
X933950Y554167D01*
X933367Y554333D01*
X932783Y554250D01*
X932283Y554000D01*
X931950Y553417D01*
X931783Y552917D01*
Y552417D01*
X931950Y551917D01*
X932367Y551417D01*
X932867Y551083D01*
X933450Y551000D01*
X934033Y551167D01*
X934617Y551667D01*
G01X937633Y551000D02*
Y554333D01*
G01Y553667D02*
X938050Y554000D01*
X938467Y554250D01*
X939050Y554333D01*
X939467Y554250D01*
X939967Y554000D01*
G01X948750Y551583D02*
X949167Y551250D01*
X949750Y551000D01*
X950250D01*
X950750Y551167D01*
X951083Y551417D01*
X951250Y551750D01*
X951167Y552250D01*
X950833Y552500D01*
X949333Y553000D01*
X949000Y553583D01*
X949167Y554000D01*
X949500Y554250D01*
X950000Y554333D01*
X950500Y554250D01*
X951000Y554000D01*
G01X955600Y554333D02*
Y551000D01*
G01Y555667D02*
X955433Y555750D01*
Y555917D01*
X955600Y556000D01*
X955767Y555917D01*
Y555750D01*
X955600Y555667D01*
G01X962700Y556000D02*
Y551000D01*
G01Y551750D02*
X962367Y551333D01*
X961867Y551083D01*
X961283Y551000D01*
X960617Y551167D01*
X960117Y551583D01*
X959783Y552083D01*
X959700Y552667D01*
X959783Y553250D01*
X960117Y553750D01*
X960617Y554167D01*
X961283Y554333D01*
X961867Y554250D01*
X962283Y554083D01*
X962700Y553750D01*
G01X965550Y553250D02*
X968217D01*
X967967Y553833D01*
X967550Y554167D01*
X966967Y554333D01*
X966383Y554250D01*
X965883Y554000D01*
X965550Y553417D01*
X965383Y552917D01*
Y552417D01*
X965550Y551917D01*
X965967Y551417D01*
X966467Y551083D01*
X967050Y551000D01*
X967633Y551167D01*
X968217Y551667D01*
G01X975917Y554333D02*
X976917Y551000D01*
X978000Y554333D01*
X979083Y551000D01*
X980083Y554333D01*
G01X983600D02*
Y551000D01*
G01Y555667D02*
X983433Y555750D01*
Y555917D01*
X983600Y556000D01*
X983767Y555917D01*
Y555750D01*
X983600Y555667D01*
G01X989200Y556000D02*
Y551000D01*
G01X988033Y554333D02*
X990367D01*
G01X993383Y551000D02*
Y556000D01*
G01Y553583D02*
X993800Y554000D01*
X994217Y554250D01*
X994883Y554333D01*
X995383Y554250D01*
X995967Y553917D01*
X996217Y553417D01*
Y551000D01*
G01X1000400D02*
X999900Y551083D01*
X999400Y551417D01*
X999067Y552000D01*
X998900Y552667D01*
X999067Y553333D01*
X999400Y553917D01*
X999900Y554250D01*
X1000400Y554333D01*
X1000900Y554250D01*
X1001400Y553917D01*
X1001733Y553333D01*
X1001817Y552667D01*
X1001733Y552000D01*
X1001400Y551417D01*
X1000900Y551083D01*
X1000400Y551000D01*
G01X1004583Y554333D02*
Y552000D01*
X1004917Y551417D01*
X1005417Y551083D01*
X1006000Y551000D01*
X1006583Y551083D01*
X1007083Y551417D01*
X1007417Y552000D01*
G01Y551000D02*
Y554333D01*
G01X1011600Y556000D02*
Y551000D01*
G01X1010433Y554333D02*
X1012767D01*
G01X831333Y551000D02*
Y554333D01*
G01Y553667D02*
X831750Y554000D01*
X832167Y554250D01*
X832750Y554333D01*
X833167Y554250D01*
X833667Y554000D01*
G01X838100Y554333D02*
Y551000D01*
G01Y555667D02*
X837933Y555750D01*
Y555917D01*
X838100Y556000D01*
X838267Y555917D01*
Y555750D01*
X838100Y555667D01*
G01X842283Y551000D02*
Y554333D01*
G01Y553500D02*
X842617Y553917D01*
X843117Y554250D01*
X843783Y554333D01*
X844367Y554250D01*
X844867Y553917D01*
X845117Y553333D01*
Y551000D01*
G01X848133Y549750D02*
X848717Y549417D01*
X849383Y549333D01*
X849967Y549417D01*
X850467Y549833D01*
X850800Y550417D01*
Y554333D01*
G01Y553667D02*
X850467Y554000D01*
X849967Y554250D01*
X849383Y554333D01*
X848717Y554167D01*
X848300Y553833D01*
X847967Y553250D01*
X847800Y552667D01*
X847883Y552167D01*
X848217Y551583D01*
X848717Y551167D01*
X849383Y551000D01*
X849883Y551083D01*
X850467Y551417D01*
X850800Y551750D01*
G01X859250Y551583D02*
X859667Y551250D01*
X860250Y551000D01*
X860750D01*
X861250Y551167D01*
X861583Y551417D01*
X861750Y551750D01*
X861667Y552250D01*
X861333Y552500D01*
X859833Y553000D01*
X859500Y553583D01*
X859667Y554000D01*
X860000Y554250D01*
X860500Y554333D01*
X861000Y554250D01*
X861500Y554000D01*
G01X866100Y554333D02*
Y551000D01*
G01Y555667D02*
X865933Y555750D01*
Y555917D01*
X866100Y556000D01*
X866267Y555917D01*
Y555750D01*
X866100Y555667D01*
G01X870450Y554333D02*
X872950D01*
X870450Y551000D01*
X872950D01*
G01X876050Y553250D02*
X878717D01*
X878467Y553833D01*
X878050Y554167D01*
X877467Y554333D01*
X876883Y554250D01*
X876383Y554000D01*
X876050Y553417D01*
X875883Y552917D01*
Y552417D01*
X876050Y551917D01*
X876467Y551417D01*
X876967Y551083D01*
X877550Y551000D01*
X878133Y551167D01*
X878717Y551667D01*
G01X888333Y550083D02*
X888667Y551167D01*
G01X829750Y542583D02*
X830167Y542250D01*
X830750Y542000D01*
X831250D01*
X831750Y542167D01*
X832083Y542417D01*
X832250Y542750D01*
X832167Y543250D01*
X831833Y543500D01*
X830333Y544000D01*
X830000Y544583D01*
X830167Y545000D01*
X830500Y545250D01*
X831000Y545333D01*
X831500Y545250D01*
X832000Y545000D01*
G01X836600Y542000D02*
X836100Y542083D01*
X835600Y542417D01*
X835267Y543000D01*
X835100Y543667D01*
X835267Y544333D01*
X835600Y544917D01*
X836100Y545250D01*
X836600Y545333D01*
X837100Y545250D01*
X837600Y544917D01*
X837933Y544333D01*
X838017Y543667D01*
X837933Y543000D01*
X837600Y542417D01*
X837100Y542083D01*
X836600Y542000D01*
G01X842200D02*
Y547000D01*
G01X849300D02*
Y542000D01*
G01Y542750D02*
X848967Y542333D01*
X848467Y542083D01*
X847883Y542000D01*
X847217Y542167D01*
X846717Y542583D01*
X846383Y543083D01*
X846300Y543667D01*
X846383Y544250D01*
X846717Y544750D01*
X847217Y545167D01*
X847883Y545333D01*
X848467Y545250D01*
X848883Y545083D01*
X849300Y544750D01*
G01X852150Y544250D02*
X854817D01*
X854567Y544833D01*
X854150Y545167D01*
X853567Y545333D01*
X852983Y545250D01*
X852483Y545000D01*
X852150Y544417D01*
X851983Y543917D01*
Y543417D01*
X852150Y542917D01*
X852567Y542417D01*
X853067Y542083D01*
X853650Y542000D01*
X854233Y542167D01*
X854817Y542667D01*
G01X857833Y542000D02*
Y545333D01*
G01Y544667D02*
X858250Y545000D01*
X858667Y545250D01*
X859250Y545333D01*
X859667Y545250D01*
X860167Y545000D01*
G01X867700Y542000D02*
Y545333D01*
G01Y544417D02*
X867950Y544833D01*
X868367Y545167D01*
X868950Y545333D01*
X869533Y545167D01*
X869950Y544833D01*
X870200Y544417D01*
Y542000D01*
G01Y544417D02*
X870450Y544833D01*
X870867Y545167D01*
X871450Y545333D01*
X872033Y545167D01*
X872450Y544833D01*
X872700Y544333D01*
Y542000D01*
G01X877300D02*
Y545333D01*
G01Y544750D02*
X876967Y545083D01*
X876467Y545250D01*
X875883Y545333D01*
X875300Y545167D01*
X874800Y544833D01*
X874467Y544333D01*
X874300Y543667D01*
X874467Y543000D01*
X874800Y542500D01*
X875300Y542167D01*
X875883Y542000D01*
X876467Y542083D01*
X876967Y542333D01*
X877300Y542667D01*
G01X880150Y542583D02*
X880567Y542250D01*
X881150Y542000D01*
X881650D01*
X882150Y542167D01*
X882483Y542417D01*
X882650Y542750D01*
X882567Y543250D01*
X882233Y543500D01*
X880733Y544000D01*
X880400Y544583D01*
X880567Y545000D01*
X880900Y545250D01*
X881400Y545333D01*
X881900Y545250D01*
X882400Y545000D01*
G01X885583Y542000D02*
Y547000D01*
G01X888250Y545333D02*
X885583Y543417D01*
G01X886667Y544167D02*
X888417Y542000D01*
G01X896700Y540333D02*
Y545333D01*
G01Y544583D02*
X897117Y545000D01*
X897533Y545250D01*
X898200Y545333D01*
X898783Y545250D01*
X899367Y544833D01*
X899617Y544250D01*
X899700Y543667D01*
X899617Y543083D01*
X899367Y542500D01*
X898867Y542167D01*
X898200Y542000D01*
X897617Y542083D01*
X897033Y542333D01*
X896700Y542667D01*
G01X905300Y542000D02*
Y545333D01*
G01Y544750D02*
X904967Y545083D01*
X904467Y545250D01*
X903883Y545333D01*
X903300Y545167D01*
X902800Y544833D01*
X902467Y544333D01*
X902300Y543667D01*
X902467Y543000D01*
X902800Y542500D01*
X903300Y542167D01*
X903883Y542000D01*
X904467Y542083D01*
X904967Y542333D01*
X905300Y542667D01*
G01X910900Y547000D02*
Y542000D01*
G01Y542750D02*
X910567Y542333D01*
X910067Y542083D01*
X909483Y542000D01*
X908817Y542167D01*
X908317Y542583D01*
X907983Y543083D01*
X907900Y543667D01*
X907983Y544250D01*
X908317Y544750D01*
X908817Y545167D01*
X909483Y545333D01*
X910067Y545250D01*
X910483Y545083D01*
X910900Y544750D01*
G01X829917Y563333D02*
X830917Y560000D01*
X832000Y563333D01*
X833083Y560000D01*
X834083Y563333D01*
G01X836183Y560000D02*
Y565000D01*
G01Y562583D02*
X836600Y563000D01*
X837017Y563250D01*
X837683Y563333D01*
X838183Y563250D01*
X838767Y562917D01*
X839017Y562417D01*
Y560000D01*
G01X843200Y563333D02*
Y560000D01*
G01Y564667D02*
X843033Y564750D01*
Y564917D01*
X843200Y565000D01*
X843367Y564917D01*
Y564750D01*
X843200Y564667D01*
G01X850133Y562917D02*
X849550Y563250D01*
X849050Y563333D01*
X848383Y563167D01*
X847883Y562833D01*
X847550Y562250D01*
X847467Y561667D01*
X847550Y561083D01*
X847883Y560583D01*
X848383Y560167D01*
X849050Y560000D01*
X849633Y560167D01*
X850133Y560500D01*
G01X852983Y560000D02*
Y565000D01*
G01Y562583D02*
X853400Y563000D01*
X853817Y563250D01*
X854483Y563333D01*
X854983Y563250D01*
X855567Y562917D01*
X855817Y562417D01*
Y560000D01*
G01X864350Y560583D02*
X864767Y560250D01*
X865350Y560000D01*
X865850D01*
X866350Y560167D01*
X866683Y560417D01*
X866850Y560750D01*
X866767Y561250D01*
X866433Y561500D01*
X864933Y562000D01*
X864600Y562583D01*
X864767Y563000D01*
X865100Y563250D01*
X865600Y563333D01*
X866100Y563250D01*
X866600Y563000D01*
G01X871200Y563333D02*
Y560000D01*
G01Y564667D02*
X871033Y564750D01*
Y564917D01*
X871200Y565000D01*
X871367Y564917D01*
Y564750D01*
X871200Y564667D01*
G01X875550Y563333D02*
X878050D01*
X875550Y560000D01*
X878050D01*
G01X881150Y562250D02*
X883817D01*
X883567Y562833D01*
X883150Y563167D01*
X882567Y563333D01*
X881983Y563250D01*
X881483Y563000D01*
X881150Y562417D01*
X880983Y561917D01*
Y561417D01*
X881150Y560917D01*
X881567Y560417D01*
X882067Y560083D01*
X882650Y560000D01*
X883233Y560167D01*
X883817Y560667D01*
G01X893600Y563333D02*
Y560000D01*
G01Y564667D02*
X893433Y564750D01*
Y564917D01*
X893600Y565000D01*
X893767Y564917D01*
Y564750D01*
X893600Y564667D01*
G01X897950Y560583D02*
X898367Y560250D01*
X898950Y560000D01*
X899450D01*
X899950Y560167D01*
X900283Y560417D01*
X900450Y560750D01*
X900367Y561250D01*
X900033Y561500D01*
X898533Y562000D01*
X898200Y562583D01*
X898367Y563000D01*
X898700Y563250D01*
X899200Y563333D01*
X899700Y563250D01*
X900200Y563000D01*
G01X908900Y560000D02*
Y565000D01*
G01Y562500D02*
X909317Y563000D01*
X909817Y563250D01*
X910317Y563333D01*
X911067Y563167D01*
X911567Y562833D01*
X911900Y562250D01*
Y561583D01*
X911733Y560917D01*
X911400Y560417D01*
X910817Y560083D01*
X910317Y560000D01*
X909817Y560083D01*
X909317Y560333D01*
X908900Y560750D01*
G01X916000Y563333D02*
Y560000D01*
G01Y564667D02*
X915833Y564750D01*
Y564917D01*
X916000Y565000D01*
X916167Y564917D01*
Y564750D01*
X916000Y564667D01*
G01X920433Y558750D02*
X921017Y558417D01*
X921683Y558333D01*
X922267Y558417D01*
X922767Y558833D01*
X923100Y559417D01*
Y563333D01*
G01Y562667D02*
X922767Y563000D01*
X922267Y563250D01*
X921683Y563333D01*
X921017Y563167D01*
X920600Y562833D01*
X920267Y562250D01*
X920100Y561667D01*
X920183Y561167D01*
X920517Y560583D01*
X921017Y560167D01*
X921683Y560000D01*
X922183Y560083D01*
X922767Y560417D01*
X923100Y560750D01*
G01X926033Y558750D02*
X926617Y558417D01*
X927283Y558333D01*
X927867Y558417D01*
X928367Y558833D01*
X928700Y559417D01*
Y563333D01*
G01Y562667D02*
X928367Y563000D01*
X927867Y563250D01*
X927283Y563333D01*
X926617Y563167D01*
X926200Y562833D01*
X925867Y562250D01*
X925700Y561667D01*
X925783Y561167D01*
X926117Y560583D01*
X926617Y560167D01*
X927283Y560000D01*
X927783Y560083D01*
X928367Y560417D01*
X928700Y560750D01*
G01X931550Y562250D02*
X934217D01*
X933967Y562833D01*
X933550Y563167D01*
X932967Y563333D01*
X932383Y563250D01*
X931883Y563000D01*
X931550Y562417D01*
X931383Y561917D01*
Y561417D01*
X931550Y560917D01*
X931967Y560417D01*
X932467Y560083D01*
X933050Y560000D01*
X933633Y560167D01*
X934217Y560667D01*
G01X937233Y560000D02*
Y563333D01*
G01Y562667D02*
X937650Y563000D01*
X938067Y563250D01*
X938650Y563333D01*
X939067Y563250D01*
X939567Y563000D01*
G01X949600Y565000D02*
Y560000D01*
G01X948433Y563333D02*
X950767D01*
G01X953783Y560000D02*
Y565000D01*
G01Y562583D02*
X954200Y563000D01*
X954617Y563250D01*
X955283Y563333D01*
X955783Y563250D01*
X956367Y562917D01*
X956617Y562417D01*
Y560000D01*
G01X962300D02*
Y563333D01*
G01Y562750D02*
X961967Y563083D01*
X961467Y563250D01*
X960883Y563333D01*
X960300Y563167D01*
X959800Y562833D01*
X959467Y562333D01*
X959300Y561667D01*
X959467Y561000D01*
X959800Y560500D01*
X960300Y560167D01*
X960883Y560000D01*
X961467Y560083D01*
X961967Y560333D01*
X962300Y560667D01*
G01X964983Y560000D02*
Y563333D01*
G01Y562500D02*
X965317Y562917D01*
X965817Y563250D01*
X966483Y563333D01*
X967067Y563250D01*
X967567Y562917D01*
X967817Y562333D01*
Y560000D01*
G01X979100D02*
Y563333D01*
G01Y562750D02*
X978767Y563083D01*
X978267Y563250D01*
X977683Y563333D01*
X977100Y563167D01*
X976600Y562833D01*
X976267Y562333D01*
X976100Y561667D01*
X976267Y561000D01*
X976600Y560500D01*
X977100Y560167D01*
X977683Y560000D01*
X978267Y560083D01*
X978767Y560333D01*
X979100Y560667D01*
G01X981783Y560000D02*
Y563333D01*
G01Y562500D02*
X982117Y562917D01*
X982617Y563250D01*
X983283Y563333D01*
X983867Y563250D01*
X984367Y562917D01*
X984617Y562333D01*
Y560000D01*
G01X987383D02*
Y563333D01*
G01Y562500D02*
X987717Y562917D01*
X988217Y563250D01*
X988883Y563333D01*
X989467Y563250D01*
X989967Y562917D01*
X990217Y562333D01*
Y560000D01*
G01X992983Y563333D02*
Y561000D01*
X993317Y560417D01*
X993817Y560083D01*
X994400Y560000D01*
X994983Y560083D01*
X995483Y560417D01*
X995817Y561000D01*
G01Y560000D02*
Y563333D01*
G01X1001500Y560000D02*
Y563333D01*
G01Y562750D02*
X1001167Y563083D01*
X1000667Y563250D01*
X1000083Y563333D01*
X999500Y563167D01*
X999000Y562833D01*
X998667Y562333D01*
X998500Y561667D01*
X998667Y561000D01*
X999000Y560500D01*
X999500Y560167D01*
X1000083Y560000D01*
X1000667Y560083D01*
X1001167Y560333D01*
X1001500Y560667D01*
G01X1005600Y560000D02*
Y565000D01*
G01X894000Y556000D02*
Y551000D01*
G01X892833Y554333D02*
X895167D01*
G01X898183Y551000D02*
Y556000D01*
G01Y553583D02*
X898600Y554000D01*
X899017Y554250D01*
X899683Y554333D01*
X900183Y554250D01*
X900767Y553917D01*
X901017Y553417D01*
Y551000D01*
G01X903950Y553250D02*
X906617D01*
X906367Y553833D01*
X905950Y554167D01*
X905367Y554333D01*
X904783Y554250D01*
X904283Y554000D01*
X903950Y553417D01*
X903783Y552917D01*
Y552417D01*
X903950Y551917D01*
X904367Y551417D01*
X904867Y551083D01*
X905450Y551000D01*
X906033Y551167D01*
X906617Y551667D01*
G01X916400Y551000D02*
X915900Y551083D01*
X915400Y551417D01*
X915067Y552000D01*
X914900Y552667D01*
X915067Y553333D01*
X915400Y553917D01*
X915900Y554250D01*
X916400Y554333D01*
X916900Y554250D01*
X917400Y553917D01*
X917733Y553333D01*
X917817Y552667D01*
X917733Y552000D01*
X917400Y551417D01*
X916900Y551083D01*
X916400Y551000D01*
G01X922000Y556000D02*
Y551000D01*
G01X920833Y554333D02*
X923167D01*
G01X926183Y551000D02*
Y556000D01*
G01Y553583D02*
X926600Y554000D01*
X927017Y554250D01*
X927683Y554333D01*
X928183Y554250D01*
X928767Y553917D01*
X929017Y553417D01*
Y551000D01*
G01X931950Y553250D02*
X934617D01*
X934367Y553833D01*
X933950Y554167D01*
X933367Y554333D01*
X932783Y554250D01*
X932283Y554000D01*
X931950Y553417D01*
X931783Y552917D01*
Y552417D01*
X931950Y551917D01*
X932367Y551417D01*
X932867Y551083D01*
X933450Y551000D01*
X934033Y551167D01*
X934617Y551667D01*
G01X937633Y551000D02*
Y554333D01*
G01Y553667D02*
X938050Y554000D01*
X938467Y554250D01*
X939050Y554333D01*
X939467Y554250D01*
X939967Y554000D01*
G01X948750Y551583D02*
X949167Y551250D01*
X949750Y551000D01*
X950250D01*
X950750Y551167D01*
X951083Y551417D01*
X951250Y551750D01*
X951167Y552250D01*
X950833Y552500D01*
X949333Y553000D01*
X949000Y553583D01*
X949167Y554000D01*
X949500Y554250D01*
X950000Y554333D01*
X950500Y554250D01*
X951000Y554000D01*
G01X955600Y554333D02*
Y551000D01*
G01Y555667D02*
X955433Y555750D01*
Y555917D01*
X955600Y556000D01*
X955767Y555917D01*
Y555750D01*
X955600Y555667D01*
G01X962700Y556000D02*
Y551000D01*
G01Y551750D02*
X962367Y551333D01*
X961867Y551083D01*
X961283Y551000D01*
X960617Y551167D01*
X960117Y551583D01*
X959783Y552083D01*
X959700Y552667D01*
X959783Y553250D01*
X960117Y553750D01*
X960617Y554167D01*
X961283Y554333D01*
X961867Y554250D01*
X962283Y554083D01*
X962700Y553750D01*
G01X965550Y553250D02*
X968217D01*
X967967Y553833D01*
X967550Y554167D01*
X966967Y554333D01*
X966383Y554250D01*
X965883Y554000D01*
X965550Y553417D01*
X965383Y552917D01*
Y552417D01*
X965550Y551917D01*
X965967Y551417D01*
X966467Y551083D01*
X967050Y551000D01*
X967633Y551167D01*
X968217Y551667D01*
G01X975917Y554333D02*
X976917Y551000D01*
X978000Y554333D01*
X979083Y551000D01*
X980083Y554333D01*
G01X983600D02*
Y551000D01*
G01Y555667D02*
X983433Y555750D01*
Y555917D01*
X983600Y556000D01*
X983767Y555917D01*
Y555750D01*
X983600Y555667D01*
G01X989200Y556000D02*
Y551000D01*
G01X988033Y554333D02*
X990367D01*
G01X993383Y551000D02*
Y556000D01*
G01Y553583D02*
X993800Y554000D01*
X994217Y554250D01*
X994883Y554333D01*
X995383Y554250D01*
X995967Y553917D01*
X996217Y553417D01*
Y551000D01*
G01X1000400D02*
X999900Y551083D01*
X999400Y551417D01*
X999067Y552000D01*
X998900Y552667D01*
X999067Y553333D01*
X999400Y553917D01*
X999900Y554250D01*
X1000400Y554333D01*
X1000900Y554250D01*
X1001400Y553917D01*
X1001733Y553333D01*
X1001817Y552667D01*
X1001733Y552000D01*
X1001400Y551417D01*
X1000900Y551083D01*
X1000400Y551000D01*
G01X1004583Y554333D02*
Y552000D01*
X1004917Y551417D01*
X1005417Y551083D01*
X1006000Y551000D01*
X1006583Y551083D01*
X1007083Y551417D01*
X1007417Y552000D01*
G01Y551000D02*
Y554333D01*
G01X1011600Y556000D02*
Y551000D01*
G01X1010433Y554333D02*
X1012767D01*
G01X831333Y551000D02*
Y554333D01*
G01Y553667D02*
X831750Y554000D01*
X832167Y554250D01*
X832750Y554333D01*
X833167Y554250D01*
X833667Y554000D01*
G01X838100Y554333D02*
Y551000D01*
G01Y555667D02*
X837933Y555750D01*
Y555917D01*
X838100Y556000D01*
X838267Y555917D01*
Y555750D01*
X838100Y555667D01*
G01X842283Y551000D02*
Y554333D01*
G01Y553500D02*
X842617Y553917D01*
X843117Y554250D01*
X843783Y554333D01*
X844367Y554250D01*
X844867Y553917D01*
X845117Y553333D01*
Y551000D01*
G01X848133Y549750D02*
X848717Y549417D01*
X849383Y549333D01*
X849967Y549417D01*
X850467Y549833D01*
X850800Y550417D01*
Y554333D01*
G01Y553667D02*
X850467Y554000D01*
X849967Y554250D01*
X849383Y554333D01*
X848717Y554167D01*
X848300Y553833D01*
X847967Y553250D01*
X847800Y552667D01*
X847883Y552167D01*
X848217Y551583D01*
X848717Y551167D01*
X849383Y551000D01*
X849883Y551083D01*
X850467Y551417D01*
X850800Y551750D01*
G01X859250Y551583D02*
X859667Y551250D01*
X860250Y551000D01*
X860750D01*
X861250Y551167D01*
X861583Y551417D01*
X861750Y551750D01*
X861667Y552250D01*
X861333Y552500D01*
X859833Y553000D01*
X859500Y553583D01*
X859667Y554000D01*
X860000Y554250D01*
X860500Y554333D01*
X861000Y554250D01*
X861500Y554000D01*
G01X866100Y554333D02*
Y551000D01*
G01Y555667D02*
X865933Y555750D01*
Y555917D01*
X866100Y556000D01*
X866267Y555917D01*
Y555750D01*
X866100Y555667D01*
G01X870450Y554333D02*
X872950D01*
X870450Y551000D01*
X872950D01*
G01X876050Y553250D02*
X878717D01*
X878467Y553833D01*
X878050Y554167D01*
X877467Y554333D01*
X876883Y554250D01*
X876383Y554000D01*
X876050Y553417D01*
X875883Y552917D01*
Y552417D01*
X876050Y551917D01*
X876467Y551417D01*
X876967Y551083D01*
X877550Y551000D01*
X878133Y551167D01*
X878717Y551667D01*
G01X888333Y550083D02*
X888667Y551167D01*
G01X878000Y591500D02*
X879667D01*
Y590000D01*
X879167Y589500D01*
X878583Y589167D01*
X877750Y589000D01*
X876917Y589167D01*
X876333Y589500D01*
X875833Y590000D01*
X875500Y590583D01*
X875333Y591250D01*
Y591833D01*
X875500Y592333D01*
X875833Y592917D01*
X876333Y593417D01*
X876833Y593750D01*
X877500Y594000D01*
X878083D01*
X878750Y593833D01*
X879250Y593500D01*
G01X881850Y591250D02*
X884517D01*
X884267Y591833D01*
X883850Y592167D01*
X883267Y592333D01*
X882683Y592250D01*
X882183Y592000D01*
X881850Y591417D01*
X881683Y590917D01*
Y590417D01*
X881850Y589917D01*
X882267Y589417D01*
X882767Y589083D01*
X883350Y589000D01*
X883933Y589167D01*
X884517Y589667D01*
G01X887533Y589000D02*
Y592333D01*
G01Y591667D02*
X887950Y592000D01*
X888367Y592250D01*
X888950Y592333D01*
X889367Y592250D01*
X889867Y592000D01*
G01X892800Y589000D02*
Y594000D01*
G01Y591500D02*
X893217Y592000D01*
X893717Y592250D01*
X894217Y592333D01*
X894967Y592167D01*
X895467Y591833D01*
X895800Y591250D01*
Y590583D01*
X895633Y589917D01*
X895300Y589417D01*
X894717Y589083D01*
X894217Y589000D01*
X893717Y589083D01*
X893217Y589333D01*
X892800Y589750D01*
G01X898650Y591250D02*
X901317D01*
X901067Y591833D01*
X900650Y592167D01*
X900067Y592333D01*
X899483Y592250D01*
X898983Y592000D01*
X898650Y591417D01*
X898483Y590917D01*
Y590417D01*
X898650Y589917D01*
X899067Y589417D01*
X899567Y589083D01*
X900150Y589000D01*
X900733Y589167D01*
X901317Y589667D01*
G01X904333Y589000D02*
Y592333D01*
G01Y591667D02*
X904750Y592000D01*
X905167Y592250D01*
X905750Y592333D01*
X906167Y592250D01*
X906667Y592000D01*
G01X918200Y594000D02*
Y589000D01*
G01Y589750D02*
X917867Y589333D01*
X917367Y589083D01*
X916783Y589000D01*
X916117Y589167D01*
X915617Y589583D01*
X915283Y590083D01*
X915200Y590667D01*
X915283Y591250D01*
X915617Y591750D01*
X916117Y592167D01*
X916783Y592333D01*
X917367Y592250D01*
X917783Y592083D01*
X918200Y591750D01*
G01X921050Y591250D02*
X923717D01*
X923467Y591833D01*
X923050Y592167D01*
X922467Y592333D01*
X921883Y592250D01*
X921383Y592000D01*
X921050Y591417D01*
X920883Y590917D01*
Y590417D01*
X921050Y589917D01*
X921467Y589417D01*
X921967Y589083D01*
X922550Y589000D01*
X923133Y589167D01*
X923717Y589667D01*
G01X926650Y589583D02*
X927067Y589250D01*
X927650Y589000D01*
X928150D01*
X928650Y589167D01*
X928983Y589417D01*
X929150Y589750D01*
X929067Y590250D01*
X928733Y590500D01*
X927233Y591000D01*
X926900Y591583D01*
X927067Y592000D01*
X927400Y592250D01*
X927900Y592333D01*
X928400Y592250D01*
X928900Y592000D01*
G01X933500Y592333D02*
Y589000D01*
G01Y593667D02*
X933333Y593750D01*
Y593917D01*
X933500Y594000D01*
X933667Y593917D01*
Y593750D01*
X933500Y593667D01*
G01X937933Y587750D02*
X938517Y587417D01*
X939183Y587333D01*
X939767Y587417D01*
X940267Y587833D01*
X940600Y588417D01*
Y592333D01*
G01Y591667D02*
X940267Y592000D01*
X939767Y592250D01*
X939183Y592333D01*
X938517Y592167D01*
X938100Y591833D01*
X937767Y591250D01*
X937600Y590667D01*
X937683Y590167D01*
X938017Y589583D01*
X938517Y589167D01*
X939183Y589000D01*
X939683Y589083D01*
X940267Y589417D01*
X940600Y589750D01*
G01X943283Y589000D02*
Y592333D01*
G01Y591500D02*
X943617Y591917D01*
X944117Y592250D01*
X944783Y592333D01*
X945367Y592250D01*
X945867Y591917D01*
X946117Y591333D01*
Y589000D01*
G01X878000Y591500D02*
X879667D01*
Y590000D01*
X879167Y589500D01*
X878583Y589167D01*
X877750Y589000D01*
X876917Y589167D01*
X876333Y589500D01*
X875833Y590000D01*
X875500Y590583D01*
X875333Y591250D01*
Y591833D01*
X875500Y592333D01*
X875833Y592917D01*
X876333Y593417D01*
X876833Y593750D01*
X877500Y594000D01*
X878083D01*
X878750Y593833D01*
X879250Y593500D01*
G01X881850Y591250D02*
X884517D01*
X884267Y591833D01*
X883850Y592167D01*
X883267Y592333D01*
X882683Y592250D01*
X882183Y592000D01*
X881850Y591417D01*
X881683Y590917D01*
Y590417D01*
X881850Y589917D01*
X882267Y589417D01*
X882767Y589083D01*
X883350Y589000D01*
X883933Y589167D01*
X884517Y589667D01*
G01X887533Y589000D02*
Y592333D01*
G01Y591667D02*
X887950Y592000D01*
X888367Y592250D01*
X888950Y592333D01*
X889367Y592250D01*
X889867Y592000D01*
G01X892800Y589000D02*
Y594000D01*
G01Y591500D02*
X893217Y592000D01*
X893717Y592250D01*
X894217Y592333D01*
X894967Y592167D01*
X895467Y591833D01*
X895800Y591250D01*
Y590583D01*
X895633Y589917D01*
X895300Y589417D01*
X894717Y589083D01*
X894217Y589000D01*
X893717Y589083D01*
X893217Y589333D01*
X892800Y589750D01*
G01X898650Y591250D02*
X901317D01*
X901067Y591833D01*
X900650Y592167D01*
X900067Y592333D01*
X899483Y592250D01*
X898983Y592000D01*
X898650Y591417D01*
X898483Y590917D01*
Y590417D01*
X898650Y589917D01*
X899067Y589417D01*
X899567Y589083D01*
X900150Y589000D01*
X900733Y589167D01*
X901317Y589667D01*
G01X904333Y589000D02*
Y592333D01*
G01Y591667D02*
X904750Y592000D01*
X905167Y592250D01*
X905750Y592333D01*
X906167Y592250D01*
X906667Y592000D01*
G01X918200Y594000D02*
Y589000D01*
G01Y589750D02*
X917867Y589333D01*
X917367Y589083D01*
X916783Y589000D01*
X916117Y589167D01*
X915617Y589583D01*
X915283Y590083D01*
X915200Y590667D01*
X915283Y591250D01*
X915617Y591750D01*
X916117Y592167D01*
X916783Y592333D01*
X917367Y592250D01*
X917783Y592083D01*
X918200Y591750D01*
G01X921050Y591250D02*
X923717D01*
X923467Y591833D01*
X923050Y592167D01*
X922467Y592333D01*
X921883Y592250D01*
X921383Y592000D01*
X921050Y591417D01*
X920883Y590917D01*
Y590417D01*
X921050Y589917D01*
X921467Y589417D01*
X921967Y589083D01*
X922550Y589000D01*
X923133Y589167D01*
X923717Y589667D01*
G01X926650Y589583D02*
X927067Y589250D01*
X927650Y589000D01*
X928150D01*
X928650Y589167D01*
X928983Y589417D01*
X929150Y589750D01*
X929067Y590250D01*
X928733Y590500D01*
X927233Y591000D01*
X926900Y591583D01*
X927067Y592000D01*
X927400Y592250D01*
X927900Y592333D01*
X928400Y592250D01*
X928900Y592000D01*
G01X933500Y592333D02*
Y589000D01*
G01Y593667D02*
X933333Y593750D01*
Y593917D01*
X933500Y594000D01*
X933667Y593917D01*
Y593750D01*
X933500Y593667D01*
G01X937933Y587750D02*
X938517Y587417D01*
X939183Y587333D01*
X939767Y587417D01*
X940267Y587833D01*
X940600Y588417D01*
Y592333D01*
G01Y591667D02*
X940267Y592000D01*
X939767Y592250D01*
X939183Y592333D01*
X938517Y592167D01*
X938100Y591833D01*
X937767Y591250D01*
X937600Y590667D01*
X937683Y590167D01*
X938017Y589583D01*
X938517Y589167D01*
X939183Y589000D01*
X939683Y589083D01*
X940267Y589417D01*
X940600Y589750D01*
G01X943283Y589000D02*
Y592333D01*
G01Y591500D02*
X943617Y591917D01*
X944117Y592250D01*
X944783Y592333D01*
X945367Y592250D01*
X945867Y591917D01*
X946117Y591333D01*
Y589000D01*
G01X843083Y734500D02*
Y739500D01*
G01Y737083D02*
X843500Y737500D01*
X843917Y737750D01*
X844583Y737833D01*
X845083Y737750D01*
X845667Y737417D01*
X845917Y736917D01*
Y734500D01*
G01X851600D02*
Y737833D01*
G01Y737250D02*
X851267Y737583D01*
X850767Y737750D01*
X850183Y737833D01*
X849600Y737667D01*
X849100Y737333D01*
X848767Y736833D01*
X848600Y736167D01*
X848767Y735500D01*
X849100Y735000D01*
X849600Y734667D01*
X850183Y734500D01*
X850767Y734583D01*
X851267Y734833D01*
X851600Y735167D01*
G01X855700Y734500D02*
Y739500D01*
G01X860800Y734500D02*
Y738750D01*
X860967Y739167D01*
X861300Y739417D01*
X861800Y739500D01*
X862300Y739333D01*
X862550Y738917D01*
G01X861550Y737500D02*
X859883D01*
G01X871000Y732833D02*
Y737833D01*
G01Y737083D02*
X871417Y737500D01*
X871833Y737750D01*
X872500Y737833D01*
X873083Y737750D01*
X873667Y737333D01*
X873917Y736750D01*
X874000Y736167D01*
X873917Y735583D01*
X873667Y735000D01*
X873167Y734667D01*
X872500Y734500D01*
X871917Y734583D01*
X871333Y734833D01*
X871000Y735167D01*
G01X878100Y734500D02*
Y739500D01*
G01X882283Y737833D02*
Y735500D01*
X882617Y734917D01*
X883117Y734583D01*
X883700Y734500D01*
X884283Y734583D01*
X884783Y734917D01*
X885117Y735500D01*
G01Y734500D02*
Y737833D01*
G01X888133Y733250D02*
X888717Y732917D01*
X889383Y732833D01*
X889967Y732917D01*
X890467Y733333D01*
X890800Y733917D01*
Y737833D01*
G01Y737167D02*
X890467Y737500D01*
X889967Y737750D01*
X889383Y737833D01*
X888717Y737667D01*
X888300Y737333D01*
X887967Y736750D01*
X887800Y736167D01*
X887883Y735667D01*
X888217Y735083D01*
X888717Y734667D01*
X889383Y734500D01*
X889883Y734583D01*
X890467Y734917D01*
X890800Y735250D01*
G01X893733Y733250D02*
X894317Y732917D01*
X894983Y732833D01*
X895567Y732917D01*
X896067Y733333D01*
X896400Y733917D01*
Y737833D01*
G01Y737167D02*
X896067Y737500D01*
X895567Y737750D01*
X894983Y737833D01*
X894317Y737667D01*
X893900Y737333D01*
X893567Y736750D01*
X893400Y736167D01*
X893483Y735667D01*
X893817Y735083D01*
X894317Y734667D01*
X894983Y734500D01*
X895483Y734583D01*
X896067Y734917D01*
X896400Y735250D01*
G01X900500Y737833D02*
Y734500D01*
G01Y739167D02*
X900333Y739250D01*
Y739417D01*
X900500Y739500D01*
X900667Y739417D01*
Y739250D01*
X900500Y739167D01*
G01X904683Y734500D02*
Y737833D01*
G01Y737000D02*
X905017Y737417D01*
X905517Y737750D01*
X906183Y737833D01*
X906767Y737750D01*
X907267Y737417D01*
X907517Y736833D01*
Y734500D01*
G01X910533Y733250D02*
X911117Y732917D01*
X911783Y732833D01*
X912367Y732917D01*
X912867Y733333D01*
X913200Y733917D01*
Y737833D01*
G01Y737167D02*
X912867Y737500D01*
X912367Y737750D01*
X911783Y737833D01*
X911117Y737667D01*
X910700Y737333D01*
X910367Y736750D01*
X910200Y736167D01*
X910283Y735667D01*
X910617Y735083D01*
X911117Y734667D01*
X911783Y734500D01*
X912283Y734583D01*
X912867Y734917D01*
X913200Y735250D01*
G01X843083Y734500D02*
Y739500D01*
G01Y737083D02*
X843500Y737500D01*
X843917Y737750D01*
X844583Y737833D01*
X845083Y737750D01*
X845667Y737417D01*
X845917Y736917D01*
Y734500D01*
G01X851600D02*
Y737833D01*
G01Y737250D02*
X851267Y737583D01*
X850767Y737750D01*
X850183Y737833D01*
X849600Y737667D01*
X849100Y737333D01*
X848767Y736833D01*
X848600Y736167D01*
X848767Y735500D01*
X849100Y735000D01*
X849600Y734667D01*
X850183Y734500D01*
X850767Y734583D01*
X851267Y734833D01*
X851600Y735167D01*
G01X855700Y734500D02*
Y739500D01*
G01X860800Y734500D02*
Y738750D01*
X860967Y739167D01*
X861300Y739417D01*
X861800Y739500D01*
X862300Y739333D01*
X862550Y738917D01*
G01X861550Y737500D02*
X859883D01*
G01X871000Y732833D02*
Y737833D01*
G01Y737083D02*
X871417Y737500D01*
X871833Y737750D01*
X872500Y737833D01*
X873083Y737750D01*
X873667Y737333D01*
X873917Y736750D01*
X874000Y736167D01*
X873917Y735583D01*
X873667Y735000D01*
X873167Y734667D01*
X872500Y734500D01*
X871917Y734583D01*
X871333Y734833D01*
X871000Y735167D01*
G01X878100Y734500D02*
Y739500D01*
G01X882283Y737833D02*
Y735500D01*
X882617Y734917D01*
X883117Y734583D01*
X883700Y734500D01*
X884283Y734583D01*
X884783Y734917D01*
X885117Y735500D01*
G01Y734500D02*
Y737833D01*
G01X888133Y733250D02*
X888717Y732917D01*
X889383Y732833D01*
X889967Y732917D01*
X890467Y733333D01*
X890800Y733917D01*
Y737833D01*
G01Y737167D02*
X890467Y737500D01*
X889967Y737750D01*
X889383Y737833D01*
X888717Y737667D01*
X888300Y737333D01*
X887967Y736750D01*
X887800Y736167D01*
X887883Y735667D01*
X888217Y735083D01*
X888717Y734667D01*
X889383Y734500D01*
X889883Y734583D01*
X890467Y734917D01*
X890800Y735250D01*
G01X893733Y733250D02*
X894317Y732917D01*
X894983Y732833D01*
X895567Y732917D01*
X896067Y733333D01*
X896400Y733917D01*
Y737833D01*
G01Y737167D02*
X896067Y737500D01*
X895567Y737750D01*
X894983Y737833D01*
X894317Y737667D01*
X893900Y737333D01*
X893567Y736750D01*
X893400Y736167D01*
X893483Y735667D01*
X893817Y735083D01*
X894317Y734667D01*
X894983Y734500D01*
X895483Y734583D01*
X896067Y734917D01*
X896400Y735250D01*
G01X900500Y737833D02*
Y734500D01*
G01Y739167D02*
X900333Y739250D01*
Y739417D01*
X900500Y739500D01*
X900667Y739417D01*
Y739250D01*
X900500Y739167D01*
G01X904683Y734500D02*
Y737833D01*
G01Y737000D02*
X905017Y737417D01*
X905517Y737750D01*
X906183Y737833D01*
X906767Y737750D01*
X907267Y737417D01*
X907517Y736833D01*
Y734500D01*
G01X910533Y733250D02*
X911117Y732917D01*
X911783Y732833D01*
X912367Y732917D01*
X912867Y733333D01*
X913200Y733917D01*
Y737833D01*
G01Y737167D02*
X912867Y737500D01*
X912367Y737750D01*
X911783Y737833D01*
X911117Y737667D01*
X910700Y737333D01*
X910367Y736750D01*
X910200Y736167D01*
X910283Y735667D01*
X910617Y735083D01*
X911117Y734667D01*
X911783Y734500D01*
X912283Y734583D01*
X912867Y734917D01*
X913200Y735250D01*
G01X980667Y16500D02*
X977333D01*
Y21500D01*
X980667D01*
G01X979333Y19083D02*
X977333D01*
G01X983350Y19833D02*
X985850Y16500D01*
G01Y19833D02*
X983350Y16500D01*
G01X990200Y16333D02*
X990033Y16417D01*
Y16583D01*
X990200Y16667D01*
X990367Y16583D01*
Y16417D01*
X990200Y16333D01*
G01X994050Y16500D02*
Y21500D01*
G01X997550D02*
Y16500D01*
G01Y19000D02*
X994050D01*
G01X999733Y16500D02*
Y21500D01*
X1001817D01*
X1002483Y21250D01*
X1002900Y20917D01*
X1003067Y20250D01*
X1002900Y19583D01*
X1002400Y19167D01*
X1001817Y18917D01*
X999733D01*
G01X1001817D02*
X1003067Y16500D01*
G01X1008667D02*
X1005333D01*
Y21500D01*
X1008667D01*
G01X1007333Y19083D02*
X1005333D01*
G01X1013600Y16500D02*
Y21500D01*
X1010517Y17917D01*
X1014683D01*
G01X1016367Y17250D02*
X1016867Y16833D01*
X1017450Y16583D01*
X1018200Y16500D01*
X1018950Y16667D01*
X1019533Y17000D01*
X1019950Y17583D01*
X1020033Y18250D01*
X1019867Y18917D01*
X1019450Y19333D01*
X1018867Y19667D01*
X1018283Y19750D01*
X1017700Y19667D01*
X1016950Y19333D01*
X1017200Y21500D01*
X1019450D01*
G01X1022050Y16500D02*
X1025550Y21500D01*
G01X1022050D02*
X1025550Y16500D01*
G01X1027983Y17083D02*
X1028567Y16667D01*
X1029233Y16500D01*
X1029900Y16667D01*
X1030483Y17167D01*
X1030900Y17917D01*
X1031067Y18667D01*
Y19583D01*
X1030900Y20333D01*
X1030483Y21000D01*
X1029983Y21333D01*
X1029400Y21500D01*
X1028733Y21333D01*
X1028233Y21000D01*
X1027900Y20500D01*
X1027733Y19833D01*
X1027900Y19250D01*
X1028317Y18667D01*
X1028817Y18333D01*
X1029400Y18250D01*
X1030067Y18417D01*
X1030567Y18833D01*
X1031067Y19583D01*
G01X1033417Y18583D02*
X1034000Y19167D01*
X1034500Y19500D01*
X1035167Y19667D01*
X1035750Y19500D01*
X1036167Y19167D01*
X1036500Y18667D01*
X1036583Y18083D01*
X1036500Y17583D01*
X1036167Y17083D01*
X1035667Y16667D01*
X1035083Y16500D01*
X1034417Y16667D01*
X1033833Y17167D01*
X1033500Y17917D01*
X1033417Y18750D01*
X1033583Y19833D01*
X1033833Y20417D01*
X1034250Y21000D01*
X1034833Y21417D01*
X1035417Y21500D01*
X1036000Y21333D01*
X1036417Y20917D01*
G01X1040183Y14833D02*
X1039350Y15667D01*
X1038933Y16500D01*
Y19833D01*
X1039350Y20667D01*
X1040183Y21500D01*
G01X1044367Y16500D02*
Y21500D01*
X1046033D01*
X1046700Y21250D01*
X1047200Y20917D01*
X1047617Y20417D01*
X1047950Y19833D01*
X1048033Y19000D01*
X1047950Y18167D01*
X1047617Y17583D01*
X1047200Y17083D01*
X1046700Y16750D01*
X1046033Y16500D01*
X1044367D01*
G01X1051800D02*
Y21500D01*
X1050800Y20500D01*
G01Y16500D02*
X1052800D01*
G01X1055817Y18583D02*
X1056400Y19167D01*
X1056900Y19500D01*
X1057567Y19667D01*
X1058150Y19500D01*
X1058567Y19167D01*
X1058900Y18667D01*
X1058983Y18083D01*
X1058900Y17583D01*
X1058567Y17083D01*
X1058067Y16667D01*
X1057483Y16500D01*
X1056817Y16667D01*
X1056233Y17167D01*
X1055900Y17917D01*
X1055817Y18750D01*
X1055983Y19833D01*
X1056233Y20417D01*
X1056650Y21000D01*
X1057233Y21417D01*
X1057817Y21500D01*
X1058400Y21333D01*
X1058817Y20917D01*
G01X1061250Y16500D02*
X1064750Y21500D01*
G01X1061250D02*
X1064750Y16500D01*
G01X1069600D02*
Y21500D01*
X1066517Y17917D01*
X1070683D01*
G01X1074617Y14833D02*
X1075450Y15667D01*
X1075867Y16500D01*
Y19833D01*
X1075450Y20667D01*
X1074617Y21500D01*
G01X980667Y16500D02*
X977333D01*
Y21500D01*
X980667D01*
G01X979333Y19083D02*
X977333D01*
G01X983350Y19833D02*
X985850Y16500D01*
G01Y19833D02*
X983350Y16500D01*
G01X990200Y16333D02*
X990033Y16417D01*
Y16583D01*
X990200Y16667D01*
X990367Y16583D01*
Y16417D01*
X990200Y16333D01*
G01X994050Y16500D02*
Y21500D01*
G01X997550D02*
Y16500D01*
G01Y19000D02*
X994050D01*
G01X999733Y16500D02*
Y21500D01*
X1001817D01*
X1002483Y21250D01*
X1002900Y20917D01*
X1003067Y20250D01*
X1002900Y19583D01*
X1002400Y19167D01*
X1001817Y18917D01*
X999733D01*
G01X1001817D02*
X1003067Y16500D01*
G01X1008667D02*
X1005333D01*
Y21500D01*
X1008667D01*
G01X1007333Y19083D02*
X1005333D01*
G01X1013600Y16500D02*
Y21500D01*
X1010517Y17917D01*
X1014683D01*
G01X1016367Y17250D02*
X1016867Y16833D01*
X1017450Y16583D01*
X1018200Y16500D01*
X1018950Y16667D01*
X1019533Y17000D01*
X1019950Y17583D01*
X1020033Y18250D01*
X1019867Y18917D01*
X1019450Y19333D01*
X1018867Y19667D01*
X1018283Y19750D01*
X1017700Y19667D01*
X1016950Y19333D01*
X1017200Y21500D01*
X1019450D01*
G01X1022050Y16500D02*
X1025550Y21500D01*
G01X1022050D02*
X1025550Y16500D01*
G01X1027983Y17083D02*
X1028567Y16667D01*
X1029233Y16500D01*
X1029900Y16667D01*
X1030483Y17167D01*
X1030900Y17917D01*
X1031067Y18667D01*
Y19583D01*
X1030900Y20333D01*
X1030483Y21000D01*
X1029983Y21333D01*
X1029400Y21500D01*
X1028733Y21333D01*
X1028233Y21000D01*
X1027900Y20500D01*
X1027733Y19833D01*
X1027900Y19250D01*
X1028317Y18667D01*
X1028817Y18333D01*
X1029400Y18250D01*
X1030067Y18417D01*
X1030567Y18833D01*
X1031067Y19583D01*
G01X1033417Y18583D02*
X1034000Y19167D01*
X1034500Y19500D01*
X1035167Y19667D01*
X1035750Y19500D01*
X1036167Y19167D01*
X1036500Y18667D01*
X1036583Y18083D01*
X1036500Y17583D01*
X1036167Y17083D01*
X1035667Y16667D01*
X1035083Y16500D01*
X1034417Y16667D01*
X1033833Y17167D01*
X1033500Y17917D01*
X1033417Y18750D01*
X1033583Y19833D01*
X1033833Y20417D01*
X1034250Y21000D01*
X1034833Y21417D01*
X1035417Y21500D01*
X1036000Y21333D01*
X1036417Y20917D01*
G01X1040183Y14833D02*
X1039350Y15667D01*
X1038933Y16500D01*
Y19833D01*
X1039350Y20667D01*
X1040183Y21500D01*
G01X1044367Y16500D02*
Y21500D01*
X1046033D01*
X1046700Y21250D01*
X1047200Y20917D01*
X1047617Y20417D01*
X1047950Y19833D01*
X1048033Y19000D01*
X1047950Y18167D01*
X1047617Y17583D01*
X1047200Y17083D01*
X1046700Y16750D01*
X1046033Y16500D01*
X1044367D01*
G01X1051800D02*
Y21500D01*
X1050800Y20500D01*
G01Y16500D02*
X1052800D01*
G01X1055817Y18583D02*
X1056400Y19167D01*
X1056900Y19500D01*
X1057567Y19667D01*
X1058150Y19500D01*
X1058567Y19167D01*
X1058900Y18667D01*
X1058983Y18083D01*
X1058900Y17583D01*
X1058567Y17083D01*
X1058067Y16667D01*
X1057483Y16500D01*
X1056817Y16667D01*
X1056233Y17167D01*
X1055900Y17917D01*
X1055817Y18750D01*
X1055983Y19833D01*
X1056233Y20417D01*
X1056650Y21000D01*
X1057233Y21417D01*
X1057817Y21500D01*
X1058400Y21333D01*
X1058817Y20917D01*
G01X1061250Y16500D02*
X1064750Y21500D01*
G01X1061250D02*
X1064750Y16500D01*
G01X1069600D02*
Y21500D01*
X1066517Y17917D01*
X1070683D01*
G01X1074617Y14833D02*
X1075450Y15667D01*
X1075867Y16500D01*
Y19833D01*
X1075450Y20667D01*
X1074617Y21500D01*
G01X977333Y65500D02*
Y70500D01*
X979417D01*
X980083Y70250D01*
X980500Y69917D01*
X980667Y69250D01*
X980500Y68583D01*
X980000Y68167D01*
X979417Y67917D01*
X977333D01*
G01X979417D02*
X980667Y65500D01*
G01X986267D02*
X982933D01*
Y70500D01*
X986267D01*
G01X984933Y68083D02*
X982933D01*
G01X992033Y70083D02*
X991533Y70333D01*
X990950Y70500D01*
X990283D01*
X989533Y70250D01*
X988950Y69833D01*
X988533Y69333D01*
X988200Y68500D01*
X988117Y67750D01*
X988283Y67000D01*
X988533Y66500D01*
X989033Y66000D01*
X989617Y65667D01*
X990200Y65500D01*
X990783D01*
X991367Y65667D01*
X991867Y65917D01*
X992283Y66250D01*
G01X995800Y70500D02*
Y65500D01*
G01X993883Y70500D02*
X997717D01*
G01X999317Y65500D02*
X1001400Y70500D01*
X1003483Y65500D01*
G01X1002733Y67250D02*
X1000067D01*
G01X1005083Y65500D02*
Y70500D01*
X1008917Y65500D01*
Y70500D01*
G01X1013100Y68000D02*
X1014767D01*
Y66500D01*
X1014267Y66000D01*
X1013683Y65667D01*
X1012850Y65500D01*
X1012017Y65667D01*
X1011433Y66000D01*
X1010933Y66500D01*
X1010600Y67083D01*
X1010433Y67750D01*
Y68333D01*
X1010600Y68833D01*
X1010933Y69417D01*
X1011433Y69917D01*
X1011933Y70250D01*
X1012600Y70500D01*
X1013183D01*
X1013850Y70333D01*
X1014350Y70000D01*
G01X1016533Y70500D02*
Y65500D01*
X1019867D01*
G01X1025467D02*
X1022133D01*
Y70500D01*
X1025467D01*
G01X1024133Y68083D02*
X1022133D01*
G01X1033167Y65500D02*
Y70500D01*
X1034833D01*
X1035500Y70250D01*
X1036000Y69917D01*
X1036417Y69417D01*
X1036750Y68833D01*
X1036833Y68000D01*
X1036750Y67167D01*
X1036417Y66583D01*
X1036000Y66083D01*
X1035500Y65750D01*
X1034833Y65500D01*
X1033167D01*
G01X1038933D02*
Y70500D01*
X1041017D01*
X1041683Y70250D01*
X1042100Y69917D01*
X1042267Y69250D01*
X1042100Y68583D01*
X1041600Y68167D01*
X1041017Y67917D01*
X1038933D01*
G01X1041017D02*
X1042267Y65500D01*
G01X1045200Y70500D02*
X1047200D01*
G01X1046200D02*
Y65500D01*
G01X1045200D02*
X1047200D01*
G01X1050133Y70500D02*
Y65500D01*
X1053467D01*
G01X1055733Y70500D02*
Y65500D01*
X1059067D01*
G01X1066850D02*
Y70500D01*
G01X1070350D02*
Y65500D01*
G01Y68000D02*
X1066850D01*
G01X1074200Y65500D02*
X1073533Y65583D01*
X1072950Y65917D01*
X1072450Y66417D01*
X1072117Y67000D01*
X1071950Y67667D01*
Y68333D01*
X1072117Y69000D01*
X1072450Y69583D01*
X1072950Y70083D01*
X1073533Y70417D01*
X1074200Y70500D01*
X1074867Y70417D01*
X1075450Y70083D01*
X1075950Y69583D01*
X1076283Y69000D01*
X1076450Y68333D01*
Y67667D01*
X1076283Y67000D01*
X1075950Y66417D01*
X1075450Y65917D01*
X1074867Y65583D01*
X1074200Y65500D01*
G01X1078133Y70500D02*
Y65500D01*
X1081467D01*
G01X1087067D02*
X1083733D01*
Y70500D01*
X1087067D01*
G01X1085733Y68083D02*
X1083733D01*
G01X1094767Y65500D02*
Y70500D01*
X1096433D01*
X1097100Y70250D01*
X1097600Y69917D01*
X1098017Y69417D01*
X1098350Y68833D01*
X1098433Y68000D01*
X1098350Y67167D01*
X1098017Y66583D01*
X1097600Y66083D01*
X1097100Y65750D01*
X1096433Y65500D01*
X1094767D01*
G01X1103867D02*
X1100533D01*
Y70500D01*
X1103867D01*
G01X1102533Y68083D02*
X1100533D01*
G01X1106217Y65500D02*
Y70500D01*
X1109383D01*
G01X1108217Y68083D02*
X1106217D01*
G01X1112400Y70500D02*
X1114400D01*
G01X1113400D02*
Y65500D01*
G01X1112400D02*
X1114400D01*
G01X1117083D02*
Y70500D01*
X1120917Y65500D01*
Y70500D01*
G01X1126267Y65500D02*
X1122933D01*
Y70500D01*
X1126267D01*
G01X1124933Y68083D02*
X1122933D01*
G01X928583Y23083D02*
X929167Y22667D01*
X929833Y22500D01*
X930500Y22667D01*
X931083Y23167D01*
X931500Y23917D01*
X931667Y24667D01*
Y25583D01*
X931500Y26333D01*
X931083Y27000D01*
X930583Y27333D01*
X930000Y27500D01*
X929333Y27333D01*
X928833Y27000D01*
X928500Y26500D01*
X928333Y25833D01*
X928500Y25250D01*
X928917Y24667D01*
X929417Y24333D01*
X930000Y24250D01*
X930667Y24417D01*
X931167Y24833D01*
X931667Y25583D01*
G01X934017Y24583D02*
X934600Y25167D01*
X935100Y25500D01*
X935767Y25667D01*
X936350Y25500D01*
X936767Y25167D01*
X937100Y24667D01*
X937183Y24083D01*
X937100Y23583D01*
X936767Y23083D01*
X936267Y22667D01*
X935683Y22500D01*
X935017Y22667D01*
X934433Y23167D01*
X934100Y23917D01*
X934017Y24750D01*
X934183Y25833D01*
X934433Y26417D01*
X934850Y27000D01*
X935433Y27417D01*
X936017Y27500D01*
X936600Y27333D01*
X937017Y26917D01*
G01X977333Y65500D02*
Y70500D01*
X979417D01*
X980083Y70250D01*
X980500Y69917D01*
X980667Y69250D01*
X980500Y68583D01*
X980000Y68167D01*
X979417Y67917D01*
X977333D01*
G01X979417D02*
X980667Y65500D01*
G01X986267D02*
X982933D01*
Y70500D01*
X986267D01*
G01X984933Y68083D02*
X982933D01*
G01X992033Y70083D02*
X991533Y70333D01*
X990950Y70500D01*
X990283D01*
X989533Y70250D01*
X988950Y69833D01*
X988533Y69333D01*
X988200Y68500D01*
X988117Y67750D01*
X988283Y67000D01*
X988533Y66500D01*
X989033Y66000D01*
X989617Y65667D01*
X990200Y65500D01*
X990783D01*
X991367Y65667D01*
X991867Y65917D01*
X992283Y66250D01*
G01X995800Y70500D02*
Y65500D01*
G01X993883Y70500D02*
X997717D01*
G01X999317Y65500D02*
X1001400Y70500D01*
X1003483Y65500D01*
G01X1002733Y67250D02*
X1000067D01*
G01X1005083Y65500D02*
Y70500D01*
X1008917Y65500D01*
Y70500D01*
G01X1013100Y68000D02*
X1014767D01*
Y66500D01*
X1014267Y66000D01*
X1013683Y65667D01*
X1012850Y65500D01*
X1012017Y65667D01*
X1011433Y66000D01*
X1010933Y66500D01*
X1010600Y67083D01*
X1010433Y67750D01*
Y68333D01*
X1010600Y68833D01*
X1010933Y69417D01*
X1011433Y69917D01*
X1011933Y70250D01*
X1012600Y70500D01*
X1013183D01*
X1013850Y70333D01*
X1014350Y70000D01*
G01X1016533Y70500D02*
Y65500D01*
X1019867D01*
G01X1025467D02*
X1022133D01*
Y70500D01*
X1025467D01*
G01X1024133Y68083D02*
X1022133D01*
G01X1033167Y65500D02*
Y70500D01*
X1034833D01*
X1035500Y70250D01*
X1036000Y69917D01*
X1036417Y69417D01*
X1036750Y68833D01*
X1036833Y68000D01*
X1036750Y67167D01*
X1036417Y66583D01*
X1036000Y66083D01*
X1035500Y65750D01*
X1034833Y65500D01*
X1033167D01*
G01X1038933D02*
Y70500D01*
X1041017D01*
X1041683Y70250D01*
X1042100Y69917D01*
X1042267Y69250D01*
X1042100Y68583D01*
X1041600Y68167D01*
X1041017Y67917D01*
X1038933D01*
G01X1041017D02*
X1042267Y65500D01*
G01X1045200Y70500D02*
X1047200D01*
G01X1046200D02*
Y65500D01*
G01X1045200D02*
X1047200D01*
G01X1050133Y70500D02*
Y65500D01*
X1053467D01*
G01X1055733Y70500D02*
Y65500D01*
X1059067D01*
G01X1066850D02*
Y70500D01*
G01X1070350D02*
Y65500D01*
G01Y68000D02*
X1066850D01*
G01X1074200Y65500D02*
X1073533Y65583D01*
X1072950Y65917D01*
X1072450Y66417D01*
X1072117Y67000D01*
X1071950Y67667D01*
Y68333D01*
X1072117Y69000D01*
X1072450Y69583D01*
X1072950Y70083D01*
X1073533Y70417D01*
X1074200Y70500D01*
X1074867Y70417D01*
X1075450Y70083D01*
X1075950Y69583D01*
X1076283Y69000D01*
X1076450Y68333D01*
Y67667D01*
X1076283Y67000D01*
X1075950Y66417D01*
X1075450Y65917D01*
X1074867Y65583D01*
X1074200Y65500D01*
G01X1078133Y70500D02*
Y65500D01*
X1081467D01*
G01X1087067D02*
X1083733D01*
Y70500D01*
X1087067D01*
G01X1085733Y68083D02*
X1083733D01*
G01X1094767Y65500D02*
Y70500D01*
X1096433D01*
X1097100Y70250D01*
X1097600Y69917D01*
X1098017Y69417D01*
X1098350Y68833D01*
X1098433Y68000D01*
X1098350Y67167D01*
X1098017Y66583D01*
X1097600Y66083D01*
X1097100Y65750D01*
X1096433Y65500D01*
X1094767D01*
G01X1103867D02*
X1100533D01*
Y70500D01*
X1103867D01*
G01X1102533Y68083D02*
X1100533D01*
G01X1106217Y65500D02*
Y70500D01*
X1109383D01*
G01X1108217Y68083D02*
X1106217D01*
G01X1112400Y70500D02*
X1114400D01*
G01X1113400D02*
Y65500D01*
G01X1112400D02*
X1114400D01*
G01X1117083D02*
Y70500D01*
X1120917Y65500D01*
Y70500D01*
G01X1126267Y65500D02*
X1122933D01*
Y70500D01*
X1126267D01*
G01X1124933Y68083D02*
X1122933D01*
G01X928583Y23083D02*
X929167Y22667D01*
X929833Y22500D01*
X930500Y22667D01*
X931083Y23167D01*
X931500Y23917D01*
X931667Y24667D01*
Y25583D01*
X931500Y26333D01*
X931083Y27000D01*
X930583Y27333D01*
X930000Y27500D01*
X929333Y27333D01*
X928833Y27000D01*
X928500Y26500D01*
X928333Y25833D01*
X928500Y25250D01*
X928917Y24667D01*
X929417Y24333D01*
X930000Y24250D01*
X930667Y24417D01*
X931167Y24833D01*
X931667Y25583D01*
G01X934017Y24583D02*
X934600Y25167D01*
X935100Y25500D01*
X935767Y25667D01*
X936350Y25500D01*
X936767Y25167D01*
X937100Y24667D01*
X937183Y24083D01*
X937100Y23583D01*
X936767Y23083D01*
X936267Y22667D01*
X935683Y22500D01*
X935017Y22667D01*
X934433Y23167D01*
X934100Y23917D01*
X934017Y24750D01*
X934183Y25833D01*
X934433Y26417D01*
X934850Y27000D01*
X935433Y27417D01*
X936017Y27500D01*
X936600Y27333D01*
X937017Y26917D01*
G01X909250Y184083D02*
X909667Y183750D01*
X910250Y183500D01*
X910750D01*
X911250Y183667D01*
X911583Y183917D01*
X911750Y184250D01*
X911667Y184750D01*
X911333Y185000D01*
X909833Y185500D01*
X909500Y186083D01*
X909667Y186500D01*
X910000Y186750D01*
X910500Y186833D01*
X911000Y186750D01*
X911500Y186500D01*
G01X916100Y188500D02*
Y183500D01*
G01X914933Y186833D02*
X917267D01*
G01X920283D02*
Y184500D01*
X920617Y183917D01*
X921117Y183583D01*
X921700Y183500D01*
X922283Y183583D01*
X922783Y183917D01*
X923117Y184500D01*
G01Y183500D02*
Y186833D01*
G01X925800Y183500D02*
Y188500D01*
G01Y186000D02*
X926217Y186500D01*
X926717Y186750D01*
X927217Y186833D01*
X927967Y186667D01*
X928467Y186333D01*
X928800Y185750D01*
Y185083D01*
X928633Y184417D01*
X928300Y183917D01*
X927717Y183583D01*
X927217Y183500D01*
X926717Y183583D01*
X926217Y183833D01*
X925800Y184250D01*
G01X938500Y183500D02*
Y188500D01*
G01X942850Y185750D02*
X945517D01*
X945267Y186333D01*
X944850Y186667D01*
X944267Y186833D01*
X943683Y186750D01*
X943183Y186500D01*
X942850Y185917D01*
X942683Y185417D01*
Y184917D01*
X942850Y184417D01*
X943267Y183917D01*
X943767Y183583D01*
X944350Y183500D01*
X944933Y183667D01*
X945517Y184167D01*
G01X948283Y183500D02*
Y186833D01*
G01Y186000D02*
X948617Y186417D01*
X949117Y186750D01*
X949783Y186833D01*
X950367Y186750D01*
X950867Y186417D01*
X951117Y185833D01*
Y183500D01*
G01X954133Y182250D02*
X954717Y181917D01*
X955383Y181833D01*
X955967Y181917D01*
X956467Y182333D01*
X956800Y182917D01*
Y186833D01*
G01Y186167D02*
X956467Y186500D01*
X955967Y186750D01*
X955383Y186833D01*
X954717Y186667D01*
X954300Y186333D01*
X953967Y185750D01*
X953800Y185167D01*
X953883Y184667D01*
X954217Y184083D01*
X954717Y183667D01*
X955383Y183500D01*
X955883Y183583D01*
X956467Y183917D01*
X956800Y184250D01*
G01X960900Y188500D02*
Y183500D01*
G01X959733Y186833D02*
X962067D01*
G01X965083Y183500D02*
Y188500D01*
G01Y186083D02*
X965500Y186500D01*
X965917Y186750D01*
X966583Y186833D01*
X967083Y186750D01*
X967667Y186417D01*
X967917Y185917D01*
Y183500D01*
G01X971017Y184417D02*
X973183D01*
G01Y185917D02*
X971017D01*
G01X976117Y185583D02*
X976700Y186167D01*
X977200Y186500D01*
X977867Y186667D01*
X978450Y186500D01*
X978867Y186167D01*
X979200Y185667D01*
X979283Y185083D01*
X979200Y184583D01*
X978867Y184083D01*
X978367Y183667D01*
X977783Y183500D01*
X977117Y183667D01*
X976533Y184167D01*
X976200Y184917D01*
X976117Y185750D01*
X976283Y186833D01*
X976533Y187417D01*
X976950Y188000D01*
X977533Y188417D01*
X978117Y188500D01*
X978700Y188333D01*
X979117Y187917D01*
G01X982383Y185167D02*
X984383D01*
G01X983300Y186250D02*
Y184083D01*
G01X987400Y183333D02*
X990400Y188500D01*
G01X993417Y185167D02*
X995583D01*
G01X998267Y184250D02*
X998767Y183833D01*
X999350Y183583D01*
X1000100Y183500D01*
X1000850Y183667D01*
X1001433Y184000D01*
X1001850Y184583D01*
X1001933Y185250D01*
X1001767Y185917D01*
X1001350Y186333D01*
X1000767Y186667D01*
X1000183Y186750D01*
X999600Y186667D01*
X998850Y186333D01*
X999100Y188500D01*
X1001350D01*
G01X1003200Y183500D02*
Y186833D01*
G01Y185917D02*
X1003450Y186333D01*
X1003867Y186667D01*
X1004450Y186833D01*
X1005033Y186667D01*
X1005450Y186333D01*
X1005700Y185917D01*
Y183500D01*
G01Y185917D02*
X1005950Y186333D01*
X1006367Y186667D01*
X1006950Y186833D01*
X1007533Y186667D01*
X1007950Y186333D01*
X1008200Y185833D01*
Y183500D01*
G01X1011300Y186833D02*
Y183500D01*
G01Y188167D02*
X1011133Y188250D01*
Y188417D01*
X1011300Y188500D01*
X1011467Y188417D01*
Y188250D01*
X1011300Y188167D01*
G01X1016900Y183500D02*
Y188500D01*
G01X909250Y184083D02*
X909667Y183750D01*
X910250Y183500D01*
X910750D01*
X911250Y183667D01*
X911583Y183917D01*
X911750Y184250D01*
X911667Y184750D01*
X911333Y185000D01*
X909833Y185500D01*
X909500Y186083D01*
X909667Y186500D01*
X910000Y186750D01*
X910500Y186833D01*
X911000Y186750D01*
X911500Y186500D01*
G01X916100Y188500D02*
Y183500D01*
G01X914933Y186833D02*
X917267D01*
G01X920283D02*
Y184500D01*
X920617Y183917D01*
X921117Y183583D01*
X921700Y183500D01*
X922283Y183583D01*
X922783Y183917D01*
X923117Y184500D01*
G01Y183500D02*
Y186833D01*
G01X925800Y183500D02*
Y188500D01*
G01Y186000D02*
X926217Y186500D01*
X926717Y186750D01*
X927217Y186833D01*
X927967Y186667D01*
X928467Y186333D01*
X928800Y185750D01*
Y185083D01*
X928633Y184417D01*
X928300Y183917D01*
X927717Y183583D01*
X927217Y183500D01*
X926717Y183583D01*
X926217Y183833D01*
X925800Y184250D01*
G01X938500Y183500D02*
Y188500D01*
G01X942850Y185750D02*
X945517D01*
X945267Y186333D01*
X944850Y186667D01*
X944267Y186833D01*
X943683Y186750D01*
X943183Y186500D01*
X942850Y185917D01*
X942683Y185417D01*
Y184917D01*
X942850Y184417D01*
X943267Y183917D01*
X943767Y183583D01*
X944350Y183500D01*
X944933Y183667D01*
X945517Y184167D01*
G01X948283Y183500D02*
Y186833D01*
G01Y186000D02*
X948617Y186417D01*
X949117Y186750D01*
X949783Y186833D01*
X950367Y186750D01*
X950867Y186417D01*
X951117Y185833D01*
Y183500D01*
G01X954133Y182250D02*
X954717Y181917D01*
X955383Y181833D01*
X955967Y181917D01*
X956467Y182333D01*
X956800Y182917D01*
Y186833D01*
G01Y186167D02*
X956467Y186500D01*
X955967Y186750D01*
X955383Y186833D01*
X954717Y186667D01*
X954300Y186333D01*
X953967Y185750D01*
X953800Y185167D01*
X953883Y184667D01*
X954217Y184083D01*
X954717Y183667D01*
X955383Y183500D01*
X955883Y183583D01*
X956467Y183917D01*
X956800Y184250D01*
G01X960900Y188500D02*
Y183500D01*
G01X959733Y186833D02*
X962067D01*
G01X965083Y183500D02*
Y188500D01*
G01Y186083D02*
X965500Y186500D01*
X965917Y186750D01*
X966583Y186833D01*
X967083Y186750D01*
X967667Y186417D01*
X967917Y185917D01*
Y183500D01*
G01X971017Y184417D02*
X973183D01*
G01Y185917D02*
X971017D01*
G01X976117Y185583D02*
X976700Y186167D01*
X977200Y186500D01*
X977867Y186667D01*
X978450Y186500D01*
X978867Y186167D01*
X979200Y185667D01*
X979283Y185083D01*
X979200Y184583D01*
X978867Y184083D01*
X978367Y183667D01*
X977783Y183500D01*
X977117Y183667D01*
X976533Y184167D01*
X976200Y184917D01*
X976117Y185750D01*
X976283Y186833D01*
X976533Y187417D01*
X976950Y188000D01*
X977533Y188417D01*
X978117Y188500D01*
X978700Y188333D01*
X979117Y187917D01*
G01X982383Y185167D02*
X984383D01*
G01X983300Y186250D02*
Y184083D01*
G01X987400Y183333D02*
X990400Y188500D01*
G01X993417Y185167D02*
X995583D01*
G01X998267Y184250D02*
X998767Y183833D01*
X999350Y183583D01*
X1000100Y183500D01*
X1000850Y183667D01*
X1001433Y184000D01*
X1001850Y184583D01*
X1001933Y185250D01*
X1001767Y185917D01*
X1001350Y186333D01*
X1000767Y186667D01*
X1000183Y186750D01*
X999600Y186667D01*
X998850Y186333D01*
X999100Y188500D01*
X1001350D01*
G01X1003200Y183500D02*
Y186833D01*
G01Y185917D02*
X1003450Y186333D01*
X1003867Y186667D01*
X1004450Y186833D01*
X1005033Y186667D01*
X1005450Y186333D01*
X1005700Y185917D01*
Y183500D01*
G01Y185917D02*
X1005950Y186333D01*
X1006367Y186667D01*
X1006950Y186833D01*
X1007533Y186667D01*
X1007950Y186333D01*
X1008200Y185833D01*
Y183500D01*
G01X1011300Y186833D02*
Y183500D01*
G01Y188167D02*
X1011133Y188250D01*
Y188417D01*
X1011300Y188500D01*
X1011467Y188417D01*
Y188250D01*
X1011300Y188167D01*
G01X1016900Y183500D02*
Y188500D01*
G01X929000Y734500D02*
Y738750D01*
X929167Y739167D01*
X929500Y739417D01*
X930000Y739500D01*
X930500Y739333D01*
X930750Y738917D01*
G01X929750Y737500D02*
X928083D01*
G01X933683Y737833D02*
Y735500D01*
X934017Y734917D01*
X934517Y734583D01*
X935100Y734500D01*
X935683Y734583D01*
X936183Y734917D01*
X936517Y735500D01*
G01Y734500D02*
Y737833D01*
G01X940700Y734500D02*
Y739500D01*
G01X946300Y734500D02*
Y739500D01*
G01X956000Y732833D02*
Y737833D01*
G01Y737083D02*
X956417Y737500D01*
X956833Y737750D01*
X957500Y737833D01*
X958083Y737750D01*
X958667Y737333D01*
X958917Y736750D01*
X959000Y736167D01*
X958917Y735583D01*
X958667Y735000D01*
X958167Y734667D01*
X957500Y734500D01*
X956917Y734583D01*
X956333Y734833D01*
X956000Y735167D01*
G01X963100Y734500D02*
Y739500D01*
G01X967283Y737833D02*
Y735500D01*
X967617Y734917D01*
X968117Y734583D01*
X968700Y734500D01*
X969283Y734583D01*
X969783Y734917D01*
X970117Y735500D01*
G01Y734500D02*
Y737833D01*
G01X973133Y733250D02*
X973717Y732917D01*
X974383Y732833D01*
X974967Y732917D01*
X975467Y733333D01*
X975800Y733917D01*
Y737833D01*
G01Y737167D02*
X975467Y737500D01*
X974967Y737750D01*
X974383Y737833D01*
X973717Y737667D01*
X973300Y737333D01*
X972967Y736750D01*
X972800Y736167D01*
X972883Y735667D01*
X973217Y735083D01*
X973717Y734667D01*
X974383Y734500D01*
X974883Y734583D01*
X975467Y734917D01*
X975800Y735250D01*
G01X978733Y733250D02*
X979317Y732917D01*
X979983Y732833D01*
X980567Y732917D01*
X981067Y733333D01*
X981400Y733917D01*
Y737833D01*
G01Y737167D02*
X981067Y737500D01*
X980567Y737750D01*
X979983Y737833D01*
X979317Y737667D01*
X978900Y737333D01*
X978567Y736750D01*
X978400Y736167D01*
X978483Y735667D01*
X978817Y735083D01*
X979317Y734667D01*
X979983Y734500D01*
X980483Y734583D01*
X981067Y734917D01*
X981400Y735250D01*
G01X985500Y737833D02*
Y734500D01*
G01Y739167D02*
X985333Y739250D01*
Y739417D01*
X985500Y739500D01*
X985667Y739417D01*
Y739250D01*
X985500Y739167D01*
G01X989683Y734500D02*
Y737833D01*
G01Y737000D02*
X990017Y737417D01*
X990517Y737750D01*
X991183Y737833D01*
X991767Y737750D01*
X992267Y737417D01*
X992517Y736833D01*
Y734500D01*
G01X995533Y733250D02*
X996117Y732917D01*
X996783Y732833D01*
X997367Y732917D01*
X997867Y733333D01*
X998200Y733917D01*
Y737833D01*
G01Y737167D02*
X997867Y737500D01*
X997367Y737750D01*
X996783Y737833D01*
X996117Y737667D01*
X995700Y737333D01*
X995367Y736750D01*
X995200Y736167D01*
X995283Y735667D01*
X995617Y735083D01*
X996117Y734667D01*
X996783Y734500D01*
X997283Y734583D01*
X997867Y734917D01*
X998200Y735250D01*
G01X929000Y734500D02*
Y738750D01*
X929167Y739167D01*
X929500Y739417D01*
X930000Y739500D01*
X930500Y739333D01*
X930750Y738917D01*
G01X929750Y737500D02*
X928083D01*
G01X933683Y737833D02*
Y735500D01*
X934017Y734917D01*
X934517Y734583D01*
X935100Y734500D01*
X935683Y734583D01*
X936183Y734917D01*
X936517Y735500D01*
G01Y734500D02*
Y737833D01*
G01X940700Y734500D02*
Y739500D01*
G01X946300Y734500D02*
Y739500D01*
G01X956000Y732833D02*
Y737833D01*
G01Y737083D02*
X956417Y737500D01*
X956833Y737750D01*
X957500Y737833D01*
X958083Y737750D01*
X958667Y737333D01*
X958917Y736750D01*
X959000Y736167D01*
X958917Y735583D01*
X958667Y735000D01*
X958167Y734667D01*
X957500Y734500D01*
X956917Y734583D01*
X956333Y734833D01*
X956000Y735167D01*
G01X963100Y734500D02*
Y739500D01*
G01X967283Y737833D02*
Y735500D01*
X967617Y734917D01*
X968117Y734583D01*
X968700Y734500D01*
X969283Y734583D01*
X969783Y734917D01*
X970117Y735500D01*
G01Y734500D02*
Y737833D01*
G01X973133Y733250D02*
X973717Y732917D01*
X974383Y732833D01*
X974967Y732917D01*
X975467Y733333D01*
X975800Y733917D01*
Y737833D01*
G01Y737167D02*
X975467Y737500D01*
X974967Y737750D01*
X974383Y737833D01*
X973717Y737667D01*
X973300Y737333D01*
X972967Y736750D01*
X972800Y736167D01*
X972883Y735667D01*
X973217Y735083D01*
X973717Y734667D01*
X974383Y734500D01*
X974883Y734583D01*
X975467Y734917D01*
X975800Y735250D01*
G01X978733Y733250D02*
X979317Y732917D01*
X979983Y732833D01*
X980567Y732917D01*
X981067Y733333D01*
X981400Y733917D01*
Y737833D01*
G01Y737167D02*
X981067Y737500D01*
X980567Y737750D01*
X979983Y737833D01*
X979317Y737667D01*
X978900Y737333D01*
X978567Y736750D01*
X978400Y736167D01*
X978483Y735667D01*
X978817Y735083D01*
X979317Y734667D01*
X979983Y734500D01*
X980483Y734583D01*
X981067Y734917D01*
X981400Y735250D01*
G01X985500Y737833D02*
Y734500D01*
G01Y739167D02*
X985333Y739250D01*
Y739417D01*
X985500Y739500D01*
X985667Y739417D01*
Y739250D01*
X985500Y739167D01*
G01X989683Y734500D02*
Y737833D01*
G01Y737000D02*
X990017Y737417D01*
X990517Y737750D01*
X991183Y737833D01*
X991767Y737750D01*
X992267Y737417D01*
X992517Y736833D01*
Y734500D01*
G01X995533Y733250D02*
X996117Y732917D01*
X996783Y732833D01*
X997367Y732917D01*
X997867Y733333D01*
X998200Y733917D01*
Y737833D01*
G01Y737167D02*
X997867Y737500D01*
X997367Y737750D01*
X996783Y737833D01*
X996117Y737667D01*
X995700Y737333D01*
X995367Y736750D01*
X995200Y736167D01*
X995283Y735667D01*
X995617Y735083D01*
X996117Y734667D01*
X996783Y734500D01*
X997283Y734583D01*
X997867Y734917D01*
X998200Y735250D01*
G01X956000Y795980D02*
Y790980D01*
G01X954083Y795980D02*
X957917D01*
G01X959517Y794313D02*
X960517Y790980D01*
X961600Y794313D01*
X962683Y790980D01*
X963683Y794313D01*
G01X967200D02*
Y790980D01*
G01Y795647D02*
X967033Y795730D01*
Y795897D01*
X967200Y795980D01*
X967367Y795897D01*
Y795730D01*
X967200Y795647D01*
G01X971550Y791563D02*
X971967Y791230D01*
X972550Y790980D01*
X973050D01*
X973550Y791147D01*
X973883Y791397D01*
X974050Y791730D01*
X973967Y792230D01*
X973633Y792480D01*
X972133Y792980D01*
X971800Y793563D01*
X971967Y793980D01*
X972300Y794230D01*
X972800Y794313D01*
X973300Y794230D01*
X973800Y793980D01*
G01X978400Y795980D02*
Y790980D01*
G01X977233Y794313D02*
X979567D01*
G01X991100Y790980D02*
Y794313D01*
G01Y793730D02*
X990767Y794063D01*
X990267Y794230D01*
X989683Y794313D01*
X989100Y794147D01*
X988600Y793813D01*
X988267Y793313D01*
X988100Y792647D01*
X988267Y791980D01*
X988600Y791480D01*
X989100Y791147D01*
X989683Y790980D01*
X990267Y791063D01*
X990767Y791313D01*
X991100Y791647D01*
G01X993783Y790980D02*
Y794313D01*
G01Y793480D02*
X994117Y793897D01*
X994617Y794230D01*
X995283Y794313D01*
X995867Y794230D01*
X996367Y793897D01*
X996617Y793313D01*
Y790980D01*
G01X1002300Y795980D02*
Y790980D01*
G01Y791730D02*
X1001967Y791313D01*
X1001467Y791063D01*
X1000883Y790980D01*
X1000217Y791147D01*
X999717Y791563D01*
X999383Y792063D01*
X999300Y792647D01*
X999383Y793230D01*
X999717Y793730D01*
X1000217Y794147D01*
X1000883Y794313D01*
X1001467Y794230D01*
X1001883Y794063D01*
X1002300Y793730D01*
G01X1010500Y790980D02*
Y795980D01*
G01Y793480D02*
X1010917Y793980D01*
X1011417Y794230D01*
X1011917Y794313D01*
X1012667Y794147D01*
X1013167Y793813D01*
X1013500Y793230D01*
Y792563D01*
X1013333Y791897D01*
X1013000Y791397D01*
X1012417Y791063D01*
X1011917Y790980D01*
X1011417Y791063D01*
X1010917Y791313D01*
X1010500Y791730D01*
G01X1017600Y790980D02*
X1017100Y791063D01*
X1016600Y791397D01*
X1016267Y791980D01*
X1016100Y792647D01*
X1016267Y793313D01*
X1016600Y793897D01*
X1017100Y794230D01*
X1017600Y794313D01*
X1018100Y794230D01*
X1018600Y793897D01*
X1018933Y793313D01*
X1019017Y792647D01*
X1018933Y791980D01*
X1018600Y791397D01*
X1018100Y791063D01*
X1017600Y790980D01*
G01X1021117Y794313D02*
X1022117Y790980D01*
X1023200Y794313D01*
X1024283Y790980D01*
X1025283Y794313D01*
G01X957500Y811500D02*
X959167D01*
Y810000D01*
X958667Y809500D01*
X958083Y809167D01*
X957250Y809000D01*
X956417Y809167D01*
X955833Y809500D01*
X955333Y810000D01*
X955000Y810583D01*
X954833Y811250D01*
Y811833D01*
X955000Y812333D01*
X955333Y812917D01*
X955833Y813417D01*
X956333Y813750D01*
X957000Y814000D01*
X957583D01*
X958250Y813833D01*
X958750Y813500D01*
G01X961100Y808833D02*
X964100Y814000D01*
G01X966617Y809000D02*
Y814000D01*
X969783D01*
G01X968617Y811583D02*
X966617D01*
G01X977650Y809667D02*
X978317Y809250D01*
X979067Y809000D01*
X979733D01*
X980400Y809250D01*
X980900Y809667D01*
X981150Y810250D01*
X980983Y810833D01*
X980567Y811333D01*
X979817Y811667D01*
X978817Y811833D01*
X978233Y812167D01*
X977983Y812750D01*
X978150Y813333D01*
X978567Y813750D01*
X979150Y814000D01*
X979733D01*
X980317Y813833D01*
X980817Y813417D01*
G01X985000Y809000D02*
Y814000D01*
G01X990600Y809000D02*
X990100Y809083D01*
X989600Y809417D01*
X989267Y810000D01*
X989100Y810667D01*
X989267Y811333D01*
X989600Y811917D01*
X990100Y812250D01*
X990600Y812333D01*
X991100Y812250D01*
X991600Y811917D01*
X991933Y811333D01*
X992017Y810667D01*
X991933Y810000D01*
X991600Y809417D01*
X991100Y809083D01*
X990600Y809000D01*
G01X996200Y814000D02*
Y809000D01*
G01X995033Y812333D02*
X997367D01*
G01X948000Y850610D02*
Y782110D01*
G01X948500Y819500D02*
X1343000D01*
G01X956000Y795980D02*
Y790980D01*
G01X954083Y795980D02*
X957917D01*
G01X959517Y794313D02*
X960517Y790980D01*
X961600Y794313D01*
X962683Y790980D01*
X963683Y794313D01*
G01X967200D02*
Y790980D01*
G01Y795647D02*
X967033Y795730D01*
Y795897D01*
X967200Y795980D01*
X967367Y795897D01*
Y795730D01*
X967200Y795647D01*
G01X971550Y791563D02*
X971967Y791230D01*
X972550Y790980D01*
X973050D01*
X973550Y791147D01*
X973883Y791397D01*
X974050Y791730D01*
X973967Y792230D01*
X973633Y792480D01*
X972133Y792980D01*
X971800Y793563D01*
X971967Y793980D01*
X972300Y794230D01*
X972800Y794313D01*
X973300Y794230D01*
X973800Y793980D01*
G01X978400Y795980D02*
Y790980D01*
G01X977233Y794313D02*
X979567D01*
G01X991100Y790980D02*
Y794313D01*
G01Y793730D02*
X990767Y794063D01*
X990267Y794230D01*
X989683Y794313D01*
X989100Y794147D01*
X988600Y793813D01*
X988267Y793313D01*
X988100Y792647D01*
X988267Y791980D01*
X988600Y791480D01*
X989100Y791147D01*
X989683Y790980D01*
X990267Y791063D01*
X990767Y791313D01*
X991100Y791647D01*
G01X993783Y790980D02*
Y794313D01*
G01Y793480D02*
X994117Y793897D01*
X994617Y794230D01*
X995283Y794313D01*
X995867Y794230D01*
X996367Y793897D01*
X996617Y793313D01*
Y790980D01*
G01X1002300Y795980D02*
Y790980D01*
G01Y791730D02*
X1001967Y791313D01*
X1001467Y791063D01*
X1000883Y790980D01*
X1000217Y791147D01*
X999717Y791563D01*
X999383Y792063D01*
X999300Y792647D01*
X999383Y793230D01*
X999717Y793730D01*
X1000217Y794147D01*
X1000883Y794313D01*
X1001467Y794230D01*
X1001883Y794063D01*
X1002300Y793730D01*
G01X1010500Y790980D02*
Y795980D01*
G01Y793480D02*
X1010917Y793980D01*
X1011417Y794230D01*
X1011917Y794313D01*
X1012667Y794147D01*
X1013167Y793813D01*
X1013500Y793230D01*
Y792563D01*
X1013333Y791897D01*
X1013000Y791397D01*
X1012417Y791063D01*
X1011917Y790980D01*
X1011417Y791063D01*
X1010917Y791313D01*
X1010500Y791730D01*
G01X1017600Y790980D02*
X1017100Y791063D01*
X1016600Y791397D01*
X1016267Y791980D01*
X1016100Y792647D01*
X1016267Y793313D01*
X1016600Y793897D01*
X1017100Y794230D01*
X1017600Y794313D01*
X1018100Y794230D01*
X1018600Y793897D01*
X1018933Y793313D01*
X1019017Y792647D01*
X1018933Y791980D01*
X1018600Y791397D01*
X1018100Y791063D01*
X1017600Y790980D01*
G01X1021117Y794313D02*
X1022117Y790980D01*
X1023200Y794313D01*
X1024283Y790980D01*
X1025283Y794313D01*
G01X957500Y811500D02*
X959167D01*
Y810000D01*
X958667Y809500D01*
X958083Y809167D01*
X957250Y809000D01*
X956417Y809167D01*
X955833Y809500D01*
X955333Y810000D01*
X955000Y810583D01*
X954833Y811250D01*
Y811833D01*
X955000Y812333D01*
X955333Y812917D01*
X955833Y813417D01*
X956333Y813750D01*
X957000Y814000D01*
X957583D01*
X958250Y813833D01*
X958750Y813500D01*
G01X961100Y808833D02*
X964100Y814000D01*
G01X966617Y809000D02*
Y814000D01*
X969783D01*
G01X968617Y811583D02*
X966617D01*
G01X977650Y809667D02*
X978317Y809250D01*
X979067Y809000D01*
X979733D01*
X980400Y809250D01*
X980900Y809667D01*
X981150Y810250D01*
X980983Y810833D01*
X980567Y811333D01*
X979817Y811667D01*
X978817Y811833D01*
X978233Y812167D01*
X977983Y812750D01*
X978150Y813333D01*
X978567Y813750D01*
X979150Y814000D01*
X979733D01*
X980317Y813833D01*
X980817Y813417D01*
G01X985000Y809000D02*
Y814000D01*
G01X990600Y809000D02*
X990100Y809083D01*
X989600Y809417D01*
X989267Y810000D01*
X989100Y810667D01*
X989267Y811333D01*
X989600Y811917D01*
X990100Y812250D01*
X990600Y812333D01*
X991100Y812250D01*
X991600Y811917D01*
X991933Y811333D01*
X992017Y810667D01*
X991933Y810000D01*
X991600Y809417D01*
X991100Y809083D01*
X990600Y809000D01*
G01X996200Y814000D02*
Y809000D01*
G01X995033Y812333D02*
X997367D01*
G01X948000Y850610D02*
Y782110D01*
G01X948500Y819500D02*
X1343000D01*
G01X955750Y826250D02*
X958417D01*
X958167Y826833D01*
X957750Y827167D01*
X957167Y827333D01*
X956583Y827250D01*
X956083Y827000D01*
X955750Y826417D01*
X955583Y825917D01*
Y825417D01*
X955750Y824917D01*
X956167Y824417D01*
X956667Y824083D01*
X957250Y824000D01*
X957833Y824167D01*
X958417Y824667D01*
G01X964100Y829000D02*
Y824000D01*
G01Y824750D02*
X963767Y824333D01*
X963267Y824083D01*
X962683Y824000D01*
X962017Y824167D01*
X961517Y824583D01*
X961183Y825083D01*
X961100Y825667D01*
X961183Y826250D01*
X961517Y826750D01*
X962017Y827167D01*
X962683Y827333D01*
X963267Y827250D01*
X963683Y827083D01*
X964100Y826750D01*
G01X967033Y822750D02*
X967617Y822417D01*
X968283Y822333D01*
X968867Y822417D01*
X969367Y822833D01*
X969700Y823417D01*
Y827333D01*
G01Y826667D02*
X969367Y827000D01*
X968867Y827250D01*
X968283Y827333D01*
X967617Y827167D01*
X967200Y826833D01*
X966867Y826250D01*
X966700Y825667D01*
X966783Y825167D01*
X967117Y824583D01*
X967617Y824167D01*
X968283Y824000D01*
X968783Y824083D01*
X969367Y824417D01*
X969700Y824750D01*
G01X972550Y826250D02*
X975217D01*
X974967Y826833D01*
X974550Y827167D01*
X973967Y827333D01*
X973383Y827250D01*
X972883Y827000D01*
X972550Y826417D01*
X972383Y825917D01*
Y825417D01*
X972550Y824917D01*
X972967Y824417D01*
X973467Y824083D01*
X974050Y824000D01*
X974633Y824167D01*
X975217Y824667D01*
G01X985000Y829000D02*
Y824000D01*
G01X983833Y827333D02*
X986167D01*
G01X990600Y824000D02*
X990100Y824083D01*
X989600Y824417D01*
X989267Y825000D01*
X989100Y825667D01*
X989267Y826333D01*
X989600Y826917D01*
X990100Y827250D01*
X990600Y827333D01*
X991100Y827250D01*
X991600Y826917D01*
X991933Y826333D01*
X992017Y825667D01*
X991933Y825000D01*
X991600Y824417D01*
X991100Y824083D01*
X990600Y824000D01*
G01X1000383D02*
Y829000D01*
G01Y826583D02*
X1000800Y827000D01*
X1001217Y827250D01*
X1001883Y827333D01*
X1002383Y827250D01*
X1002967Y826917D01*
X1003217Y826417D01*
Y824000D01*
G01X1007400D02*
X1006900Y824083D01*
X1006400Y824417D01*
X1006067Y825000D01*
X1005900Y825667D01*
X1006067Y826333D01*
X1006400Y826917D01*
X1006900Y827250D01*
X1007400Y827333D01*
X1007900Y827250D01*
X1008400Y826917D01*
X1008733Y826333D01*
X1008817Y825667D01*
X1008733Y825000D01*
X1008400Y824417D01*
X1007900Y824083D01*
X1007400Y824000D01*
G01X1013000D02*
Y829000D01*
G01X1017350Y826250D02*
X1020017D01*
X1019767Y826833D01*
X1019350Y827167D01*
X1018767Y827333D01*
X1018183Y827250D01*
X1017683Y827000D01*
X1017350Y826417D01*
X1017183Y825917D01*
Y825417D01*
X1017350Y824917D01*
X1017767Y824417D01*
X1018267Y824083D01*
X1018850Y824000D01*
X1019433Y824167D01*
X1020017Y824667D01*
G01X955750Y842750D02*
X958417D01*
X958167Y843333D01*
X957750Y843667D01*
X957167Y843833D01*
X956583Y843750D01*
X956083Y843500D01*
X955750Y842917D01*
X955583Y842417D01*
Y841917D01*
X955750Y841417D01*
X956167Y840917D01*
X956667Y840583D01*
X957250Y840500D01*
X957833Y840667D01*
X958417Y841167D01*
G01X964100Y845500D02*
Y840500D01*
G01Y841250D02*
X963767Y840833D01*
X963267Y840583D01*
X962683Y840500D01*
X962017Y840667D01*
X961517Y841083D01*
X961183Y841583D01*
X961100Y842167D01*
X961183Y842750D01*
X961517Y843250D01*
X962017Y843667D01*
X962683Y843833D01*
X963267Y843750D01*
X963683Y843583D01*
X964100Y843250D01*
G01X967033Y839250D02*
X967617Y838917D01*
X968283Y838833D01*
X968867Y838917D01*
X969367Y839333D01*
X969700Y839917D01*
Y843833D01*
G01Y843167D02*
X969367Y843500D01*
X968867Y843750D01*
X968283Y843833D01*
X967617Y843667D01*
X967200Y843333D01*
X966867Y842750D01*
X966700Y842167D01*
X966783Y841667D01*
X967117Y841083D01*
X967617Y840667D01*
X968283Y840500D01*
X968783Y840583D01*
X969367Y840917D01*
X969700Y841250D01*
G01X972550Y842750D02*
X975217D01*
X974967Y843333D01*
X974550Y843667D01*
X973967Y843833D01*
X973383Y843750D01*
X972883Y843500D01*
X972550Y842917D01*
X972383Y842417D01*
Y841917D01*
X972550Y841417D01*
X972967Y840917D01*
X973467Y840583D01*
X974050Y840500D01*
X974633Y840667D01*
X975217Y841167D01*
G01X985000Y845500D02*
Y840500D01*
G01X983833Y843833D02*
X986167D01*
G01X990600Y840500D02*
X990100Y840583D01*
X989600Y840917D01*
X989267Y841500D01*
X989100Y842167D01*
X989267Y842833D01*
X989600Y843417D01*
X990100Y843750D01*
X990600Y843833D01*
X991100Y843750D01*
X991600Y843417D01*
X991933Y842833D01*
X992017Y842167D01*
X991933Y841500D01*
X991600Y840917D01*
X991100Y840583D01*
X990600Y840500D01*
G01X1000550Y842750D02*
X1003217D01*
X1002967Y843333D01*
X1002550Y843667D01*
X1001967Y843833D01*
X1001383Y843750D01*
X1000883Y843500D01*
X1000550Y842917D01*
X1000383Y842417D01*
Y841917D01*
X1000550Y841417D01*
X1000967Y840917D01*
X1001467Y840583D01*
X1002050Y840500D01*
X1002633Y840667D01*
X1003217Y841167D01*
G01X1008900Y845500D02*
Y840500D01*
G01Y841250D02*
X1008567Y840833D01*
X1008067Y840583D01*
X1007483Y840500D01*
X1006817Y840667D01*
X1006317Y841083D01*
X1005983Y841583D01*
X1005900Y842167D01*
X1005983Y842750D01*
X1006317Y843250D01*
X1006817Y843667D01*
X1007483Y843833D01*
X1008067Y843750D01*
X1008483Y843583D01*
X1008900Y843250D01*
G01X1011833Y839250D02*
X1012417Y838917D01*
X1013083Y838833D01*
X1013667Y838917D01*
X1014167Y839333D01*
X1014500Y839917D01*
Y843833D01*
G01Y843167D02*
X1014167Y843500D01*
X1013667Y843750D01*
X1013083Y843833D01*
X1012417Y843667D01*
X1012000Y843333D01*
X1011667Y842750D01*
X1011500Y842167D01*
X1011583Y841667D01*
X1011917Y841083D01*
X1012417Y840667D01*
X1013083Y840500D01*
X1013583Y840583D01*
X1014167Y840917D01*
X1014500Y841250D01*
G01X1017350Y842750D02*
X1020017D01*
X1019767Y843333D01*
X1019350Y843667D01*
X1018767Y843833D01*
X1018183Y843750D01*
X1017683Y843500D01*
X1017350Y842917D01*
X1017183Y842417D01*
Y841917D01*
X1017350Y841417D01*
X1017767Y840917D01*
X1018267Y840583D01*
X1018850Y840500D01*
X1019433Y840667D01*
X1020017Y841167D01*
G01X948500Y834500D02*
X1343000D01*
G01X955750Y826250D02*
X958417D01*
X958167Y826833D01*
X957750Y827167D01*
X957167Y827333D01*
X956583Y827250D01*
X956083Y827000D01*
X955750Y826417D01*
X955583Y825917D01*
Y825417D01*
X955750Y824917D01*
X956167Y824417D01*
X956667Y824083D01*
X957250Y824000D01*
X957833Y824167D01*
X958417Y824667D01*
G01X964100Y829000D02*
Y824000D01*
G01Y824750D02*
X963767Y824333D01*
X963267Y824083D01*
X962683Y824000D01*
X962017Y824167D01*
X961517Y824583D01*
X961183Y825083D01*
X961100Y825667D01*
X961183Y826250D01*
X961517Y826750D01*
X962017Y827167D01*
X962683Y827333D01*
X963267Y827250D01*
X963683Y827083D01*
X964100Y826750D01*
G01X967033Y822750D02*
X967617Y822417D01*
X968283Y822333D01*
X968867Y822417D01*
X969367Y822833D01*
X969700Y823417D01*
Y827333D01*
G01Y826667D02*
X969367Y827000D01*
X968867Y827250D01*
X968283Y827333D01*
X967617Y827167D01*
X967200Y826833D01*
X966867Y826250D01*
X966700Y825667D01*
X966783Y825167D01*
X967117Y824583D01*
X967617Y824167D01*
X968283Y824000D01*
X968783Y824083D01*
X969367Y824417D01*
X969700Y824750D01*
G01X972550Y826250D02*
X975217D01*
X974967Y826833D01*
X974550Y827167D01*
X973967Y827333D01*
X973383Y827250D01*
X972883Y827000D01*
X972550Y826417D01*
X972383Y825917D01*
Y825417D01*
X972550Y824917D01*
X972967Y824417D01*
X973467Y824083D01*
X974050Y824000D01*
X974633Y824167D01*
X975217Y824667D01*
G01X985000Y829000D02*
Y824000D01*
G01X983833Y827333D02*
X986167D01*
G01X990600Y824000D02*
X990100Y824083D01*
X989600Y824417D01*
X989267Y825000D01*
X989100Y825667D01*
X989267Y826333D01*
X989600Y826917D01*
X990100Y827250D01*
X990600Y827333D01*
X991100Y827250D01*
X991600Y826917D01*
X991933Y826333D01*
X992017Y825667D01*
X991933Y825000D01*
X991600Y824417D01*
X991100Y824083D01*
X990600Y824000D01*
G01X1000383D02*
Y829000D01*
G01Y826583D02*
X1000800Y827000D01*
X1001217Y827250D01*
X1001883Y827333D01*
X1002383Y827250D01*
X1002967Y826917D01*
X1003217Y826417D01*
Y824000D01*
G01X1007400D02*
X1006900Y824083D01*
X1006400Y824417D01*
X1006067Y825000D01*
X1005900Y825667D01*
X1006067Y826333D01*
X1006400Y826917D01*
X1006900Y827250D01*
X1007400Y827333D01*
X1007900Y827250D01*
X1008400Y826917D01*
X1008733Y826333D01*
X1008817Y825667D01*
X1008733Y825000D01*
X1008400Y824417D01*
X1007900Y824083D01*
X1007400Y824000D01*
G01X1013000D02*
Y829000D01*
G01X1017350Y826250D02*
X1020017D01*
X1019767Y826833D01*
X1019350Y827167D01*
X1018767Y827333D01*
X1018183Y827250D01*
X1017683Y827000D01*
X1017350Y826417D01*
X1017183Y825917D01*
Y825417D01*
X1017350Y824917D01*
X1017767Y824417D01*
X1018267Y824083D01*
X1018850Y824000D01*
X1019433Y824167D01*
X1020017Y824667D01*
G01X955750Y842750D02*
X958417D01*
X958167Y843333D01*
X957750Y843667D01*
X957167Y843833D01*
X956583Y843750D01*
X956083Y843500D01*
X955750Y842917D01*
X955583Y842417D01*
Y841917D01*
X955750Y841417D01*
X956167Y840917D01*
X956667Y840583D01*
X957250Y840500D01*
X957833Y840667D01*
X958417Y841167D01*
G01X964100Y845500D02*
Y840500D01*
G01Y841250D02*
X963767Y840833D01*
X963267Y840583D01*
X962683Y840500D01*
X962017Y840667D01*
X961517Y841083D01*
X961183Y841583D01*
X961100Y842167D01*
X961183Y842750D01*
X961517Y843250D01*
X962017Y843667D01*
X962683Y843833D01*
X963267Y843750D01*
X963683Y843583D01*
X964100Y843250D01*
G01X967033Y839250D02*
X967617Y838917D01*
X968283Y838833D01*
X968867Y838917D01*
X969367Y839333D01*
X969700Y839917D01*
Y843833D01*
G01Y843167D02*
X969367Y843500D01*
X968867Y843750D01*
X968283Y843833D01*
X967617Y843667D01*
X967200Y843333D01*
X966867Y842750D01*
X966700Y842167D01*
X966783Y841667D01*
X967117Y841083D01*
X967617Y840667D01*
X968283Y840500D01*
X968783Y840583D01*
X969367Y840917D01*
X969700Y841250D01*
G01X972550Y842750D02*
X975217D01*
X974967Y843333D01*
X974550Y843667D01*
X973967Y843833D01*
X973383Y843750D01*
X972883Y843500D01*
X972550Y842917D01*
X972383Y842417D01*
Y841917D01*
X972550Y841417D01*
X972967Y840917D01*
X973467Y840583D01*
X974050Y840500D01*
X974633Y840667D01*
X975217Y841167D01*
G01X985000Y845500D02*
Y840500D01*
G01X983833Y843833D02*
X986167D01*
G01X990600Y840500D02*
X990100Y840583D01*
X989600Y840917D01*
X989267Y841500D01*
X989100Y842167D01*
X989267Y842833D01*
X989600Y843417D01*
X990100Y843750D01*
X990600Y843833D01*
X991100Y843750D01*
X991600Y843417D01*
X991933Y842833D01*
X992017Y842167D01*
X991933Y841500D01*
X991600Y840917D01*
X991100Y840583D01*
X990600Y840500D01*
G01X1000550Y842750D02*
X1003217D01*
X1002967Y843333D01*
X1002550Y843667D01*
X1001967Y843833D01*
X1001383Y843750D01*
X1000883Y843500D01*
X1000550Y842917D01*
X1000383Y842417D01*
Y841917D01*
X1000550Y841417D01*
X1000967Y840917D01*
X1001467Y840583D01*
X1002050Y840500D01*
X1002633Y840667D01*
X1003217Y841167D01*
G01X1008900Y845500D02*
Y840500D01*
G01Y841250D02*
X1008567Y840833D01*
X1008067Y840583D01*
X1007483Y840500D01*
X1006817Y840667D01*
X1006317Y841083D01*
X1005983Y841583D01*
X1005900Y842167D01*
X1005983Y842750D01*
X1006317Y843250D01*
X1006817Y843667D01*
X1007483Y843833D01*
X1008067Y843750D01*
X1008483Y843583D01*
X1008900Y843250D01*
G01X1011833Y839250D02*
X1012417Y838917D01*
X1013083Y838833D01*
X1013667Y838917D01*
X1014167Y839333D01*
X1014500Y839917D01*
Y843833D01*
G01Y843167D02*
X1014167Y843500D01*
X1013667Y843750D01*
X1013083Y843833D01*
X1012417Y843667D01*
X1012000Y843333D01*
X1011667Y842750D01*
X1011500Y842167D01*
X1011583Y841667D01*
X1011917Y841083D01*
X1012417Y840667D01*
X1013083Y840500D01*
X1013583Y840583D01*
X1014167Y840917D01*
X1014500Y841250D01*
G01X1017350Y842750D02*
X1020017D01*
X1019767Y843333D01*
X1019350Y843667D01*
X1018767Y843833D01*
X1018183Y843750D01*
X1017683Y843500D01*
X1017350Y842917D01*
X1017183Y842417D01*
Y841917D01*
X1017350Y841417D01*
X1017767Y840917D01*
X1018267Y840583D01*
X1018850Y840500D01*
X1019433Y840667D01*
X1020017Y841167D01*
G01X948500Y834500D02*
X1343000D01*
G01X995667Y5500D02*
Y10500D01*
X997333D01*
X998000Y10250D01*
X998500Y9917D01*
X998917Y9417D01*
X999250Y8833D01*
X999333Y8000D01*
X999250Y7167D01*
X998917Y6583D01*
X998500Y6083D01*
X998000Y5750D01*
X997333Y5500D01*
X995667D01*
G01X1003100D02*
Y10500D01*
X1002100Y9500D01*
G01Y5500D02*
X1004100D01*
G01X1007117Y7583D02*
X1007700Y8167D01*
X1008200Y8500D01*
X1008867Y8667D01*
X1009450Y8500D01*
X1009867Y8167D01*
X1010200Y7667D01*
X1010283Y7083D01*
X1010200Y6583D01*
X1009867Y6083D01*
X1009367Y5667D01*
X1008783Y5500D01*
X1008117Y5667D01*
X1007533Y6167D01*
X1007200Y6917D01*
X1007117Y7750D01*
X1007283Y8833D01*
X1007533Y9417D01*
X1007950Y10000D01*
X1008533Y10417D01*
X1009117Y10500D01*
X1009700Y10333D01*
X1010117Y9917D01*
G01X1014300Y5333D02*
X1014133Y5417D01*
Y5583D01*
X1014300Y5667D01*
X1014467Y5583D01*
Y5417D01*
X1014300Y5333D01*
G01Y7583D02*
X1014133Y7667D01*
Y7833D01*
X1014300Y7917D01*
X1014467Y7833D01*
Y7667D01*
X1014300Y7583D01*
G01X1018067Y5500D02*
Y10500D01*
X1019733D01*
X1020400Y10250D01*
X1020900Y9917D01*
X1021317Y9417D01*
X1021650Y8833D01*
X1021733Y8000D01*
X1021650Y7167D01*
X1021317Y6583D01*
X1020900Y6083D01*
X1020400Y5750D01*
X1019733Y5500D01*
X1018067D01*
G01X1025500Y8833D02*
Y5500D01*
G01Y10167D02*
X1025333Y10250D01*
Y10417D01*
X1025500Y10500D01*
X1025667Y10417D01*
Y10250D01*
X1025500Y10167D01*
G01X1032600Y5500D02*
Y8833D01*
G01Y8250D02*
X1032267Y8583D01*
X1031767Y8750D01*
X1031183Y8833D01*
X1030600Y8667D01*
X1030100Y8333D01*
X1029767Y7833D01*
X1029600Y7167D01*
X1029767Y6500D01*
X1030100Y6000D01*
X1030600Y5667D01*
X1031183Y5500D01*
X1031767Y5583D01*
X1032267Y5833D01*
X1032600Y6167D01*
G01X1034200Y5500D02*
Y8833D01*
G01Y7917D02*
X1034450Y8333D01*
X1034867Y8667D01*
X1035450Y8833D01*
X1036033Y8667D01*
X1036450Y8333D01*
X1036700Y7917D01*
Y5500D01*
G01Y7917D02*
X1036950Y8333D01*
X1037367Y8667D01*
X1037950Y8833D01*
X1038533Y8667D01*
X1038950Y8333D01*
X1039200Y7833D01*
Y5500D01*
G01X1041050Y7750D02*
X1043717D01*
X1043467Y8333D01*
X1043050Y8667D01*
X1042467Y8833D01*
X1041883Y8750D01*
X1041383Y8500D01*
X1041050Y7917D01*
X1040883Y7417D01*
Y6917D01*
X1041050Y6417D01*
X1041467Y5917D01*
X1041967Y5583D01*
X1042550Y5500D01*
X1043133Y5667D01*
X1043717Y6167D01*
G01X1047900Y10500D02*
Y5500D01*
G01X1046733Y8833D02*
X1049067D01*
G01X1052250Y7750D02*
X1054917D01*
X1054667Y8333D01*
X1054250Y8667D01*
X1053667Y8833D01*
X1053083Y8750D01*
X1052583Y8500D01*
X1052250Y7917D01*
X1052083Y7417D01*
Y6917D01*
X1052250Y6417D01*
X1052667Y5917D01*
X1053167Y5583D01*
X1053750Y5500D01*
X1054333Y5667D01*
X1054917Y6167D01*
G01X1057933Y5500D02*
Y8833D01*
G01Y8167D02*
X1058350Y8500D01*
X1058767Y8750D01*
X1059350Y8833D01*
X1059767Y8750D01*
X1060267Y8500D01*
G01X1070300Y5500D02*
Y10500D01*
X1069300Y9500D01*
G01Y5500D02*
X1071300D01*
G01X1074317Y7583D02*
X1074900Y8167D01*
X1075400Y8500D01*
X1076067Y8667D01*
X1076650Y8500D01*
X1077067Y8167D01*
X1077400Y7667D01*
X1077483Y7083D01*
X1077400Y6583D01*
X1077067Y6083D01*
X1076567Y5667D01*
X1075983Y5500D01*
X1075317Y5667D01*
X1074733Y6167D01*
X1074400Y6917D01*
X1074317Y7750D01*
X1074483Y8833D01*
X1074733Y9417D01*
X1075150Y10000D01*
X1075733Y10417D01*
X1076317Y10500D01*
X1076900Y10333D01*
X1077317Y9917D01*
G01X1079000Y5500D02*
Y8833D01*
G01Y7917D02*
X1079250Y8333D01*
X1079667Y8667D01*
X1080250Y8833D01*
X1080833Y8667D01*
X1081250Y8333D01*
X1081500Y7917D01*
Y5500D01*
G01Y7917D02*
X1081750Y8333D01*
X1082167Y8667D01*
X1082750Y8833D01*
X1083333Y8667D01*
X1083750Y8333D01*
X1084000Y7833D01*
Y5500D01*
G01X1087100Y8833D02*
Y5500D01*
G01Y10167D02*
X1086933Y10250D01*
Y10417D01*
X1087100Y10500D01*
X1087267Y10417D01*
Y10250D01*
X1087100Y10167D01*
G01X1092700Y5500D02*
Y10500D01*
G01X995667Y5500D02*
Y10500D01*
X997333D01*
X998000Y10250D01*
X998500Y9917D01*
X998917Y9417D01*
X999250Y8833D01*
X999333Y8000D01*
X999250Y7167D01*
X998917Y6583D01*
X998500Y6083D01*
X998000Y5750D01*
X997333Y5500D01*
X995667D01*
G01X1003100D02*
Y10500D01*
X1002100Y9500D01*
G01Y5500D02*
X1004100D01*
G01X1007117Y7583D02*
X1007700Y8167D01*
X1008200Y8500D01*
X1008867Y8667D01*
X1009450Y8500D01*
X1009867Y8167D01*
X1010200Y7667D01*
X1010283Y7083D01*
X1010200Y6583D01*
X1009867Y6083D01*
X1009367Y5667D01*
X1008783Y5500D01*
X1008117Y5667D01*
X1007533Y6167D01*
X1007200Y6917D01*
X1007117Y7750D01*
X1007283Y8833D01*
X1007533Y9417D01*
X1007950Y10000D01*
X1008533Y10417D01*
X1009117Y10500D01*
X1009700Y10333D01*
X1010117Y9917D01*
G01X1014300Y5333D02*
X1014133Y5417D01*
Y5583D01*
X1014300Y5667D01*
X1014467Y5583D01*
Y5417D01*
X1014300Y5333D01*
G01Y7583D02*
X1014133Y7667D01*
Y7833D01*
X1014300Y7917D01*
X1014467Y7833D01*
Y7667D01*
X1014300Y7583D01*
G01X1018067Y5500D02*
Y10500D01*
X1019733D01*
X1020400Y10250D01*
X1020900Y9917D01*
X1021317Y9417D01*
X1021650Y8833D01*
X1021733Y8000D01*
X1021650Y7167D01*
X1021317Y6583D01*
X1020900Y6083D01*
X1020400Y5750D01*
X1019733Y5500D01*
X1018067D01*
G01X1025500Y8833D02*
Y5500D01*
G01Y10167D02*
X1025333Y10250D01*
Y10417D01*
X1025500Y10500D01*
X1025667Y10417D01*
Y10250D01*
X1025500Y10167D01*
G01X1032600Y5500D02*
Y8833D01*
G01Y8250D02*
X1032267Y8583D01*
X1031767Y8750D01*
X1031183Y8833D01*
X1030600Y8667D01*
X1030100Y8333D01*
X1029767Y7833D01*
X1029600Y7167D01*
X1029767Y6500D01*
X1030100Y6000D01*
X1030600Y5667D01*
X1031183Y5500D01*
X1031767Y5583D01*
X1032267Y5833D01*
X1032600Y6167D01*
G01X1034200Y5500D02*
Y8833D01*
G01Y7917D02*
X1034450Y8333D01*
X1034867Y8667D01*
X1035450Y8833D01*
X1036033Y8667D01*
X1036450Y8333D01*
X1036700Y7917D01*
Y5500D01*
G01Y7917D02*
X1036950Y8333D01*
X1037367Y8667D01*
X1037950Y8833D01*
X1038533Y8667D01*
X1038950Y8333D01*
X1039200Y7833D01*
Y5500D01*
G01X1041050Y7750D02*
X1043717D01*
X1043467Y8333D01*
X1043050Y8667D01*
X1042467Y8833D01*
X1041883Y8750D01*
X1041383Y8500D01*
X1041050Y7917D01*
X1040883Y7417D01*
Y6917D01*
X1041050Y6417D01*
X1041467Y5917D01*
X1041967Y5583D01*
X1042550Y5500D01*
X1043133Y5667D01*
X1043717Y6167D01*
G01X1047900Y10500D02*
Y5500D01*
G01X1046733Y8833D02*
X1049067D01*
G01X1052250Y7750D02*
X1054917D01*
X1054667Y8333D01*
X1054250Y8667D01*
X1053667Y8833D01*
X1053083Y8750D01*
X1052583Y8500D01*
X1052250Y7917D01*
X1052083Y7417D01*
Y6917D01*
X1052250Y6417D01*
X1052667Y5917D01*
X1053167Y5583D01*
X1053750Y5500D01*
X1054333Y5667D01*
X1054917Y6167D01*
G01X1057933Y5500D02*
Y8833D01*
G01Y8167D02*
X1058350Y8500D01*
X1058767Y8750D01*
X1059350Y8833D01*
X1059767Y8750D01*
X1060267Y8500D01*
G01X1070300Y5500D02*
Y10500D01*
X1069300Y9500D01*
G01Y5500D02*
X1071300D01*
G01X1074317Y7583D02*
X1074900Y8167D01*
X1075400Y8500D01*
X1076067Y8667D01*
X1076650Y8500D01*
X1077067Y8167D01*
X1077400Y7667D01*
X1077483Y7083D01*
X1077400Y6583D01*
X1077067Y6083D01*
X1076567Y5667D01*
X1075983Y5500D01*
X1075317Y5667D01*
X1074733Y6167D01*
X1074400Y6917D01*
X1074317Y7750D01*
X1074483Y8833D01*
X1074733Y9417D01*
X1075150Y10000D01*
X1075733Y10417D01*
X1076317Y10500D01*
X1076900Y10333D01*
X1077317Y9917D01*
G01X1079000Y5500D02*
Y8833D01*
G01Y7917D02*
X1079250Y8333D01*
X1079667Y8667D01*
X1080250Y8833D01*
X1080833Y8667D01*
X1081250Y8333D01*
X1081500Y7917D01*
Y5500D01*
G01Y7917D02*
X1081750Y8333D01*
X1082167Y8667D01*
X1082750Y8833D01*
X1083333Y8667D01*
X1083750Y8333D01*
X1084000Y7833D01*
Y5500D01*
G01X1087100Y8833D02*
Y5500D01*
G01Y10167D02*
X1086933Y10250D01*
Y10417D01*
X1087100Y10500D01*
X1087267Y10417D01*
Y10250D01*
X1087100Y10167D01*
G01X1092700Y5500D02*
Y10500D01*
G01X1026000Y336000D02*
Y86000D01*
G01Y336000D02*
Y86000D01*
G01X1033500Y370500D02*
Y375500D01*
G01Y373000D02*
X1033917Y373500D01*
X1034417Y373750D01*
X1034917Y373833D01*
X1035667Y373667D01*
X1036167Y373333D01*
X1036500Y372750D01*
Y372083D01*
X1036333Y371417D01*
X1036000Y370917D01*
X1035417Y370583D01*
X1034917Y370500D01*
X1034417Y370583D01*
X1033917Y370833D01*
X1033500Y371250D01*
G01X1039183Y373833D02*
Y371500D01*
X1039517Y370917D01*
X1040017Y370583D01*
X1040600Y370500D01*
X1041183Y370583D01*
X1041683Y370917D01*
X1042017Y371500D01*
G01Y370500D02*
Y373833D01*
G01X1044700Y370500D02*
Y375500D01*
G01Y373000D02*
X1045117Y373500D01*
X1045617Y373750D01*
X1046117Y373833D01*
X1046867Y373667D01*
X1047367Y373333D01*
X1047700Y372750D01*
Y372083D01*
X1047533Y371417D01*
X1047200Y370917D01*
X1046617Y370583D01*
X1046117Y370500D01*
X1045617Y370583D01*
X1045117Y370833D01*
X1044700Y371250D01*
G01X1050300Y370500D02*
Y375500D01*
G01Y373000D02*
X1050717Y373500D01*
X1051217Y373750D01*
X1051717Y373833D01*
X1052467Y373667D01*
X1052967Y373333D01*
X1053300Y372750D01*
Y372083D01*
X1053133Y371417D01*
X1052800Y370917D01*
X1052217Y370583D01*
X1051717Y370500D01*
X1051217Y370583D01*
X1050717Y370833D01*
X1050300Y371250D01*
G01X1057400Y370500D02*
Y375500D01*
G01X1061750Y372750D02*
X1064417D01*
X1064167Y373333D01*
X1063750Y373667D01*
X1063167Y373833D01*
X1062583Y373750D01*
X1062083Y373500D01*
X1061750Y372917D01*
X1061583Y372417D01*
Y371917D01*
X1061750Y371417D01*
X1062167Y370917D01*
X1062667Y370583D01*
X1063250Y370500D01*
X1063833Y370667D01*
X1064417Y371167D01*
G01X1074200Y373833D02*
Y370500D01*
G01Y375167D02*
X1074033Y375250D01*
Y375417D01*
X1074200Y375500D01*
X1074367Y375417D01*
Y375250D01*
X1074200Y375167D01*
G01X1078383Y370500D02*
Y373833D01*
G01Y373000D02*
X1078717Y373417D01*
X1079217Y373750D01*
X1079883Y373833D01*
X1080467Y373750D01*
X1080967Y373417D01*
X1081217Y372833D01*
Y370500D01*
G01X1084150Y371083D02*
X1084567Y370750D01*
X1085150Y370500D01*
X1085650D01*
X1086150Y370667D01*
X1086483Y370917D01*
X1086650Y371250D01*
X1086567Y371750D01*
X1086233Y372000D01*
X1084733Y372500D01*
X1084400Y373083D01*
X1084567Y373500D01*
X1084900Y373750D01*
X1085400Y373833D01*
X1085900Y373750D01*
X1086400Y373500D01*
G01X1091000Y373833D02*
Y370500D01*
G01Y375167D02*
X1090833Y375250D01*
Y375417D01*
X1091000Y375500D01*
X1091167Y375417D01*
Y375250D01*
X1091000Y375167D01*
G01X1098100Y375500D02*
Y370500D01*
G01Y371250D02*
X1097767Y370833D01*
X1097267Y370583D01*
X1096683Y370500D01*
X1096017Y370667D01*
X1095517Y371083D01*
X1095183Y371583D01*
X1095100Y372167D01*
X1095183Y372750D01*
X1095517Y373250D01*
X1096017Y373667D01*
X1096683Y373833D01*
X1097267Y373750D01*
X1097683Y373583D01*
X1098100Y373250D01*
G01X1100950Y372750D02*
X1103617D01*
X1103367Y373333D01*
X1102950Y373667D01*
X1102367Y373833D01*
X1101783Y373750D01*
X1101283Y373500D01*
X1100950Y372917D01*
X1100783Y372417D01*
Y371917D01*
X1100950Y371417D01*
X1101367Y370917D01*
X1101867Y370583D01*
X1102450Y370500D01*
X1103033Y370667D01*
X1103617Y371167D01*
G01X1113400Y375500D02*
Y370500D01*
G01X1112233Y373833D02*
X1114567D01*
G01X1117583Y370500D02*
Y375500D01*
G01Y373083D02*
X1118000Y373500D01*
X1118417Y373750D01*
X1119083Y373833D01*
X1119583Y373750D01*
X1120167Y373417D01*
X1120417Y372917D01*
Y370500D01*
G01X1123350Y372750D02*
X1126017D01*
X1125767Y373333D01*
X1125350Y373667D01*
X1124767Y373833D01*
X1124183Y373750D01*
X1123683Y373500D01*
X1123350Y372917D01*
X1123183Y372417D01*
Y371917D01*
X1123350Y371417D01*
X1123767Y370917D01*
X1124267Y370583D01*
X1124850Y370500D01*
X1125433Y370667D01*
X1126017Y371167D01*
G01X1134633Y370500D02*
Y373833D01*
G01Y373167D02*
X1135050Y373500D01*
X1135467Y373750D01*
X1136050Y373833D01*
X1136467Y373750D01*
X1136967Y373500D01*
G01X1140150Y372750D02*
X1142817D01*
X1142567Y373333D01*
X1142150Y373667D01*
X1141567Y373833D01*
X1140983Y373750D01*
X1140483Y373500D01*
X1140150Y372917D01*
X1139983Y372417D01*
Y371917D01*
X1140150Y371417D01*
X1140567Y370917D01*
X1141067Y370583D01*
X1141650Y370500D01*
X1142233Y370667D01*
X1142817Y371167D01*
G01X1145750Y371083D02*
X1146167Y370750D01*
X1146750Y370500D01*
X1147250D01*
X1147750Y370667D01*
X1148083Y370917D01*
X1148250Y371250D01*
X1148167Y371750D01*
X1147833Y372000D01*
X1146333Y372500D01*
X1146000Y373083D01*
X1146167Y373500D01*
X1146500Y373750D01*
X1147000Y373833D01*
X1147500Y373750D01*
X1148000Y373500D01*
G01X1152600Y373833D02*
Y370500D01*
G01Y375167D02*
X1152433Y375250D01*
Y375417D01*
X1152600Y375500D01*
X1152767Y375417D01*
Y375250D01*
X1152600Y375167D01*
G01X1156783Y370500D02*
Y373833D01*
G01Y373000D02*
X1157117Y373417D01*
X1157617Y373750D01*
X1158283Y373833D01*
X1158867Y373750D01*
X1159367Y373417D01*
X1159617Y372833D01*
Y370500D01*
G01X1163800Y370333D02*
X1163633Y370417D01*
Y370583D01*
X1163800Y370667D01*
X1163967Y370583D01*
Y370417D01*
X1163800Y370333D01*
G01X1021417Y383667D02*
X1021917Y384167D01*
X1022500Y384417D01*
X1023167Y384500D01*
X1024000Y384333D01*
X1024583Y383917D01*
X1024750Y383417D01*
X1024667Y382917D01*
X1024333Y382500D01*
X1022667Y381667D01*
X1021917Y381083D01*
X1021417Y380250D01*
X1021250Y379500D01*
X1024750D01*
G01X1028600Y379333D02*
X1028433Y379417D01*
Y379583D01*
X1028600Y379667D01*
X1028767Y379583D01*
Y379417D01*
X1028600Y379333D01*
G01X1032117Y384500D02*
X1034200Y379500D01*
X1036283Y384500D01*
G01X1039800Y382833D02*
Y379500D01*
G01Y384167D02*
X1039633Y384250D01*
Y384417D01*
X1039800Y384500D01*
X1039967Y384417D01*
Y384250D01*
X1039800Y384167D01*
G01X1046900Y379500D02*
Y382833D01*
G01Y382250D02*
X1046567Y382583D01*
X1046067Y382750D01*
X1045483Y382833D01*
X1044900Y382667D01*
X1044400Y382333D01*
X1044067Y381833D01*
X1043900Y381167D01*
X1044067Y380500D01*
X1044400Y380000D01*
X1044900Y379667D01*
X1045483Y379500D01*
X1046067Y379583D01*
X1046567Y379833D01*
X1046900Y380167D01*
G01X1055350Y380083D02*
X1055767Y379750D01*
X1056350Y379500D01*
X1056850D01*
X1057350Y379667D01*
X1057683Y379917D01*
X1057850Y380250D01*
X1057767Y380750D01*
X1057433Y381000D01*
X1055933Y381500D01*
X1055600Y382083D01*
X1055767Y382500D01*
X1056100Y382750D01*
X1056600Y382833D01*
X1057100Y382750D01*
X1057600Y382500D01*
G01X1060783Y379500D02*
Y384500D01*
G01Y382083D02*
X1061200Y382500D01*
X1061617Y382750D01*
X1062283Y382833D01*
X1062783Y382750D01*
X1063367Y382417D01*
X1063617Y381917D01*
Y379500D01*
G01X1067800D02*
X1067300Y379583D01*
X1066800Y379917D01*
X1066467Y380500D01*
X1066300Y381167D01*
X1066467Y381833D01*
X1066800Y382417D01*
X1067300Y382750D01*
X1067800Y382833D01*
X1068300Y382750D01*
X1068800Y382417D01*
X1069133Y381833D01*
X1069217Y381167D01*
X1069133Y380500D01*
X1068800Y379917D01*
X1068300Y379583D01*
X1067800Y379500D01*
G01X1071983Y382833D02*
Y380500D01*
X1072317Y379917D01*
X1072817Y379583D01*
X1073400Y379500D01*
X1073983Y379583D01*
X1074483Y379917D01*
X1074817Y380500D01*
G01Y379500D02*
Y382833D01*
G01X1079000Y379500D02*
Y384500D01*
G01X1086100D02*
Y379500D01*
G01Y380250D02*
X1085767Y379833D01*
X1085267Y379583D01*
X1084683Y379500D01*
X1084017Y379667D01*
X1083517Y380083D01*
X1083183Y380583D01*
X1083100Y381167D01*
X1083183Y381750D01*
X1083517Y382250D01*
X1084017Y382667D01*
X1084683Y382833D01*
X1085267Y382750D01*
X1085683Y382583D01*
X1086100Y382250D01*
G01X1094300Y379500D02*
Y384500D01*
G01Y382000D02*
X1094717Y382500D01*
X1095217Y382750D01*
X1095717Y382833D01*
X1096467Y382667D01*
X1096967Y382333D01*
X1097300Y381750D01*
Y381083D01*
X1097133Y380417D01*
X1096800Y379917D01*
X1096217Y379583D01*
X1095717Y379500D01*
X1095217Y379583D01*
X1094717Y379833D01*
X1094300Y380250D01*
G01X1100150Y381750D02*
X1102817D01*
X1102567Y382333D01*
X1102150Y382667D01*
X1101567Y382833D01*
X1100983Y382750D01*
X1100483Y382500D01*
X1100150Y381917D01*
X1099983Y381417D01*
Y380917D01*
X1100150Y380417D01*
X1100567Y379917D01*
X1101067Y379583D01*
X1101650Y379500D01*
X1102233Y379667D01*
X1102817Y380167D01*
G01X1111100Y377833D02*
Y382833D01*
G01Y382083D02*
X1111517Y382500D01*
X1111933Y382750D01*
X1112600Y382833D01*
X1113183Y382750D01*
X1113767Y382333D01*
X1114017Y381750D01*
X1114100Y381167D01*
X1114017Y380583D01*
X1113767Y380000D01*
X1113267Y379667D01*
X1112600Y379500D01*
X1112017Y379583D01*
X1111433Y379833D01*
X1111100Y380167D01*
G01X1118200Y379500D02*
Y384500D01*
G01X1122383Y382833D02*
Y380500D01*
X1122717Y379917D01*
X1123217Y379583D01*
X1123800Y379500D01*
X1124383Y379583D01*
X1124883Y379917D01*
X1125217Y380500D01*
G01Y379500D02*
Y382833D01*
G01X1128233Y378250D02*
X1128817Y377917D01*
X1129483Y377833D01*
X1130067Y377917D01*
X1130567Y378333D01*
X1130900Y378917D01*
Y382833D01*
G01Y382167D02*
X1130567Y382500D01*
X1130067Y382750D01*
X1129483Y382833D01*
X1128817Y382667D01*
X1128400Y382333D01*
X1128067Y381750D01*
X1127900Y381167D01*
X1127983Y380667D01*
X1128317Y380083D01*
X1128817Y379667D01*
X1129483Y379500D01*
X1129983Y379583D01*
X1130567Y379917D01*
X1130900Y380250D01*
G01X1133833Y378250D02*
X1134417Y377917D01*
X1135083Y377833D01*
X1135667Y377917D01*
X1136167Y378333D01*
X1136500Y378917D01*
Y382833D01*
G01Y382167D02*
X1136167Y382500D01*
X1135667Y382750D01*
X1135083Y382833D01*
X1134417Y382667D01*
X1134000Y382333D01*
X1133667Y381750D01*
X1133500Y381167D01*
X1133583Y380667D01*
X1133917Y380083D01*
X1134417Y379667D01*
X1135083Y379500D01*
X1135583Y379583D01*
X1136167Y379917D01*
X1136500Y380250D01*
G01X1139350Y381750D02*
X1142017D01*
X1141767Y382333D01*
X1141350Y382667D01*
X1140767Y382833D01*
X1140183Y382750D01*
X1139683Y382500D01*
X1139350Y381917D01*
X1139183Y381417D01*
Y380917D01*
X1139350Y380417D01*
X1139767Y379917D01*
X1140267Y379583D01*
X1140850Y379500D01*
X1141433Y379667D01*
X1142017Y380167D01*
G01X1147700Y384500D02*
Y379500D01*
G01Y380250D02*
X1147367Y379833D01*
X1146867Y379583D01*
X1146283Y379500D01*
X1145617Y379667D01*
X1145117Y380083D01*
X1144783Y380583D01*
X1144700Y381167D01*
X1144783Y381750D01*
X1145117Y382250D01*
X1145617Y382667D01*
X1146283Y382833D01*
X1146867Y382750D01*
X1147283Y382583D01*
X1147700Y382250D01*
G01X1155317Y382833D02*
X1156317Y379500D01*
X1157400Y382833D01*
X1158483Y379500D01*
X1159483Y382833D01*
G01X1163000D02*
Y379500D01*
G01Y384167D02*
X1162833Y384250D01*
Y384417D01*
X1163000Y384500D01*
X1163167Y384417D01*
Y384250D01*
X1163000Y384167D01*
G01X1168600Y384500D02*
Y379500D01*
G01X1167433Y382833D02*
X1169767D01*
G01X1172783Y379500D02*
Y384500D01*
G01Y382083D02*
X1173200Y382500D01*
X1173617Y382750D01*
X1174283Y382833D01*
X1174783Y382750D01*
X1175367Y382417D01*
X1175617Y381917D01*
Y379500D01*
G01X1183733D02*
X1187067Y381167D01*
X1183733Y382833D01*
G01X1189583Y380083D02*
X1190167Y379667D01*
X1190833Y379500D01*
X1191500Y379667D01*
X1192083Y380167D01*
X1192500Y380917D01*
X1192667Y381667D01*
Y382583D01*
X1192500Y383333D01*
X1192083Y384000D01*
X1191583Y384333D01*
X1191000Y384500D01*
X1190333Y384333D01*
X1189833Y384000D01*
X1189500Y383500D01*
X1189333Y382833D01*
X1189500Y382250D01*
X1189917Y381667D01*
X1190417Y381333D01*
X1191000Y381250D01*
X1191667Y381417D01*
X1192167Y381833D01*
X1192667Y382583D01*
G01X1196600Y384500D02*
X1195933Y384333D01*
X1195433Y383917D01*
X1195100Y383417D01*
X1194850Y382750D01*
X1194767Y382000D01*
X1194850Y381250D01*
X1195100Y380583D01*
X1195433Y380083D01*
X1195933Y379667D01*
X1196600Y379500D01*
X1197267Y379667D01*
X1197767Y380083D01*
X1198100Y380583D01*
X1198350Y381250D01*
X1198433Y382000D01*
X1198350Y382750D01*
X1198100Y383417D01*
X1197767Y383917D01*
X1197267Y384333D01*
X1196600Y384500D01*
G01X1200700Y379333D02*
X1203700Y384500D01*
G01X1200700D02*
X1200200Y384333D01*
X1199950Y384083D01*
X1199783Y383583D01*
X1199950Y383083D01*
X1200200Y382833D01*
X1200700Y382667D01*
X1201200Y382833D01*
X1201450Y383083D01*
X1201617Y383583D01*
X1201450Y384083D01*
X1201200Y384333D01*
X1200700Y384500D01*
G01X1203700Y381167D02*
X1203200Y381000D01*
X1202950Y380750D01*
X1202783Y380250D01*
X1202950Y379750D01*
X1203200Y379500D01*
X1203700Y379333D01*
X1204200Y379500D01*
X1204450Y379750D01*
X1204617Y380250D01*
X1204450Y380750D01*
X1204200Y381000D01*
X1203700Y381167D01*
G01X1212233Y379500D02*
Y382833D01*
G01Y382167D02*
X1212650Y382500D01*
X1213067Y382750D01*
X1213650Y382833D01*
X1214067Y382750D01*
X1214567Y382500D01*
G01X1217750Y381750D02*
X1220417D01*
X1220167Y382333D01*
X1219750Y382667D01*
X1219167Y382833D01*
X1218583Y382750D01*
X1218083Y382500D01*
X1217750Y381917D01*
X1217583Y381417D01*
Y380917D01*
X1217750Y380417D01*
X1218167Y379917D01*
X1218667Y379583D01*
X1219250Y379500D01*
X1219833Y379667D01*
X1220417Y380167D01*
G01X1223350Y380083D02*
X1223767Y379750D01*
X1224350Y379500D01*
X1224850D01*
X1225350Y379667D01*
X1225683Y379917D01*
X1225850Y380250D01*
X1225767Y380750D01*
X1225433Y381000D01*
X1223933Y381500D01*
X1223600Y382083D01*
X1223767Y382500D01*
X1224100Y382750D01*
X1224600Y382833D01*
X1225100Y382750D01*
X1225600Y382500D01*
G01X1230200Y382833D02*
Y379500D01*
G01Y384167D02*
X1230033Y384250D01*
Y384417D01*
X1230200Y384500D01*
X1230367Y384417D01*
Y384250D01*
X1230200Y384167D01*
G01X1234383Y379500D02*
Y382833D01*
G01Y382000D02*
X1234717Y382417D01*
X1235217Y382750D01*
X1235883Y382833D01*
X1236467Y382750D01*
X1236967Y382417D01*
X1237217Y381833D01*
Y379500D01*
G01X1246417Y378000D02*
X1247583Y379167D01*
Y380333D01*
X1246417D01*
Y379167D01*
X1247583D01*
G01Y381167D02*
Y382333D01*
X1246417D01*
Y381167D01*
X1247583D01*
G01X1250767Y379500D02*
Y384500D01*
X1252433D01*
X1253100Y384250D01*
X1253600Y383917D01*
X1254017Y383417D01*
X1254350Y382833D01*
X1254433Y382000D01*
X1254350Y381167D01*
X1254017Y380583D01*
X1253600Y380083D01*
X1253100Y379750D01*
X1252433Y379500D01*
X1250767D01*
G01X1258200D02*
X1257700Y379583D01*
X1257200Y379917D01*
X1256867Y380500D01*
X1256700Y381167D01*
X1256867Y381833D01*
X1257200Y382417D01*
X1257700Y382750D01*
X1258200Y382833D01*
X1258700Y382750D01*
X1259200Y382417D01*
X1259533Y381833D01*
X1259617Y381167D01*
X1259533Y380500D01*
X1259200Y379917D01*
X1258700Y379583D01*
X1258200Y379500D01*
G01X1267983D02*
Y382833D01*
G01Y382000D02*
X1268317Y382417D01*
X1268817Y382750D01*
X1269483Y382833D01*
X1270067Y382750D01*
X1270567Y382417D01*
X1270817Y381833D01*
Y379500D01*
G01X1275000D02*
X1274500Y379583D01*
X1274000Y379917D01*
X1273667Y380500D01*
X1273500Y381167D01*
X1273667Y381833D01*
X1274000Y382417D01*
X1274500Y382750D01*
X1275000Y382833D01*
X1275500Y382750D01*
X1276000Y382417D01*
X1276333Y381833D01*
X1276417Y381167D01*
X1276333Y380500D01*
X1276000Y379917D01*
X1275500Y379583D01*
X1275000Y379500D01*
G01X1280600Y384500D02*
Y379500D01*
G01X1279433Y382833D02*
X1281767D01*
G01X1293300Y379500D02*
Y382833D01*
G01Y382250D02*
X1292967Y382583D01*
X1292467Y382750D01*
X1291883Y382833D01*
X1291300Y382667D01*
X1290800Y382333D01*
X1290467Y381833D01*
X1290300Y381167D01*
X1290467Y380500D01*
X1290800Y380000D01*
X1291300Y379667D01*
X1291883Y379500D01*
X1292467Y379583D01*
X1292967Y379833D01*
X1293300Y380167D01*
G01X1297400Y379500D02*
Y384500D01*
G01X1303000Y379500D02*
Y384500D01*
G01X1308600Y379500D02*
X1308100Y379583D01*
X1307600Y379917D01*
X1307267Y380500D01*
X1307100Y381167D01*
X1307267Y381833D01*
X1307600Y382417D01*
X1308100Y382750D01*
X1308600Y382833D01*
X1309100Y382750D01*
X1309600Y382417D01*
X1309933Y381833D01*
X1310017Y381167D01*
X1309933Y380500D01*
X1309600Y379917D01*
X1309100Y379583D01*
X1308600Y379500D01*
G01X1312117Y382833D02*
X1313117Y379500D01*
X1314200Y382833D01*
X1315283Y379500D01*
X1316283Y382833D01*
G01X1033500Y413500D02*
Y418500D01*
G01Y416000D02*
X1033917Y416500D01*
X1034417Y416750D01*
X1034917Y416833D01*
X1035667Y416667D01*
X1036167Y416333D01*
X1036500Y415750D01*
Y415083D01*
X1036333Y414417D01*
X1036000Y413917D01*
X1035417Y413583D01*
X1034917Y413500D01*
X1034417Y413583D01*
X1033917Y413833D01*
X1033500Y414250D01*
G01X1039183Y416833D02*
Y414500D01*
X1039517Y413917D01*
X1040017Y413583D01*
X1040600Y413500D01*
X1041183Y413583D01*
X1041683Y413917D01*
X1042017Y414500D01*
G01Y413500D02*
Y416833D01*
G01X1044700Y413500D02*
Y418500D01*
G01Y416000D02*
X1045117Y416500D01*
X1045617Y416750D01*
X1046117Y416833D01*
X1046867Y416667D01*
X1047367Y416333D01*
X1047700Y415750D01*
Y415083D01*
X1047533Y414417D01*
X1047200Y413917D01*
X1046617Y413583D01*
X1046117Y413500D01*
X1045617Y413583D01*
X1045117Y413833D01*
X1044700Y414250D01*
G01X1050300Y413500D02*
Y418500D01*
G01Y416000D02*
X1050717Y416500D01*
X1051217Y416750D01*
X1051717Y416833D01*
X1052467Y416667D01*
X1052967Y416333D01*
X1053300Y415750D01*
Y415083D01*
X1053133Y414417D01*
X1052800Y413917D01*
X1052217Y413583D01*
X1051717Y413500D01*
X1051217Y413583D01*
X1050717Y413833D01*
X1050300Y414250D01*
G01X1057400Y413500D02*
Y418500D01*
G01X1061750Y415750D02*
X1064417D01*
X1064167Y416333D01*
X1063750Y416667D01*
X1063167Y416833D01*
X1062583Y416750D01*
X1062083Y416500D01*
X1061750Y415917D01*
X1061583Y415417D01*
Y414917D01*
X1061750Y414417D01*
X1062167Y413917D01*
X1062667Y413583D01*
X1063250Y413500D01*
X1063833Y413667D01*
X1064417Y414167D01*
G01X1074200Y416833D02*
Y413500D01*
G01Y418167D02*
X1074033Y418250D01*
Y418417D01*
X1074200Y418500D01*
X1074367Y418417D01*
Y418250D01*
X1074200Y418167D01*
G01X1078383Y413500D02*
Y416833D01*
G01Y416000D02*
X1078717Y416417D01*
X1079217Y416750D01*
X1079883Y416833D01*
X1080467Y416750D01*
X1080967Y416417D01*
X1081217Y415833D01*
Y413500D01*
G01X1084150Y414083D02*
X1084567Y413750D01*
X1085150Y413500D01*
X1085650D01*
X1086150Y413667D01*
X1086483Y413917D01*
X1086650Y414250D01*
X1086567Y414750D01*
X1086233Y415000D01*
X1084733Y415500D01*
X1084400Y416083D01*
X1084567Y416500D01*
X1084900Y416750D01*
X1085400Y416833D01*
X1085900Y416750D01*
X1086400Y416500D01*
G01X1091000Y416833D02*
Y413500D01*
G01Y418167D02*
X1090833Y418250D01*
Y418417D01*
X1091000Y418500D01*
X1091167Y418417D01*
Y418250D01*
X1091000Y418167D01*
G01X1098100Y418500D02*
Y413500D01*
G01Y414250D02*
X1097767Y413833D01*
X1097267Y413583D01*
X1096683Y413500D01*
X1096017Y413667D01*
X1095517Y414083D01*
X1095183Y414583D01*
X1095100Y415167D01*
X1095183Y415750D01*
X1095517Y416250D01*
X1096017Y416667D01*
X1096683Y416833D01*
X1097267Y416750D01*
X1097683Y416583D01*
X1098100Y416250D01*
G01X1100950Y415750D02*
X1103617D01*
X1103367Y416333D01*
X1102950Y416667D01*
X1102367Y416833D01*
X1101783Y416750D01*
X1101283Y416500D01*
X1100950Y415917D01*
X1100783Y415417D01*
Y414917D01*
X1100950Y414417D01*
X1101367Y413917D01*
X1101867Y413583D01*
X1102450Y413500D01*
X1103033Y413667D01*
X1103617Y414167D01*
G01X1113400Y418500D02*
Y413500D01*
G01X1112233Y416833D02*
X1114567D01*
G01X1117583Y413500D02*
Y418500D01*
G01Y416083D02*
X1118000Y416500D01*
X1118417Y416750D01*
X1119083Y416833D01*
X1119583Y416750D01*
X1120167Y416417D01*
X1120417Y415917D01*
Y413500D01*
G01X1123350Y415750D02*
X1126017D01*
X1125767Y416333D01*
X1125350Y416667D01*
X1124767Y416833D01*
X1124183Y416750D01*
X1123683Y416500D01*
X1123350Y415917D01*
X1123183Y415417D01*
Y414917D01*
X1123350Y414417D01*
X1123767Y413917D01*
X1124267Y413583D01*
X1124850Y413500D01*
X1125433Y413667D01*
X1126017Y414167D01*
G01X1134633Y413500D02*
Y416833D01*
G01Y416167D02*
X1135050Y416500D01*
X1135467Y416750D01*
X1136050Y416833D01*
X1136467Y416750D01*
X1136967Y416500D01*
G01X1140150Y415750D02*
X1142817D01*
X1142567Y416333D01*
X1142150Y416667D01*
X1141567Y416833D01*
X1140983Y416750D01*
X1140483Y416500D01*
X1140150Y415917D01*
X1139983Y415417D01*
Y414917D01*
X1140150Y414417D01*
X1140567Y413917D01*
X1141067Y413583D01*
X1141650Y413500D01*
X1142233Y413667D01*
X1142817Y414167D01*
G01X1145750Y414083D02*
X1146167Y413750D01*
X1146750Y413500D01*
X1147250D01*
X1147750Y413667D01*
X1148083Y413917D01*
X1148250Y414250D01*
X1148167Y414750D01*
X1147833Y415000D01*
X1146333Y415500D01*
X1146000Y416083D01*
X1146167Y416500D01*
X1146500Y416750D01*
X1147000Y416833D01*
X1147500Y416750D01*
X1148000Y416500D01*
G01X1152600Y416833D02*
Y413500D01*
G01Y418167D02*
X1152433Y418250D01*
Y418417D01*
X1152600Y418500D01*
X1152767Y418417D01*
Y418250D01*
X1152600Y418167D01*
G01X1156783Y413500D02*
Y416833D01*
G01Y416000D02*
X1157117Y416417D01*
X1157617Y416750D01*
X1158283Y416833D01*
X1158867Y416750D01*
X1159367Y416417D01*
X1159617Y415833D01*
Y413500D01*
G01X1163800Y413333D02*
X1163633Y413417D01*
Y413583D01*
X1163800Y413667D01*
X1163967Y413583D01*
Y413417D01*
X1163800Y413333D01*
G01X1023000Y390000D02*
Y395000D01*
X1022000Y394000D01*
G01Y390000D02*
X1024000D01*
G01X1028600Y389833D02*
X1028433Y389917D01*
Y390083D01*
X1028600Y390167D01*
X1028767Y390083D01*
Y389917D01*
X1028600Y389833D01*
G01X1032367Y390000D02*
Y395000D01*
X1034033D01*
X1034700Y394750D01*
X1035200Y394417D01*
X1035617Y393917D01*
X1035950Y393333D01*
X1036033Y392500D01*
X1035950Y391667D01*
X1035617Y391083D01*
X1035200Y390583D01*
X1034700Y390250D01*
X1034033Y390000D01*
X1032367D01*
G01X1039800Y393333D02*
Y390000D01*
G01Y394667D02*
X1039633Y394750D01*
Y394917D01*
X1039800Y395000D01*
X1039967Y394917D01*
Y394750D01*
X1039800Y394667D01*
G01X1042900Y390000D02*
Y393333D01*
G01Y392417D02*
X1043150Y392833D01*
X1043567Y393167D01*
X1044150Y393333D01*
X1044733Y393167D01*
X1045150Y392833D01*
X1045400Y392417D01*
Y390000D01*
G01Y392417D02*
X1045650Y392833D01*
X1046067Y393167D01*
X1046650Y393333D01*
X1047233Y393167D01*
X1047650Y392833D01*
X1047900Y392333D01*
Y390000D01*
G01X1049500Y388333D02*
Y393333D01*
G01Y392583D02*
X1049917Y393000D01*
X1050333Y393250D01*
X1051000Y393333D01*
X1051583Y393250D01*
X1052167Y392833D01*
X1052417Y392250D01*
X1052500Y391667D01*
X1052417Y391083D01*
X1052167Y390500D01*
X1051667Y390167D01*
X1051000Y390000D01*
X1050417Y390083D01*
X1049833Y390333D01*
X1049500Y390667D01*
G01X1056600Y390000D02*
Y395000D01*
G01X1060950Y392250D02*
X1063617D01*
X1063367Y392833D01*
X1062950Y393167D01*
X1062367Y393333D01*
X1061783Y393250D01*
X1061283Y393000D01*
X1060950Y392417D01*
X1060783Y391917D01*
Y391417D01*
X1060950Y390917D01*
X1061367Y390417D01*
X1061867Y390083D01*
X1062450Y390000D01*
X1063033Y390167D01*
X1063617Y390667D01*
G01X1075067Y390000D02*
X1071733Y391667D01*
X1075067Y393333D01*
G01X1084600Y390000D02*
Y395000D01*
X1083600Y394000D01*
G01Y390000D02*
X1085600D01*
G01X1093300D02*
Y393333D01*
G01Y392417D02*
X1093550Y392833D01*
X1093967Y393167D01*
X1094550Y393333D01*
X1095133Y393167D01*
X1095550Y392833D01*
X1095800Y392417D01*
Y390000D01*
G01Y392417D02*
X1096050Y392833D01*
X1096467Y393167D01*
X1097050Y393333D01*
X1097633Y393167D01*
X1098050Y392833D01*
X1098300Y392333D01*
Y390000D01*
G01X1101400Y393333D02*
Y390000D01*
G01Y394667D02*
X1101233Y394750D01*
Y394917D01*
X1101400Y395000D01*
X1101567Y394917D01*
Y394750D01*
X1101400Y394667D01*
G01X1107000Y390000D02*
Y395000D01*
G01X1117617Y388500D02*
X1118783Y389667D01*
Y390833D01*
X1117617D01*
Y389667D01*
X1118783D01*
G01Y391667D02*
Y392833D01*
X1117617D01*
Y391667D01*
X1118783D01*
G01X1016000Y604500D02*
Y366000D01*
G01X1033500Y370500D02*
Y375500D01*
G01Y373000D02*
X1033917Y373500D01*
X1034417Y373750D01*
X1034917Y373833D01*
X1035667Y373667D01*
X1036167Y373333D01*
X1036500Y372750D01*
Y372083D01*
X1036333Y371417D01*
X1036000Y370917D01*
X1035417Y370583D01*
X1034917Y370500D01*
X1034417Y370583D01*
X1033917Y370833D01*
X1033500Y371250D01*
G01X1039183Y373833D02*
Y371500D01*
X1039517Y370917D01*
X1040017Y370583D01*
X1040600Y370500D01*
X1041183Y370583D01*
X1041683Y370917D01*
X1042017Y371500D01*
G01Y370500D02*
Y373833D01*
G01X1044700Y370500D02*
Y375500D01*
G01Y373000D02*
X1045117Y373500D01*
X1045617Y373750D01*
X1046117Y373833D01*
X1046867Y373667D01*
X1047367Y373333D01*
X1047700Y372750D01*
Y372083D01*
X1047533Y371417D01*
X1047200Y370917D01*
X1046617Y370583D01*
X1046117Y370500D01*
X1045617Y370583D01*
X1045117Y370833D01*
X1044700Y371250D01*
G01X1050300Y370500D02*
Y375500D01*
G01Y373000D02*
X1050717Y373500D01*
X1051217Y373750D01*
X1051717Y373833D01*
X1052467Y373667D01*
X1052967Y373333D01*
X1053300Y372750D01*
Y372083D01*
X1053133Y371417D01*
X1052800Y370917D01*
X1052217Y370583D01*
X1051717Y370500D01*
X1051217Y370583D01*
X1050717Y370833D01*
X1050300Y371250D01*
G01X1057400Y370500D02*
Y375500D01*
G01X1061750Y372750D02*
X1064417D01*
X1064167Y373333D01*
X1063750Y373667D01*
X1063167Y373833D01*
X1062583Y373750D01*
X1062083Y373500D01*
X1061750Y372917D01*
X1061583Y372417D01*
Y371917D01*
X1061750Y371417D01*
X1062167Y370917D01*
X1062667Y370583D01*
X1063250Y370500D01*
X1063833Y370667D01*
X1064417Y371167D01*
G01X1074200Y373833D02*
Y370500D01*
G01Y375167D02*
X1074033Y375250D01*
Y375417D01*
X1074200Y375500D01*
X1074367Y375417D01*
Y375250D01*
X1074200Y375167D01*
G01X1078383Y370500D02*
Y373833D01*
G01Y373000D02*
X1078717Y373417D01*
X1079217Y373750D01*
X1079883Y373833D01*
X1080467Y373750D01*
X1080967Y373417D01*
X1081217Y372833D01*
Y370500D01*
G01X1084150Y371083D02*
X1084567Y370750D01*
X1085150Y370500D01*
X1085650D01*
X1086150Y370667D01*
X1086483Y370917D01*
X1086650Y371250D01*
X1086567Y371750D01*
X1086233Y372000D01*
X1084733Y372500D01*
X1084400Y373083D01*
X1084567Y373500D01*
X1084900Y373750D01*
X1085400Y373833D01*
X1085900Y373750D01*
X1086400Y373500D01*
G01X1091000Y373833D02*
Y370500D01*
G01Y375167D02*
X1090833Y375250D01*
Y375417D01*
X1091000Y375500D01*
X1091167Y375417D01*
Y375250D01*
X1091000Y375167D01*
G01X1098100Y375500D02*
Y370500D01*
G01Y371250D02*
X1097767Y370833D01*
X1097267Y370583D01*
X1096683Y370500D01*
X1096017Y370667D01*
X1095517Y371083D01*
X1095183Y371583D01*
X1095100Y372167D01*
X1095183Y372750D01*
X1095517Y373250D01*
X1096017Y373667D01*
X1096683Y373833D01*
X1097267Y373750D01*
X1097683Y373583D01*
X1098100Y373250D01*
G01X1100950Y372750D02*
X1103617D01*
X1103367Y373333D01*
X1102950Y373667D01*
X1102367Y373833D01*
X1101783Y373750D01*
X1101283Y373500D01*
X1100950Y372917D01*
X1100783Y372417D01*
Y371917D01*
X1100950Y371417D01*
X1101367Y370917D01*
X1101867Y370583D01*
X1102450Y370500D01*
X1103033Y370667D01*
X1103617Y371167D01*
G01X1113400Y375500D02*
Y370500D01*
G01X1112233Y373833D02*
X1114567D01*
G01X1117583Y370500D02*
Y375500D01*
G01Y373083D02*
X1118000Y373500D01*
X1118417Y373750D01*
X1119083Y373833D01*
X1119583Y373750D01*
X1120167Y373417D01*
X1120417Y372917D01*
Y370500D01*
G01X1123350Y372750D02*
X1126017D01*
X1125767Y373333D01*
X1125350Y373667D01*
X1124767Y373833D01*
X1124183Y373750D01*
X1123683Y373500D01*
X1123350Y372917D01*
X1123183Y372417D01*
Y371917D01*
X1123350Y371417D01*
X1123767Y370917D01*
X1124267Y370583D01*
X1124850Y370500D01*
X1125433Y370667D01*
X1126017Y371167D01*
G01X1134633Y370500D02*
Y373833D01*
G01Y373167D02*
X1135050Y373500D01*
X1135467Y373750D01*
X1136050Y373833D01*
X1136467Y373750D01*
X1136967Y373500D01*
G01X1140150Y372750D02*
X1142817D01*
X1142567Y373333D01*
X1142150Y373667D01*
X1141567Y373833D01*
X1140983Y373750D01*
X1140483Y373500D01*
X1140150Y372917D01*
X1139983Y372417D01*
Y371917D01*
X1140150Y371417D01*
X1140567Y370917D01*
X1141067Y370583D01*
X1141650Y370500D01*
X1142233Y370667D01*
X1142817Y371167D01*
G01X1145750Y371083D02*
X1146167Y370750D01*
X1146750Y370500D01*
X1147250D01*
X1147750Y370667D01*
X1148083Y370917D01*
X1148250Y371250D01*
X1148167Y371750D01*
X1147833Y372000D01*
X1146333Y372500D01*
X1146000Y373083D01*
X1146167Y373500D01*
X1146500Y373750D01*
X1147000Y373833D01*
X1147500Y373750D01*
X1148000Y373500D01*
G01X1152600Y373833D02*
Y370500D01*
G01Y375167D02*
X1152433Y375250D01*
Y375417D01*
X1152600Y375500D01*
X1152767Y375417D01*
Y375250D01*
X1152600Y375167D01*
G01X1156783Y370500D02*
Y373833D01*
G01Y373000D02*
X1157117Y373417D01*
X1157617Y373750D01*
X1158283Y373833D01*
X1158867Y373750D01*
X1159367Y373417D01*
X1159617Y372833D01*
Y370500D01*
G01X1163800Y370333D02*
X1163633Y370417D01*
Y370583D01*
X1163800Y370667D01*
X1163967Y370583D01*
Y370417D01*
X1163800Y370333D01*
G01X1021417Y383667D02*
X1021917Y384167D01*
X1022500Y384417D01*
X1023167Y384500D01*
X1024000Y384333D01*
X1024583Y383917D01*
X1024750Y383417D01*
X1024667Y382917D01*
X1024333Y382500D01*
X1022667Y381667D01*
X1021917Y381083D01*
X1021417Y380250D01*
X1021250Y379500D01*
X1024750D01*
G01X1028600Y379333D02*
X1028433Y379417D01*
Y379583D01*
X1028600Y379667D01*
X1028767Y379583D01*
Y379417D01*
X1028600Y379333D01*
G01X1032117Y384500D02*
X1034200Y379500D01*
X1036283Y384500D01*
G01X1039800Y382833D02*
Y379500D01*
G01Y384167D02*
X1039633Y384250D01*
Y384417D01*
X1039800Y384500D01*
X1039967Y384417D01*
Y384250D01*
X1039800Y384167D01*
G01X1046900Y379500D02*
Y382833D01*
G01Y382250D02*
X1046567Y382583D01*
X1046067Y382750D01*
X1045483Y382833D01*
X1044900Y382667D01*
X1044400Y382333D01*
X1044067Y381833D01*
X1043900Y381167D01*
X1044067Y380500D01*
X1044400Y380000D01*
X1044900Y379667D01*
X1045483Y379500D01*
X1046067Y379583D01*
X1046567Y379833D01*
X1046900Y380167D01*
G01X1055350Y380083D02*
X1055767Y379750D01*
X1056350Y379500D01*
X1056850D01*
X1057350Y379667D01*
X1057683Y379917D01*
X1057850Y380250D01*
X1057767Y380750D01*
X1057433Y381000D01*
X1055933Y381500D01*
X1055600Y382083D01*
X1055767Y382500D01*
X1056100Y382750D01*
X1056600Y382833D01*
X1057100Y382750D01*
X1057600Y382500D01*
G01X1060783Y379500D02*
Y384500D01*
G01Y382083D02*
X1061200Y382500D01*
X1061617Y382750D01*
X1062283Y382833D01*
X1062783Y382750D01*
X1063367Y382417D01*
X1063617Y381917D01*
Y379500D01*
G01X1067800D02*
X1067300Y379583D01*
X1066800Y379917D01*
X1066467Y380500D01*
X1066300Y381167D01*
X1066467Y381833D01*
X1066800Y382417D01*
X1067300Y382750D01*
X1067800Y382833D01*
X1068300Y382750D01*
X1068800Y382417D01*
X1069133Y381833D01*
X1069217Y381167D01*
X1069133Y380500D01*
X1068800Y379917D01*
X1068300Y379583D01*
X1067800Y379500D01*
G01X1071983Y382833D02*
Y380500D01*
X1072317Y379917D01*
X1072817Y379583D01*
X1073400Y379500D01*
X1073983Y379583D01*
X1074483Y379917D01*
X1074817Y380500D01*
G01Y379500D02*
Y382833D01*
G01X1079000Y379500D02*
Y384500D01*
G01X1086100D02*
Y379500D01*
G01Y380250D02*
X1085767Y379833D01*
X1085267Y379583D01*
X1084683Y379500D01*
X1084017Y379667D01*
X1083517Y380083D01*
X1083183Y380583D01*
X1083100Y381167D01*
X1083183Y381750D01*
X1083517Y382250D01*
X1084017Y382667D01*
X1084683Y382833D01*
X1085267Y382750D01*
X1085683Y382583D01*
X1086100Y382250D01*
G01X1094300Y379500D02*
Y384500D01*
G01Y382000D02*
X1094717Y382500D01*
X1095217Y382750D01*
X1095717Y382833D01*
X1096467Y382667D01*
X1096967Y382333D01*
X1097300Y381750D01*
Y381083D01*
X1097133Y380417D01*
X1096800Y379917D01*
X1096217Y379583D01*
X1095717Y379500D01*
X1095217Y379583D01*
X1094717Y379833D01*
X1094300Y380250D01*
G01X1100150Y381750D02*
X1102817D01*
X1102567Y382333D01*
X1102150Y382667D01*
X1101567Y382833D01*
X1100983Y382750D01*
X1100483Y382500D01*
X1100150Y381917D01*
X1099983Y381417D01*
Y380917D01*
X1100150Y380417D01*
X1100567Y379917D01*
X1101067Y379583D01*
X1101650Y379500D01*
X1102233Y379667D01*
X1102817Y380167D01*
G01X1111100Y377833D02*
Y382833D01*
G01Y382083D02*
X1111517Y382500D01*
X1111933Y382750D01*
X1112600Y382833D01*
X1113183Y382750D01*
X1113767Y382333D01*
X1114017Y381750D01*
X1114100Y381167D01*
X1114017Y380583D01*
X1113767Y380000D01*
X1113267Y379667D01*
X1112600Y379500D01*
X1112017Y379583D01*
X1111433Y379833D01*
X1111100Y380167D01*
G01X1118200Y379500D02*
Y384500D01*
G01X1122383Y382833D02*
Y380500D01*
X1122717Y379917D01*
X1123217Y379583D01*
X1123800Y379500D01*
X1124383Y379583D01*
X1124883Y379917D01*
X1125217Y380500D01*
G01Y379500D02*
Y382833D01*
G01X1128233Y378250D02*
X1128817Y377917D01*
X1129483Y377833D01*
X1130067Y377917D01*
X1130567Y378333D01*
X1130900Y378917D01*
Y382833D01*
G01Y382167D02*
X1130567Y382500D01*
X1130067Y382750D01*
X1129483Y382833D01*
X1128817Y382667D01*
X1128400Y382333D01*
X1128067Y381750D01*
X1127900Y381167D01*
X1127983Y380667D01*
X1128317Y380083D01*
X1128817Y379667D01*
X1129483Y379500D01*
X1129983Y379583D01*
X1130567Y379917D01*
X1130900Y380250D01*
G01X1133833Y378250D02*
X1134417Y377917D01*
X1135083Y377833D01*
X1135667Y377917D01*
X1136167Y378333D01*
X1136500Y378917D01*
Y382833D01*
G01Y382167D02*
X1136167Y382500D01*
X1135667Y382750D01*
X1135083Y382833D01*
X1134417Y382667D01*
X1134000Y382333D01*
X1133667Y381750D01*
X1133500Y381167D01*
X1133583Y380667D01*
X1133917Y380083D01*
X1134417Y379667D01*
X1135083Y379500D01*
X1135583Y379583D01*
X1136167Y379917D01*
X1136500Y380250D01*
G01X1139350Y381750D02*
X1142017D01*
X1141767Y382333D01*
X1141350Y382667D01*
X1140767Y382833D01*
X1140183Y382750D01*
X1139683Y382500D01*
X1139350Y381917D01*
X1139183Y381417D01*
Y380917D01*
X1139350Y380417D01*
X1139767Y379917D01*
X1140267Y379583D01*
X1140850Y379500D01*
X1141433Y379667D01*
X1142017Y380167D01*
G01X1147700Y384500D02*
Y379500D01*
G01Y380250D02*
X1147367Y379833D01*
X1146867Y379583D01*
X1146283Y379500D01*
X1145617Y379667D01*
X1145117Y380083D01*
X1144783Y380583D01*
X1144700Y381167D01*
X1144783Y381750D01*
X1145117Y382250D01*
X1145617Y382667D01*
X1146283Y382833D01*
X1146867Y382750D01*
X1147283Y382583D01*
X1147700Y382250D01*
G01X1155317Y382833D02*
X1156317Y379500D01*
X1157400Y382833D01*
X1158483Y379500D01*
X1159483Y382833D01*
G01X1163000D02*
Y379500D01*
G01Y384167D02*
X1162833Y384250D01*
Y384417D01*
X1163000Y384500D01*
X1163167Y384417D01*
Y384250D01*
X1163000Y384167D01*
G01X1168600Y384500D02*
Y379500D01*
G01X1167433Y382833D02*
X1169767D01*
G01X1172783Y379500D02*
Y384500D01*
G01Y382083D02*
X1173200Y382500D01*
X1173617Y382750D01*
X1174283Y382833D01*
X1174783Y382750D01*
X1175367Y382417D01*
X1175617Y381917D01*
Y379500D01*
G01X1183733D02*
X1187067Y381167D01*
X1183733Y382833D01*
G01X1189583Y380083D02*
X1190167Y379667D01*
X1190833Y379500D01*
X1191500Y379667D01*
X1192083Y380167D01*
X1192500Y380917D01*
X1192667Y381667D01*
Y382583D01*
X1192500Y383333D01*
X1192083Y384000D01*
X1191583Y384333D01*
X1191000Y384500D01*
X1190333Y384333D01*
X1189833Y384000D01*
X1189500Y383500D01*
X1189333Y382833D01*
X1189500Y382250D01*
X1189917Y381667D01*
X1190417Y381333D01*
X1191000Y381250D01*
X1191667Y381417D01*
X1192167Y381833D01*
X1192667Y382583D01*
G01X1196600Y384500D02*
X1195933Y384333D01*
X1195433Y383917D01*
X1195100Y383417D01*
X1194850Y382750D01*
X1194767Y382000D01*
X1194850Y381250D01*
X1195100Y380583D01*
X1195433Y380083D01*
X1195933Y379667D01*
X1196600Y379500D01*
X1197267Y379667D01*
X1197767Y380083D01*
X1198100Y380583D01*
X1198350Y381250D01*
X1198433Y382000D01*
X1198350Y382750D01*
X1198100Y383417D01*
X1197767Y383917D01*
X1197267Y384333D01*
X1196600Y384500D01*
G01X1200700Y379333D02*
X1203700Y384500D01*
G01X1200700D02*
X1200200Y384333D01*
X1199950Y384083D01*
X1199783Y383583D01*
X1199950Y383083D01*
X1200200Y382833D01*
X1200700Y382667D01*
X1201200Y382833D01*
X1201450Y383083D01*
X1201617Y383583D01*
X1201450Y384083D01*
X1201200Y384333D01*
X1200700Y384500D01*
G01X1203700Y381167D02*
X1203200Y381000D01*
X1202950Y380750D01*
X1202783Y380250D01*
X1202950Y379750D01*
X1203200Y379500D01*
X1203700Y379333D01*
X1204200Y379500D01*
X1204450Y379750D01*
X1204617Y380250D01*
X1204450Y380750D01*
X1204200Y381000D01*
X1203700Y381167D01*
G01X1212233Y379500D02*
Y382833D01*
G01Y382167D02*
X1212650Y382500D01*
X1213067Y382750D01*
X1213650Y382833D01*
X1214067Y382750D01*
X1214567Y382500D01*
G01X1217750Y381750D02*
X1220417D01*
X1220167Y382333D01*
X1219750Y382667D01*
X1219167Y382833D01*
X1218583Y382750D01*
X1218083Y382500D01*
X1217750Y381917D01*
X1217583Y381417D01*
Y380917D01*
X1217750Y380417D01*
X1218167Y379917D01*
X1218667Y379583D01*
X1219250Y379500D01*
X1219833Y379667D01*
X1220417Y380167D01*
G01X1223350Y380083D02*
X1223767Y379750D01*
X1224350Y379500D01*
X1224850D01*
X1225350Y379667D01*
X1225683Y379917D01*
X1225850Y380250D01*
X1225767Y380750D01*
X1225433Y381000D01*
X1223933Y381500D01*
X1223600Y382083D01*
X1223767Y382500D01*
X1224100Y382750D01*
X1224600Y382833D01*
X1225100Y382750D01*
X1225600Y382500D01*
G01X1230200Y382833D02*
Y379500D01*
G01Y384167D02*
X1230033Y384250D01*
Y384417D01*
X1230200Y384500D01*
X1230367Y384417D01*
Y384250D01*
X1230200Y384167D01*
G01X1234383Y379500D02*
Y382833D01*
G01Y382000D02*
X1234717Y382417D01*
X1235217Y382750D01*
X1235883Y382833D01*
X1236467Y382750D01*
X1236967Y382417D01*
X1237217Y381833D01*
Y379500D01*
G01X1246417Y378000D02*
X1247583Y379167D01*
Y380333D01*
X1246417D01*
Y379167D01*
X1247583D01*
G01Y381167D02*
Y382333D01*
X1246417D01*
Y381167D01*
X1247583D01*
G01X1250767Y379500D02*
Y384500D01*
X1252433D01*
X1253100Y384250D01*
X1253600Y383917D01*
X1254017Y383417D01*
X1254350Y382833D01*
X1254433Y382000D01*
X1254350Y381167D01*
X1254017Y380583D01*
X1253600Y380083D01*
X1253100Y379750D01*
X1252433Y379500D01*
X1250767D01*
G01X1258200D02*
X1257700Y379583D01*
X1257200Y379917D01*
X1256867Y380500D01*
X1256700Y381167D01*
X1256867Y381833D01*
X1257200Y382417D01*
X1257700Y382750D01*
X1258200Y382833D01*
X1258700Y382750D01*
X1259200Y382417D01*
X1259533Y381833D01*
X1259617Y381167D01*
X1259533Y380500D01*
X1259200Y379917D01*
X1258700Y379583D01*
X1258200Y379500D01*
G01X1267983D02*
Y382833D01*
G01Y382000D02*
X1268317Y382417D01*
X1268817Y382750D01*
X1269483Y382833D01*
X1270067Y382750D01*
X1270567Y382417D01*
X1270817Y381833D01*
Y379500D01*
G01X1275000D02*
X1274500Y379583D01*
X1274000Y379917D01*
X1273667Y380500D01*
X1273500Y381167D01*
X1273667Y381833D01*
X1274000Y382417D01*
X1274500Y382750D01*
X1275000Y382833D01*
X1275500Y382750D01*
X1276000Y382417D01*
X1276333Y381833D01*
X1276417Y381167D01*
X1276333Y380500D01*
X1276000Y379917D01*
X1275500Y379583D01*
X1275000Y379500D01*
G01X1280600Y384500D02*
Y379500D01*
G01X1279433Y382833D02*
X1281767D01*
G01X1293300Y379500D02*
Y382833D01*
G01Y382250D02*
X1292967Y382583D01*
X1292467Y382750D01*
X1291883Y382833D01*
X1291300Y382667D01*
X1290800Y382333D01*
X1290467Y381833D01*
X1290300Y381167D01*
X1290467Y380500D01*
X1290800Y380000D01*
X1291300Y379667D01*
X1291883Y379500D01*
X1292467Y379583D01*
X1292967Y379833D01*
X1293300Y380167D01*
G01X1297400Y379500D02*
Y384500D01*
G01X1303000Y379500D02*
Y384500D01*
G01X1308600Y379500D02*
X1308100Y379583D01*
X1307600Y379917D01*
X1307267Y380500D01*
X1307100Y381167D01*
X1307267Y381833D01*
X1307600Y382417D01*
X1308100Y382750D01*
X1308600Y382833D01*
X1309100Y382750D01*
X1309600Y382417D01*
X1309933Y381833D01*
X1310017Y381167D01*
X1309933Y380500D01*
X1309600Y379917D01*
X1309100Y379583D01*
X1308600Y379500D01*
G01X1312117Y382833D02*
X1313117Y379500D01*
X1314200Y382833D01*
X1315283Y379500D01*
X1316283Y382833D01*
G01X1033500Y413500D02*
Y418500D01*
G01Y416000D02*
X1033917Y416500D01*
X1034417Y416750D01*
X1034917Y416833D01*
X1035667Y416667D01*
X1036167Y416333D01*
X1036500Y415750D01*
Y415083D01*
X1036333Y414417D01*
X1036000Y413917D01*
X1035417Y413583D01*
X1034917Y413500D01*
X1034417Y413583D01*
X1033917Y413833D01*
X1033500Y414250D01*
G01X1039183Y416833D02*
Y414500D01*
X1039517Y413917D01*
X1040017Y413583D01*
X1040600Y413500D01*
X1041183Y413583D01*
X1041683Y413917D01*
X1042017Y414500D01*
G01Y413500D02*
Y416833D01*
G01X1044700Y413500D02*
Y418500D01*
G01Y416000D02*
X1045117Y416500D01*
X1045617Y416750D01*
X1046117Y416833D01*
X1046867Y416667D01*
X1047367Y416333D01*
X1047700Y415750D01*
Y415083D01*
X1047533Y414417D01*
X1047200Y413917D01*
X1046617Y413583D01*
X1046117Y413500D01*
X1045617Y413583D01*
X1045117Y413833D01*
X1044700Y414250D01*
G01X1050300Y413500D02*
Y418500D01*
G01Y416000D02*
X1050717Y416500D01*
X1051217Y416750D01*
X1051717Y416833D01*
X1052467Y416667D01*
X1052967Y416333D01*
X1053300Y415750D01*
Y415083D01*
X1053133Y414417D01*
X1052800Y413917D01*
X1052217Y413583D01*
X1051717Y413500D01*
X1051217Y413583D01*
X1050717Y413833D01*
X1050300Y414250D01*
G01X1057400Y413500D02*
Y418500D01*
G01X1061750Y415750D02*
X1064417D01*
X1064167Y416333D01*
X1063750Y416667D01*
X1063167Y416833D01*
X1062583Y416750D01*
X1062083Y416500D01*
X1061750Y415917D01*
X1061583Y415417D01*
Y414917D01*
X1061750Y414417D01*
X1062167Y413917D01*
X1062667Y413583D01*
X1063250Y413500D01*
X1063833Y413667D01*
X1064417Y414167D01*
G01X1074200Y416833D02*
Y413500D01*
G01Y418167D02*
X1074033Y418250D01*
Y418417D01*
X1074200Y418500D01*
X1074367Y418417D01*
Y418250D01*
X1074200Y418167D01*
G01X1078383Y413500D02*
Y416833D01*
G01Y416000D02*
X1078717Y416417D01*
X1079217Y416750D01*
X1079883Y416833D01*
X1080467Y416750D01*
X1080967Y416417D01*
X1081217Y415833D01*
Y413500D01*
G01X1084150Y414083D02*
X1084567Y413750D01*
X1085150Y413500D01*
X1085650D01*
X1086150Y413667D01*
X1086483Y413917D01*
X1086650Y414250D01*
X1086567Y414750D01*
X1086233Y415000D01*
X1084733Y415500D01*
X1084400Y416083D01*
X1084567Y416500D01*
X1084900Y416750D01*
X1085400Y416833D01*
X1085900Y416750D01*
X1086400Y416500D01*
G01X1091000Y416833D02*
Y413500D01*
G01Y418167D02*
X1090833Y418250D01*
Y418417D01*
X1091000Y418500D01*
X1091167Y418417D01*
Y418250D01*
X1091000Y418167D01*
G01X1098100Y418500D02*
Y413500D01*
G01Y414250D02*
X1097767Y413833D01*
X1097267Y413583D01*
X1096683Y413500D01*
X1096017Y413667D01*
X1095517Y414083D01*
X1095183Y414583D01*
X1095100Y415167D01*
X1095183Y415750D01*
X1095517Y416250D01*
X1096017Y416667D01*
X1096683Y416833D01*
X1097267Y416750D01*
X1097683Y416583D01*
X1098100Y416250D01*
G01X1100950Y415750D02*
X1103617D01*
X1103367Y416333D01*
X1102950Y416667D01*
X1102367Y416833D01*
X1101783Y416750D01*
X1101283Y416500D01*
X1100950Y415917D01*
X1100783Y415417D01*
Y414917D01*
X1100950Y414417D01*
X1101367Y413917D01*
X1101867Y413583D01*
X1102450Y413500D01*
X1103033Y413667D01*
X1103617Y414167D01*
G01X1113400Y418500D02*
Y413500D01*
G01X1112233Y416833D02*
X1114567D01*
G01X1117583Y413500D02*
Y418500D01*
G01Y416083D02*
X1118000Y416500D01*
X1118417Y416750D01*
X1119083Y416833D01*
X1119583Y416750D01*
X1120167Y416417D01*
X1120417Y415917D01*
Y413500D01*
G01X1123350Y415750D02*
X1126017D01*
X1125767Y416333D01*
X1125350Y416667D01*
X1124767Y416833D01*
X1124183Y416750D01*
X1123683Y416500D01*
X1123350Y415917D01*
X1123183Y415417D01*
Y414917D01*
X1123350Y414417D01*
X1123767Y413917D01*
X1124267Y413583D01*
X1124850Y413500D01*
X1125433Y413667D01*
X1126017Y414167D01*
G01X1134633Y413500D02*
Y416833D01*
G01Y416167D02*
X1135050Y416500D01*
X1135467Y416750D01*
X1136050Y416833D01*
X1136467Y416750D01*
X1136967Y416500D01*
G01X1140150Y415750D02*
X1142817D01*
X1142567Y416333D01*
X1142150Y416667D01*
X1141567Y416833D01*
X1140983Y416750D01*
X1140483Y416500D01*
X1140150Y415917D01*
X1139983Y415417D01*
Y414917D01*
X1140150Y414417D01*
X1140567Y413917D01*
X1141067Y413583D01*
X1141650Y413500D01*
X1142233Y413667D01*
X1142817Y414167D01*
G01X1145750Y414083D02*
X1146167Y413750D01*
X1146750Y413500D01*
X1147250D01*
X1147750Y413667D01*
X1148083Y413917D01*
X1148250Y414250D01*
X1148167Y414750D01*
X1147833Y415000D01*
X1146333Y415500D01*
X1146000Y416083D01*
X1146167Y416500D01*
X1146500Y416750D01*
X1147000Y416833D01*
X1147500Y416750D01*
X1148000Y416500D01*
G01X1152600Y416833D02*
Y413500D01*
G01Y418167D02*
X1152433Y418250D01*
Y418417D01*
X1152600Y418500D01*
X1152767Y418417D01*
Y418250D01*
X1152600Y418167D01*
G01X1156783Y413500D02*
Y416833D01*
G01Y416000D02*
X1157117Y416417D01*
X1157617Y416750D01*
X1158283Y416833D01*
X1158867Y416750D01*
X1159367Y416417D01*
X1159617Y415833D01*
Y413500D01*
G01X1163800Y413333D02*
X1163633Y413417D01*
Y413583D01*
X1163800Y413667D01*
X1163967Y413583D01*
Y413417D01*
X1163800Y413333D01*
G01X1023000Y390000D02*
Y395000D01*
X1022000Y394000D01*
G01Y390000D02*
X1024000D01*
G01X1028600Y389833D02*
X1028433Y389917D01*
Y390083D01*
X1028600Y390167D01*
X1028767Y390083D01*
Y389917D01*
X1028600Y389833D01*
G01X1032367Y390000D02*
Y395000D01*
X1034033D01*
X1034700Y394750D01*
X1035200Y394417D01*
X1035617Y393917D01*
X1035950Y393333D01*
X1036033Y392500D01*
X1035950Y391667D01*
X1035617Y391083D01*
X1035200Y390583D01*
X1034700Y390250D01*
X1034033Y390000D01*
X1032367D01*
G01X1039800Y393333D02*
Y390000D01*
G01Y394667D02*
X1039633Y394750D01*
Y394917D01*
X1039800Y395000D01*
X1039967Y394917D01*
Y394750D01*
X1039800Y394667D01*
G01X1042900Y390000D02*
Y393333D01*
G01Y392417D02*
X1043150Y392833D01*
X1043567Y393167D01*
X1044150Y393333D01*
X1044733Y393167D01*
X1045150Y392833D01*
X1045400Y392417D01*
Y390000D01*
G01Y392417D02*
X1045650Y392833D01*
X1046067Y393167D01*
X1046650Y393333D01*
X1047233Y393167D01*
X1047650Y392833D01*
X1047900Y392333D01*
Y390000D01*
G01X1049500Y388333D02*
Y393333D01*
G01Y392583D02*
X1049917Y393000D01*
X1050333Y393250D01*
X1051000Y393333D01*
X1051583Y393250D01*
X1052167Y392833D01*
X1052417Y392250D01*
X1052500Y391667D01*
X1052417Y391083D01*
X1052167Y390500D01*
X1051667Y390167D01*
X1051000Y390000D01*
X1050417Y390083D01*
X1049833Y390333D01*
X1049500Y390667D01*
G01X1056600Y390000D02*
Y395000D01*
G01X1060950Y392250D02*
X1063617D01*
X1063367Y392833D01*
X1062950Y393167D01*
X1062367Y393333D01*
X1061783Y393250D01*
X1061283Y393000D01*
X1060950Y392417D01*
X1060783Y391917D01*
Y391417D01*
X1060950Y390917D01*
X1061367Y390417D01*
X1061867Y390083D01*
X1062450Y390000D01*
X1063033Y390167D01*
X1063617Y390667D01*
G01X1075067Y390000D02*
X1071733Y391667D01*
X1075067Y393333D01*
G01X1084600Y390000D02*
Y395000D01*
X1083600Y394000D01*
G01Y390000D02*
X1085600D01*
G01X1093300D02*
Y393333D01*
G01Y392417D02*
X1093550Y392833D01*
X1093967Y393167D01*
X1094550Y393333D01*
X1095133Y393167D01*
X1095550Y392833D01*
X1095800Y392417D01*
Y390000D01*
G01Y392417D02*
X1096050Y392833D01*
X1096467Y393167D01*
X1097050Y393333D01*
X1097633Y393167D01*
X1098050Y392833D01*
X1098300Y392333D01*
Y390000D01*
G01X1101400Y393333D02*
Y390000D01*
G01Y394667D02*
X1101233Y394750D01*
Y394917D01*
X1101400Y395000D01*
X1101567Y394917D01*
Y394750D01*
X1101400Y394667D01*
G01X1107000Y390000D02*
Y395000D01*
G01X1117617Y388500D02*
X1118783Y389667D01*
Y390833D01*
X1117617D01*
Y389667D01*
X1118783D01*
G01Y391667D02*
Y392833D01*
X1117617D01*
Y391667D01*
X1118783D01*
G01X1016000Y604500D02*
Y366000D01*
G01X1023000Y424000D02*
Y429000D01*
X1022000Y428000D01*
G01Y424000D02*
X1024000D01*
G01X1028600Y423833D02*
X1028433Y423917D01*
Y424083D01*
X1028600Y424167D01*
X1028767Y424083D01*
Y423917D01*
X1028600Y423833D01*
G01X1032117Y429000D02*
X1034200Y424000D01*
X1036283Y429000D01*
G01X1039800Y427333D02*
Y424000D01*
G01Y428667D02*
X1039633Y428750D01*
Y428917D01*
X1039800Y429000D01*
X1039967Y428917D01*
Y428750D01*
X1039800Y428667D01*
G01X1046900Y424000D02*
Y427333D01*
G01Y426750D02*
X1046567Y427083D01*
X1046067Y427250D01*
X1045483Y427333D01*
X1044900Y427167D01*
X1044400Y426833D01*
X1044067Y426333D01*
X1043900Y425667D01*
X1044067Y425000D01*
X1044400Y424500D01*
X1044900Y424167D01*
X1045483Y424000D01*
X1046067Y424083D01*
X1046567Y424333D01*
X1046900Y424667D01*
G01X1055350Y424583D02*
X1055767Y424250D01*
X1056350Y424000D01*
X1056850D01*
X1057350Y424167D01*
X1057683Y424417D01*
X1057850Y424750D01*
X1057767Y425250D01*
X1057433Y425500D01*
X1055933Y426000D01*
X1055600Y426583D01*
X1055767Y427000D01*
X1056100Y427250D01*
X1056600Y427333D01*
X1057100Y427250D01*
X1057600Y427000D01*
G01X1060783Y424000D02*
Y429000D01*
G01Y426583D02*
X1061200Y427000D01*
X1061617Y427250D01*
X1062283Y427333D01*
X1062783Y427250D01*
X1063367Y426917D01*
X1063617Y426417D01*
Y424000D01*
G01X1067800D02*
X1067300Y424083D01*
X1066800Y424417D01*
X1066467Y425000D01*
X1066300Y425667D01*
X1066467Y426333D01*
X1066800Y426917D01*
X1067300Y427250D01*
X1067800Y427333D01*
X1068300Y427250D01*
X1068800Y426917D01*
X1069133Y426333D01*
X1069217Y425667D01*
X1069133Y425000D01*
X1068800Y424417D01*
X1068300Y424083D01*
X1067800Y424000D01*
G01X1071983Y427333D02*
Y425000D01*
X1072317Y424417D01*
X1072817Y424083D01*
X1073400Y424000D01*
X1073983Y424083D01*
X1074483Y424417D01*
X1074817Y425000D01*
G01Y424000D02*
Y427333D01*
G01X1079000Y424000D02*
Y429000D01*
G01X1086100D02*
Y424000D01*
G01Y424750D02*
X1085767Y424333D01*
X1085267Y424083D01*
X1084683Y424000D01*
X1084017Y424167D01*
X1083517Y424583D01*
X1083183Y425083D01*
X1083100Y425667D01*
X1083183Y426250D01*
X1083517Y426750D01*
X1084017Y427167D01*
X1084683Y427333D01*
X1085267Y427250D01*
X1085683Y427083D01*
X1086100Y426750D01*
G01X1094300Y424000D02*
Y429000D01*
G01Y426500D02*
X1094717Y427000D01*
X1095217Y427250D01*
X1095717Y427333D01*
X1096467Y427167D01*
X1096967Y426833D01*
X1097300Y426250D01*
Y425583D01*
X1097133Y424917D01*
X1096800Y424417D01*
X1096217Y424083D01*
X1095717Y424000D01*
X1095217Y424083D01*
X1094717Y424333D01*
X1094300Y424750D01*
G01X1100150Y426250D02*
X1102817D01*
X1102567Y426833D01*
X1102150Y427167D01*
X1101567Y427333D01*
X1100983Y427250D01*
X1100483Y427000D01*
X1100150Y426417D01*
X1099983Y425917D01*
Y425417D01*
X1100150Y424917D01*
X1100567Y424417D01*
X1101067Y424083D01*
X1101650Y424000D01*
X1102233Y424167D01*
X1102817Y424667D01*
G01X1111100Y422333D02*
Y427333D01*
G01Y426583D02*
X1111517Y427000D01*
X1111933Y427250D01*
X1112600Y427333D01*
X1113183Y427250D01*
X1113767Y426833D01*
X1114017Y426250D01*
X1114100Y425667D01*
X1114017Y425083D01*
X1113767Y424500D01*
X1113267Y424167D01*
X1112600Y424000D01*
X1112017Y424083D01*
X1111433Y424333D01*
X1111100Y424667D01*
G01X1118200Y424000D02*
Y429000D01*
G01X1122383Y427333D02*
Y425000D01*
X1122717Y424417D01*
X1123217Y424083D01*
X1123800Y424000D01*
X1124383Y424083D01*
X1124883Y424417D01*
X1125217Y425000D01*
G01Y424000D02*
Y427333D01*
G01X1128233Y422750D02*
X1128817Y422417D01*
X1129483Y422333D01*
X1130067Y422417D01*
X1130567Y422833D01*
X1130900Y423417D01*
Y427333D01*
G01Y426667D02*
X1130567Y427000D01*
X1130067Y427250D01*
X1129483Y427333D01*
X1128817Y427167D01*
X1128400Y426833D01*
X1128067Y426250D01*
X1127900Y425667D01*
X1127983Y425167D01*
X1128317Y424583D01*
X1128817Y424167D01*
X1129483Y424000D01*
X1129983Y424083D01*
X1130567Y424417D01*
X1130900Y424750D01*
G01X1133833Y422750D02*
X1134417Y422417D01*
X1135083Y422333D01*
X1135667Y422417D01*
X1136167Y422833D01*
X1136500Y423417D01*
Y427333D01*
G01Y426667D02*
X1136167Y427000D01*
X1135667Y427250D01*
X1135083Y427333D01*
X1134417Y427167D01*
X1134000Y426833D01*
X1133667Y426250D01*
X1133500Y425667D01*
X1133583Y425167D01*
X1133917Y424583D01*
X1134417Y424167D01*
X1135083Y424000D01*
X1135583Y424083D01*
X1136167Y424417D01*
X1136500Y424750D01*
G01X1139350Y426250D02*
X1142017D01*
X1141767Y426833D01*
X1141350Y427167D01*
X1140767Y427333D01*
X1140183Y427250D01*
X1139683Y427000D01*
X1139350Y426417D01*
X1139183Y425917D01*
Y425417D01*
X1139350Y424917D01*
X1139767Y424417D01*
X1140267Y424083D01*
X1140850Y424000D01*
X1141433Y424167D01*
X1142017Y424667D01*
G01X1147700Y429000D02*
Y424000D01*
G01Y424750D02*
X1147367Y424333D01*
X1146867Y424083D01*
X1146283Y424000D01*
X1145617Y424167D01*
X1145117Y424583D01*
X1144783Y425083D01*
X1144700Y425667D01*
X1144783Y426250D01*
X1145117Y426750D01*
X1145617Y427167D01*
X1146283Y427333D01*
X1146867Y427250D01*
X1147283Y427083D01*
X1147700Y426750D01*
G01X1155317Y427333D02*
X1156317Y424000D01*
X1157400Y427333D01*
X1158483Y424000D01*
X1159483Y427333D01*
G01X1163000D02*
Y424000D01*
G01Y428667D02*
X1162833Y428750D01*
Y428917D01*
X1163000Y429000D01*
X1163167Y428917D01*
Y428750D01*
X1163000Y428667D01*
G01X1168600Y429000D02*
Y424000D01*
G01X1167433Y427333D02*
X1169767D01*
G01X1172783Y424000D02*
Y429000D01*
G01Y426583D02*
X1173200Y427000D01*
X1173617Y427250D01*
X1174283Y427333D01*
X1174783Y427250D01*
X1175367Y426917D01*
X1175617Y426417D01*
Y424000D01*
G01X1183733D02*
X1187067Y425667D01*
X1183733Y427333D01*
G01X1189583Y424583D02*
X1190167Y424167D01*
X1190833Y424000D01*
X1191500Y424167D01*
X1192083Y424667D01*
X1192500Y425417D01*
X1192667Y426167D01*
Y427083D01*
X1192500Y427833D01*
X1192083Y428500D01*
X1191583Y428833D01*
X1191000Y429000D01*
X1190333Y428833D01*
X1189833Y428500D01*
X1189500Y428000D01*
X1189333Y427333D01*
X1189500Y426750D01*
X1189917Y426167D01*
X1190417Y425833D01*
X1191000Y425750D01*
X1191667Y425917D01*
X1192167Y426333D01*
X1192667Y427083D01*
G01X1196600Y429000D02*
X1195933Y428833D01*
X1195433Y428417D01*
X1195100Y427917D01*
X1194850Y427250D01*
X1194767Y426500D01*
X1194850Y425750D01*
X1195100Y425083D01*
X1195433Y424583D01*
X1195933Y424167D01*
X1196600Y424000D01*
X1197267Y424167D01*
X1197767Y424583D01*
X1198100Y425083D01*
X1198350Y425750D01*
X1198433Y426500D01*
X1198350Y427250D01*
X1198100Y427917D01*
X1197767Y428417D01*
X1197267Y428833D01*
X1196600Y429000D01*
G01X1200700Y423833D02*
X1203700Y429000D01*
G01X1200700D02*
X1200200Y428833D01*
X1199950Y428583D01*
X1199783Y428083D01*
X1199950Y427583D01*
X1200200Y427333D01*
X1200700Y427167D01*
X1201200Y427333D01*
X1201450Y427583D01*
X1201617Y428083D01*
X1201450Y428583D01*
X1201200Y428833D01*
X1200700Y429000D01*
G01X1203700Y425667D02*
X1203200Y425500D01*
X1202950Y425250D01*
X1202783Y424750D01*
X1202950Y424250D01*
X1203200Y424000D01*
X1203700Y423833D01*
X1204200Y424000D01*
X1204450Y424250D01*
X1204617Y424750D01*
X1204450Y425250D01*
X1204200Y425500D01*
X1203700Y425667D01*
G01X1212233Y424000D02*
Y427333D01*
G01Y426667D02*
X1212650Y427000D01*
X1213067Y427250D01*
X1213650Y427333D01*
X1214067Y427250D01*
X1214567Y427000D01*
G01X1217750Y426250D02*
X1220417D01*
X1220167Y426833D01*
X1219750Y427167D01*
X1219167Y427333D01*
X1218583Y427250D01*
X1218083Y427000D01*
X1217750Y426417D01*
X1217583Y425917D01*
Y425417D01*
X1217750Y424917D01*
X1218167Y424417D01*
X1218667Y424083D01*
X1219250Y424000D01*
X1219833Y424167D01*
X1220417Y424667D01*
G01X1223350Y424583D02*
X1223767Y424250D01*
X1224350Y424000D01*
X1224850D01*
X1225350Y424167D01*
X1225683Y424417D01*
X1225850Y424750D01*
X1225767Y425250D01*
X1225433Y425500D01*
X1223933Y426000D01*
X1223600Y426583D01*
X1223767Y427000D01*
X1224100Y427250D01*
X1224600Y427333D01*
X1225100Y427250D01*
X1225600Y427000D01*
G01X1230200Y427333D02*
Y424000D01*
G01Y428667D02*
X1230033Y428750D01*
Y428917D01*
X1230200Y429000D01*
X1230367Y428917D01*
Y428750D01*
X1230200Y428667D01*
G01X1234383Y424000D02*
Y427333D01*
G01Y426500D02*
X1234717Y426917D01*
X1235217Y427250D01*
X1235883Y427333D01*
X1236467Y427250D01*
X1236967Y426917D01*
X1237217Y426333D01*
Y424000D01*
G01X1246417Y422500D02*
X1247583Y423667D01*
Y424833D01*
X1246417D01*
Y423667D01*
X1247583D01*
G01Y425667D02*
Y426833D01*
X1246417D01*
Y425667D01*
X1247583D01*
G01X1250767Y424000D02*
Y429000D01*
X1252433D01*
X1253100Y428750D01*
X1253600Y428417D01*
X1254017Y427917D01*
X1254350Y427333D01*
X1254433Y426500D01*
X1254350Y425667D01*
X1254017Y425083D01*
X1253600Y424583D01*
X1253100Y424250D01*
X1252433Y424000D01*
X1250767D01*
G01X1258200D02*
X1257700Y424083D01*
X1257200Y424417D01*
X1256867Y425000D01*
X1256700Y425667D01*
X1256867Y426333D01*
X1257200Y426917D01*
X1257700Y427250D01*
X1258200Y427333D01*
X1258700Y427250D01*
X1259200Y426917D01*
X1259533Y426333D01*
X1259617Y425667D01*
X1259533Y425000D01*
X1259200Y424417D01*
X1258700Y424083D01*
X1258200Y424000D01*
G01X1267983D02*
Y427333D01*
G01Y426500D02*
X1268317Y426917D01*
X1268817Y427250D01*
X1269483Y427333D01*
X1270067Y427250D01*
X1270567Y426917D01*
X1270817Y426333D01*
Y424000D01*
G01X1275000D02*
X1274500Y424083D01*
X1274000Y424417D01*
X1273667Y425000D01*
X1273500Y425667D01*
X1273667Y426333D01*
X1274000Y426917D01*
X1274500Y427250D01*
X1275000Y427333D01*
X1275500Y427250D01*
X1276000Y426917D01*
X1276333Y426333D01*
X1276417Y425667D01*
X1276333Y425000D01*
X1276000Y424417D01*
X1275500Y424083D01*
X1275000Y424000D01*
G01X1280600Y429000D02*
Y424000D01*
G01X1279433Y427333D02*
X1281767D01*
G01X1293300Y424000D02*
Y427333D01*
G01Y426750D02*
X1292967Y427083D01*
X1292467Y427250D01*
X1291883Y427333D01*
X1291300Y427167D01*
X1290800Y426833D01*
X1290467Y426333D01*
X1290300Y425667D01*
X1290467Y425000D01*
X1290800Y424500D01*
X1291300Y424167D01*
X1291883Y424000D01*
X1292467Y424083D01*
X1292967Y424333D01*
X1293300Y424667D01*
G01X1297400Y424000D02*
Y429000D01*
G01X1303000Y424000D02*
Y429000D01*
G01X1308600Y424000D02*
X1308100Y424083D01*
X1307600Y424417D01*
X1307267Y425000D01*
X1307100Y425667D01*
X1307267Y426333D01*
X1307600Y426917D01*
X1308100Y427250D01*
X1308600Y427333D01*
X1309100Y427250D01*
X1309600Y426917D01*
X1309933Y426333D01*
X1310017Y425667D01*
X1309933Y425000D01*
X1309600Y424417D01*
X1309100Y424083D01*
X1308600Y424000D01*
G01X1312117Y427333D02*
X1313117Y424000D01*
X1314200Y427333D01*
X1315283Y424000D01*
X1316283Y427333D01*
G01X1025417Y445500D02*
X1027500Y440500D01*
X1029583Y445500D01*
G01X1033100Y443833D02*
Y440500D01*
G01Y445167D02*
X1032933Y445250D01*
Y445417D01*
X1033100Y445500D01*
X1033267Y445417D01*
Y445250D01*
X1033100Y445167D01*
G01X1040200Y440500D02*
Y443833D01*
G01Y443250D02*
X1039867Y443583D01*
X1039367Y443750D01*
X1038783Y443833D01*
X1038200Y443667D01*
X1037700Y443333D01*
X1037367Y442833D01*
X1037200Y442167D01*
X1037367Y441500D01*
X1037700Y441000D01*
X1038200Y440667D01*
X1038783Y440500D01*
X1039367Y440583D01*
X1039867Y440833D01*
X1040200Y441167D01*
G01X1048650Y441083D02*
X1049067Y440750D01*
X1049650Y440500D01*
X1050150D01*
X1050650Y440667D01*
X1050983Y440917D01*
X1051150Y441250D01*
X1051067Y441750D01*
X1050733Y442000D01*
X1049233Y442500D01*
X1048900Y443083D01*
X1049067Y443500D01*
X1049400Y443750D01*
X1049900Y443833D01*
X1050400Y443750D01*
X1050900Y443500D01*
G01X1054083Y440500D02*
Y445500D01*
G01Y443083D02*
X1054500Y443500D01*
X1054917Y443750D01*
X1055583Y443833D01*
X1056083Y443750D01*
X1056667Y443417D01*
X1056917Y442917D01*
Y440500D01*
G01X1061100D02*
X1060600Y440583D01*
X1060100Y440917D01*
X1059767Y441500D01*
X1059600Y442167D01*
X1059767Y442833D01*
X1060100Y443417D01*
X1060600Y443750D01*
X1061100Y443833D01*
X1061600Y443750D01*
X1062100Y443417D01*
X1062433Y442833D01*
X1062517Y442167D01*
X1062433Y441500D01*
X1062100Y440917D01*
X1061600Y440583D01*
X1061100Y440500D01*
G01X1065283Y443833D02*
Y441500D01*
X1065617Y440917D01*
X1066117Y440583D01*
X1066700Y440500D01*
X1067283Y440583D01*
X1067783Y440917D01*
X1068117Y441500D01*
G01Y440500D02*
Y443833D01*
G01X1072300Y440500D02*
Y445500D01*
G01X1079400D02*
Y440500D01*
G01Y441250D02*
X1079067Y440833D01*
X1078567Y440583D01*
X1077983Y440500D01*
X1077317Y440667D01*
X1076817Y441083D01*
X1076483Y441583D01*
X1076400Y442167D01*
X1076483Y442750D01*
X1076817Y443250D01*
X1077317Y443667D01*
X1077983Y443833D01*
X1078567Y443750D01*
X1078983Y443583D01*
X1079400Y443250D01*
G01X1087600Y440500D02*
Y445500D01*
G01Y443000D02*
X1088017Y443500D01*
X1088517Y443750D01*
X1089017Y443833D01*
X1089767Y443667D01*
X1090267Y443333D01*
X1090600Y442750D01*
Y442083D01*
X1090433Y441417D01*
X1090100Y440917D01*
X1089517Y440583D01*
X1089017Y440500D01*
X1088517Y440583D01*
X1088017Y440833D01*
X1087600Y441250D01*
G01X1093450Y442750D02*
X1096117D01*
X1095867Y443333D01*
X1095450Y443667D01*
X1094867Y443833D01*
X1094283Y443750D01*
X1093783Y443500D01*
X1093450Y442917D01*
X1093283Y442417D01*
Y441917D01*
X1093450Y441417D01*
X1093867Y440917D01*
X1094367Y440583D01*
X1094950Y440500D01*
X1095533Y440667D01*
X1096117Y441167D01*
G01X1104400Y438833D02*
Y443833D01*
G01Y443083D02*
X1104817Y443500D01*
X1105233Y443750D01*
X1105900Y443833D01*
X1106483Y443750D01*
X1107067Y443333D01*
X1107317Y442750D01*
X1107400Y442167D01*
X1107317Y441583D01*
X1107067Y441000D01*
X1106567Y440667D01*
X1105900Y440500D01*
X1105317Y440583D01*
X1104733Y440833D01*
X1104400Y441167D01*
G01X1111500Y440500D02*
Y445500D01*
G01X1115683Y443833D02*
Y441500D01*
X1116017Y440917D01*
X1116517Y440583D01*
X1117100Y440500D01*
X1117683Y440583D01*
X1118183Y440917D01*
X1118517Y441500D01*
G01Y440500D02*
Y443833D01*
G01X1121533Y439250D02*
X1122117Y438917D01*
X1122783Y438833D01*
X1123367Y438917D01*
X1123867Y439333D01*
X1124200Y439917D01*
Y443833D01*
G01Y443167D02*
X1123867Y443500D01*
X1123367Y443750D01*
X1122783Y443833D01*
X1122117Y443667D01*
X1121700Y443333D01*
X1121367Y442750D01*
X1121200Y442167D01*
X1121283Y441667D01*
X1121617Y441083D01*
X1122117Y440667D01*
X1122783Y440500D01*
X1123283Y440583D01*
X1123867Y440917D01*
X1124200Y441250D01*
G01X1127133Y439250D02*
X1127717Y438917D01*
X1128383Y438833D01*
X1128967Y438917D01*
X1129467Y439333D01*
X1129800Y439917D01*
Y443833D01*
G01Y443167D02*
X1129467Y443500D01*
X1128967Y443750D01*
X1128383Y443833D01*
X1127717Y443667D01*
X1127300Y443333D01*
X1126967Y442750D01*
X1126800Y442167D01*
X1126883Y441667D01*
X1127217Y441083D01*
X1127717Y440667D01*
X1128383Y440500D01*
X1128883Y440583D01*
X1129467Y440917D01*
X1129800Y441250D01*
G01X1132650Y442750D02*
X1135317D01*
X1135067Y443333D01*
X1134650Y443667D01*
X1134067Y443833D01*
X1133483Y443750D01*
X1132983Y443500D01*
X1132650Y442917D01*
X1132483Y442417D01*
Y441917D01*
X1132650Y441417D01*
X1133067Y440917D01*
X1133567Y440583D01*
X1134150Y440500D01*
X1134733Y440667D01*
X1135317Y441167D01*
G01X1141000Y445500D02*
Y440500D01*
G01Y441250D02*
X1140667Y440833D01*
X1140167Y440583D01*
X1139583Y440500D01*
X1138917Y440667D01*
X1138417Y441083D01*
X1138083Y441583D01*
X1138000Y442167D01*
X1138083Y442750D01*
X1138417Y443250D01*
X1138917Y443667D01*
X1139583Y443833D01*
X1140167Y443750D01*
X1140583Y443583D01*
X1141000Y443250D01*
G01X1148617Y443833D02*
X1149617Y440500D01*
X1150700Y443833D01*
X1151783Y440500D01*
X1152783Y443833D01*
G01X1156300D02*
Y440500D01*
G01Y445167D02*
X1156133Y445250D01*
Y445417D01*
X1156300Y445500D01*
X1156467Y445417D01*
Y445250D01*
X1156300Y445167D01*
G01X1161900Y445500D02*
Y440500D01*
G01X1160733Y443833D02*
X1163067D01*
G01X1166083Y440500D02*
Y445500D01*
G01Y443083D02*
X1166500Y443500D01*
X1166917Y443750D01*
X1167583Y443833D01*
X1168083Y443750D01*
X1168667Y443417D01*
X1168917Y442917D01*
Y440500D01*
G01X1177033D02*
X1180367Y442167D01*
X1177033Y443833D01*
G01X1182883Y441083D02*
X1183467Y440667D01*
X1184133Y440500D01*
X1184800Y440667D01*
X1185383Y441167D01*
X1185800Y441917D01*
X1185967Y442667D01*
Y443583D01*
X1185800Y444333D01*
X1185383Y445000D01*
X1184883Y445333D01*
X1184300Y445500D01*
X1183633Y445333D01*
X1183133Y445000D01*
X1182800Y444500D01*
X1182633Y443833D01*
X1182800Y443250D01*
X1183217Y442667D01*
X1183717Y442333D01*
X1184300Y442250D01*
X1184967Y442417D01*
X1185467Y442833D01*
X1185967Y443583D01*
G01X1189900Y445500D02*
X1189233Y445333D01*
X1188733Y444917D01*
X1188400Y444417D01*
X1188150Y443750D01*
X1188067Y443000D01*
X1188150Y442250D01*
X1188400Y441583D01*
X1188733Y441083D01*
X1189233Y440667D01*
X1189900Y440500D01*
X1190567Y440667D01*
X1191067Y441083D01*
X1191400Y441583D01*
X1191650Y442250D01*
X1191733Y443000D01*
X1191650Y443750D01*
X1191400Y444417D01*
X1191067Y444917D01*
X1190567Y445333D01*
X1189900Y445500D01*
G01X1194000Y440333D02*
X1197000Y445500D01*
G01X1194000D02*
X1193500Y445333D01*
X1193250Y445083D01*
X1193083Y444583D01*
X1193250Y444083D01*
X1193500Y443833D01*
X1194000Y443667D01*
X1194500Y443833D01*
X1194750Y444083D01*
X1194917Y444583D01*
X1194750Y445083D01*
X1194500Y445333D01*
X1194000Y445500D01*
G01X1197000Y442167D02*
X1196500Y442000D01*
X1196250Y441750D01*
X1196083Y441250D01*
X1196250Y440750D01*
X1196500Y440500D01*
X1197000Y440333D01*
X1197500Y440500D01*
X1197750Y440750D01*
X1197917Y441250D01*
X1197750Y441750D01*
X1197500Y442000D01*
X1197000Y442167D01*
G01X1205533Y440500D02*
Y443833D01*
G01Y443167D02*
X1205950Y443500D01*
X1206367Y443750D01*
X1206950Y443833D01*
X1207367Y443750D01*
X1207867Y443500D01*
G01X1211050Y442750D02*
X1213717D01*
X1213467Y443333D01*
X1213050Y443667D01*
X1212467Y443833D01*
X1211883Y443750D01*
X1211383Y443500D01*
X1211050Y442917D01*
X1210883Y442417D01*
Y441917D01*
X1211050Y441417D01*
X1211467Y440917D01*
X1211967Y440583D01*
X1212550Y440500D01*
X1213133Y440667D01*
X1213717Y441167D01*
G01X1216650Y441083D02*
X1217067Y440750D01*
X1217650Y440500D01*
X1218150D01*
X1218650Y440667D01*
X1218983Y440917D01*
X1219150Y441250D01*
X1219067Y441750D01*
X1218733Y442000D01*
X1217233Y442500D01*
X1216900Y443083D01*
X1217067Y443500D01*
X1217400Y443750D01*
X1217900Y443833D01*
X1218400Y443750D01*
X1218900Y443500D01*
G01X1223500Y443833D02*
Y440500D01*
G01Y445167D02*
X1223333Y445250D01*
Y445417D01*
X1223500Y445500D01*
X1223667Y445417D01*
Y445250D01*
X1223500Y445167D01*
G01X1227683Y440500D02*
Y443833D01*
G01Y443000D02*
X1228017Y443417D01*
X1228517Y443750D01*
X1229183Y443833D01*
X1229767Y443750D01*
X1230267Y443417D01*
X1230517Y442833D01*
Y440500D01*
G01X1023917Y466500D02*
X1026000Y461500D01*
X1028083Y466500D01*
G01X1031600Y464833D02*
Y461500D01*
G01Y466167D02*
X1031433Y466250D01*
Y466417D01*
X1031600Y466500D01*
X1031767Y466417D01*
Y466250D01*
X1031600Y466167D01*
G01X1038700Y461500D02*
Y464833D01*
G01Y464250D02*
X1038367Y464583D01*
X1037867Y464750D01*
X1037283Y464833D01*
X1036700Y464667D01*
X1036200Y464333D01*
X1035867Y463833D01*
X1035700Y463167D01*
X1035867Y462500D01*
X1036200Y462000D01*
X1036700Y461667D01*
X1037283Y461500D01*
X1037867Y461583D01*
X1038367Y461833D01*
X1038700Y462167D01*
G01X1047150Y462083D02*
X1047567Y461750D01*
X1048150Y461500D01*
X1048650D01*
X1049150Y461667D01*
X1049483Y461917D01*
X1049650Y462250D01*
X1049567Y462750D01*
X1049233Y463000D01*
X1047733Y463500D01*
X1047400Y464083D01*
X1047567Y464500D01*
X1047900Y464750D01*
X1048400Y464833D01*
X1048900Y464750D01*
X1049400Y464500D01*
G01X1052583Y461500D02*
Y466500D01*
G01Y464083D02*
X1053000Y464500D01*
X1053417Y464750D01*
X1054083Y464833D01*
X1054583Y464750D01*
X1055167Y464417D01*
X1055417Y463917D01*
Y461500D01*
G01X1059600D02*
X1059100Y461583D01*
X1058600Y461917D01*
X1058267Y462500D01*
X1058100Y463167D01*
X1058267Y463833D01*
X1058600Y464417D01*
X1059100Y464750D01*
X1059600Y464833D01*
X1060100Y464750D01*
X1060600Y464417D01*
X1060933Y463833D01*
X1061017Y463167D01*
X1060933Y462500D01*
X1060600Y461917D01*
X1060100Y461583D01*
X1059600Y461500D01*
G01X1063783Y464833D02*
Y462500D01*
X1064117Y461917D01*
X1064617Y461583D01*
X1065200Y461500D01*
X1065783Y461583D01*
X1066283Y461917D01*
X1066617Y462500D01*
G01Y461500D02*
Y464833D01*
G01X1070800Y461500D02*
Y466500D01*
G01X1077900D02*
Y461500D01*
G01Y462250D02*
X1077567Y461833D01*
X1077067Y461583D01*
X1076483Y461500D01*
X1075817Y461667D01*
X1075317Y462083D01*
X1074983Y462583D01*
X1074900Y463167D01*
X1074983Y463750D01*
X1075317Y464250D01*
X1075817Y464667D01*
X1076483Y464833D01*
X1077067Y464750D01*
X1077483Y464583D01*
X1077900Y464250D01*
G01X1086100Y461500D02*
Y466500D01*
G01Y464000D02*
X1086517Y464500D01*
X1087017Y464750D01*
X1087517Y464833D01*
X1088267Y464667D01*
X1088767Y464333D01*
X1089100Y463750D01*
Y463083D01*
X1088933Y462417D01*
X1088600Y461917D01*
X1088017Y461583D01*
X1087517Y461500D01*
X1087017Y461583D01*
X1086517Y461833D01*
X1086100Y462250D01*
G01X1091950Y463750D02*
X1094617D01*
X1094367Y464333D01*
X1093950Y464667D01*
X1093367Y464833D01*
X1092783Y464750D01*
X1092283Y464500D01*
X1091950Y463917D01*
X1091783Y463417D01*
Y462917D01*
X1091950Y462417D01*
X1092367Y461917D01*
X1092867Y461583D01*
X1093450Y461500D01*
X1094033Y461667D01*
X1094617Y462167D01*
G01X1102900Y459833D02*
Y464833D01*
G01Y464083D02*
X1103317Y464500D01*
X1103733Y464750D01*
X1104400Y464833D01*
X1104983Y464750D01*
X1105567Y464333D01*
X1105817Y463750D01*
X1105900Y463167D01*
X1105817Y462583D01*
X1105567Y462000D01*
X1105067Y461667D01*
X1104400Y461500D01*
X1103817Y461583D01*
X1103233Y461833D01*
X1102900Y462167D01*
G01X1110000Y461500D02*
Y466500D01*
G01X1114183Y464833D02*
Y462500D01*
X1114517Y461917D01*
X1115017Y461583D01*
X1115600Y461500D01*
X1116183Y461583D01*
X1116683Y461917D01*
X1117017Y462500D01*
G01Y461500D02*
Y464833D01*
G01X1120033Y460250D02*
X1120617Y459917D01*
X1121283Y459833D01*
X1121867Y459917D01*
X1122367Y460333D01*
X1122700Y460917D01*
Y464833D01*
G01Y464167D02*
X1122367Y464500D01*
X1121867Y464750D01*
X1121283Y464833D01*
X1120617Y464667D01*
X1120200Y464333D01*
X1119867Y463750D01*
X1119700Y463167D01*
X1119783Y462667D01*
X1120117Y462083D01*
X1120617Y461667D01*
X1121283Y461500D01*
X1121783Y461583D01*
X1122367Y461917D01*
X1122700Y462250D01*
G01X1125633Y460250D02*
X1126217Y459917D01*
X1126883Y459833D01*
X1127467Y459917D01*
X1127967Y460333D01*
X1128300Y460917D01*
Y464833D01*
G01Y464167D02*
X1127967Y464500D01*
X1127467Y464750D01*
X1126883Y464833D01*
X1126217Y464667D01*
X1125800Y464333D01*
X1125467Y463750D01*
X1125300Y463167D01*
X1125383Y462667D01*
X1125717Y462083D01*
X1126217Y461667D01*
X1126883Y461500D01*
X1127383Y461583D01*
X1127967Y461917D01*
X1128300Y462250D01*
G01X1131150Y463750D02*
X1133817D01*
X1133567Y464333D01*
X1133150Y464667D01*
X1132567Y464833D01*
X1131983Y464750D01*
X1131483Y464500D01*
X1131150Y463917D01*
X1130983Y463417D01*
Y462917D01*
X1131150Y462417D01*
X1131567Y461917D01*
X1132067Y461583D01*
X1132650Y461500D01*
X1133233Y461667D01*
X1133817Y462167D01*
G01X1139500Y466500D02*
Y461500D01*
G01Y462250D02*
X1139167Y461833D01*
X1138667Y461583D01*
X1138083Y461500D01*
X1137417Y461667D01*
X1136917Y462083D01*
X1136583Y462583D01*
X1136500Y463167D01*
X1136583Y463750D01*
X1136917Y464250D01*
X1137417Y464667D01*
X1138083Y464833D01*
X1138667Y464750D01*
X1139083Y464583D01*
X1139500Y464250D01*
G01X1150200Y461500D02*
Y466500D01*
X1147117Y462917D01*
X1151283D01*
G01X1154800Y466500D02*
X1154133Y466333D01*
X1153633Y465917D01*
X1153300Y465417D01*
X1153050Y464750D01*
X1152967Y464000D01*
X1153050Y463250D01*
X1153300Y462583D01*
X1153633Y462083D01*
X1154133Y461667D01*
X1154800Y461500D01*
X1155467Y461667D01*
X1155967Y462083D01*
X1156300Y462583D01*
X1156550Y463250D01*
X1156633Y464000D01*
X1156550Y464750D01*
X1156300Y465417D01*
X1155967Y465917D01*
X1155467Y466333D01*
X1154800Y466500D01*
G01X1158900Y461333D02*
X1161900Y466500D01*
G01X1158900D02*
X1158400Y466333D01*
X1158150Y466083D01*
X1157983Y465583D01*
X1158150Y465083D01*
X1158400Y464833D01*
X1158900Y464667D01*
X1159400Y464833D01*
X1159650Y465083D01*
X1159817Y465583D01*
X1159650Y466083D01*
X1159400Y466333D01*
X1158900Y466500D01*
G01X1161900Y463167D02*
X1161400Y463000D01*
X1161150Y462750D01*
X1160983Y462250D01*
X1161150Y461750D01*
X1161400Y461500D01*
X1161900Y461333D01*
X1162400Y461500D01*
X1162650Y461750D01*
X1162817Y462250D01*
X1162650Y462750D01*
X1162400Y463000D01*
X1161900Y463167D01*
G01X1169100D02*
X1169933Y464833D01*
X1170767D01*
X1172433Y461500D01*
X1173267D01*
X1174100Y463167D01*
G01X1182800Y461500D02*
Y466500D01*
X1181800Y465500D01*
G01Y461500D02*
X1183800D01*
G01X1188400Y466500D02*
X1187733Y466333D01*
X1187233Y465917D01*
X1186900Y465417D01*
X1186650Y464750D01*
X1186567Y464000D01*
X1186650Y463250D01*
X1186900Y462583D01*
X1187233Y462083D01*
X1187733Y461667D01*
X1188400Y461500D01*
X1189067Y461667D01*
X1189567Y462083D01*
X1189900Y462583D01*
X1190150Y463250D01*
X1190233Y464000D01*
X1190150Y464750D01*
X1189900Y465417D01*
X1189567Y465917D01*
X1189067Y466333D01*
X1188400Y466500D01*
G01X1194000D02*
X1193333Y466333D01*
X1192833Y465917D01*
X1192500Y465417D01*
X1192250Y464750D01*
X1192167Y464000D01*
X1192250Y463250D01*
X1192500Y462583D01*
X1192833Y462083D01*
X1193333Y461667D01*
X1194000Y461500D01*
X1194667Y461667D01*
X1195167Y462083D01*
X1195500Y462583D01*
X1195750Y463250D01*
X1195833Y464000D01*
X1195750Y464750D01*
X1195500Y465417D01*
X1195167Y465917D01*
X1194667Y466333D01*
X1194000Y466500D01*
G01X1198100Y461333D02*
X1201100Y466500D01*
G01X1198100D02*
X1197600Y466333D01*
X1197350Y466083D01*
X1197183Y465583D01*
X1197350Y465083D01*
X1197600Y464833D01*
X1198100Y464667D01*
X1198600Y464833D01*
X1198850Y465083D01*
X1199017Y465583D01*
X1198850Y466083D01*
X1198600Y466333D01*
X1198100Y466500D01*
G01X1201100Y463167D02*
X1200600Y463000D01*
X1200350Y462750D01*
X1200183Y462250D01*
X1200350Y461750D01*
X1200600Y461500D01*
X1201100Y461333D01*
X1201600Y461500D01*
X1201850Y461750D01*
X1202017Y462250D01*
X1201850Y462750D01*
X1201600Y463000D01*
X1201100Y463167D01*
G01X1209550Y462083D02*
X1209967Y461750D01*
X1210550Y461500D01*
X1211050D01*
X1211550Y461667D01*
X1211883Y461917D01*
X1212050Y462250D01*
X1211967Y462750D01*
X1211633Y463000D01*
X1210133Y463500D01*
X1209800Y464083D01*
X1209967Y464500D01*
X1210300Y464750D01*
X1210800Y464833D01*
X1211300Y464750D01*
X1211800Y464500D01*
G01X1216400Y461500D02*
X1215900Y461583D01*
X1215400Y461917D01*
X1215067Y462500D01*
X1214900Y463167D01*
X1215067Y463833D01*
X1215400Y464417D01*
X1215900Y464750D01*
X1216400Y464833D01*
X1216900Y464750D01*
X1217400Y464417D01*
X1217733Y463833D01*
X1217817Y463167D01*
X1217733Y462500D01*
X1217400Y461917D01*
X1216900Y461583D01*
X1216400Y461500D01*
G01X1222000D02*
Y466500D01*
G01X1229100D02*
Y461500D01*
G01Y462250D02*
X1228767Y461833D01*
X1228267Y461583D01*
X1227683Y461500D01*
X1227017Y461667D01*
X1226517Y462083D01*
X1226183Y462583D01*
X1226100Y463167D01*
X1226183Y463750D01*
X1226517Y464250D01*
X1227017Y464667D01*
X1227683Y464833D01*
X1228267Y464750D01*
X1228683Y464583D01*
X1229100Y464250D01*
G01X1231950Y463750D02*
X1234617D01*
X1234367Y464333D01*
X1233950Y464667D01*
X1233367Y464833D01*
X1232783Y464750D01*
X1232283Y464500D01*
X1231950Y463917D01*
X1231783Y463417D01*
Y462917D01*
X1231950Y462417D01*
X1232367Y461917D01*
X1232867Y461583D01*
X1233450Y461500D01*
X1234033Y461667D01*
X1234617Y462167D01*
G01X1237633Y461500D02*
Y464833D01*
G01Y464167D02*
X1238050Y464500D01*
X1238467Y464750D01*
X1239050Y464833D01*
X1239467Y464750D01*
X1239967Y464500D01*
G01X1247500Y461500D02*
Y464833D01*
G01Y463917D02*
X1247750Y464333D01*
X1248167Y464667D01*
X1248750Y464833D01*
X1249333Y464667D01*
X1249750Y464333D01*
X1250000Y463917D01*
Y461500D01*
G01Y463917D02*
X1250250Y464333D01*
X1250667Y464667D01*
X1251250Y464833D01*
X1251833Y464667D01*
X1252250Y464333D01*
X1252500Y463833D01*
Y461500D01*
G01X1257100D02*
Y464833D01*
G01Y464250D02*
X1256767Y464583D01*
X1256267Y464750D01*
X1255683Y464833D01*
X1255100Y464667D01*
X1254600Y464333D01*
X1254267Y463833D01*
X1254100Y463167D01*
X1254267Y462500D01*
X1254600Y462000D01*
X1255100Y461667D01*
X1255683Y461500D01*
X1256267Y461583D01*
X1256767Y461833D01*
X1257100Y462167D01*
G01X1259950Y462083D02*
X1260367Y461750D01*
X1260950Y461500D01*
X1261450D01*
X1261950Y461667D01*
X1262283Y461917D01*
X1262450Y462250D01*
X1262367Y462750D01*
X1262033Y463000D01*
X1260533Y463500D01*
X1260200Y464083D01*
X1260367Y464500D01*
X1260700Y464750D01*
X1261200Y464833D01*
X1261700Y464750D01*
X1262200Y464500D01*
G01X1265383Y461500D02*
Y466500D01*
G01X1268050Y464833D02*
X1265383Y462917D01*
G01X1266467Y463667D02*
X1268217Y461500D01*
G01X1046500Y485833D02*
X1048000Y482500D01*
X1049500Y485833D01*
G01X1053600D02*
Y482500D01*
G01Y487167D02*
X1053433Y487250D01*
Y487417D01*
X1053600Y487500D01*
X1053767Y487417D01*
Y487250D01*
X1053600Y487167D01*
G01X1060700Y482500D02*
Y485833D01*
G01Y485250D02*
X1060367Y485583D01*
X1059867Y485750D01*
X1059283Y485833D01*
X1058700Y485667D01*
X1058200Y485333D01*
X1057867Y484833D01*
X1057700Y484167D01*
X1057867Y483500D01*
X1058200Y483000D01*
X1058700Y482667D01*
X1059283Y482500D01*
X1059867Y482583D01*
X1060367Y482833D01*
X1060700Y483167D01*
G01X1069150Y483083D02*
X1069567Y482750D01*
X1070150Y482500D01*
X1070650D01*
X1071150Y482667D01*
X1071483Y482917D01*
X1071650Y483250D01*
X1071567Y483750D01*
X1071233Y484000D01*
X1069733Y484500D01*
X1069400Y485083D01*
X1069567Y485500D01*
X1069900Y485750D01*
X1070400Y485833D01*
X1070900Y485750D01*
X1071400Y485500D01*
G01X1074583Y482500D02*
Y487500D01*
G01Y485083D02*
X1075000Y485500D01*
X1075417Y485750D01*
X1076083Y485833D01*
X1076583Y485750D01*
X1077167Y485417D01*
X1077417Y484917D01*
Y482500D01*
G01X1083100D02*
Y485833D01*
G01Y485250D02*
X1082767Y485583D01*
X1082267Y485750D01*
X1081683Y485833D01*
X1081100Y485667D01*
X1080600Y485333D01*
X1080267Y484833D01*
X1080100Y484167D01*
X1080267Y483500D01*
X1080600Y483000D01*
X1081100Y482667D01*
X1081683Y482500D01*
X1082267Y482583D01*
X1082767Y482833D01*
X1083100Y483167D01*
G01X1087200Y482500D02*
Y487500D01*
G01X1092800Y482500D02*
Y487500D01*
G01X1102500Y482500D02*
Y487500D01*
G01Y485000D02*
X1102917Y485500D01*
X1103417Y485750D01*
X1103917Y485833D01*
X1104667Y485667D01*
X1105167Y485333D01*
X1105500Y484750D01*
Y484083D01*
X1105333Y483417D01*
X1105000Y482917D01*
X1104417Y482583D01*
X1103917Y482500D01*
X1103417Y482583D01*
X1102917Y482833D01*
X1102500Y483250D01*
G01X1108350Y484750D02*
X1111017D01*
X1110767Y485333D01*
X1110350Y485667D01*
X1109767Y485833D01*
X1109183Y485750D01*
X1108683Y485500D01*
X1108350Y484917D01*
X1108183Y484417D01*
Y483917D01*
X1108350Y483417D01*
X1108767Y482917D01*
X1109267Y482583D01*
X1109850Y482500D01*
X1110433Y482667D01*
X1111017Y483167D01*
G01X1118717Y485833D02*
X1119717Y482500D01*
X1120800Y485833D01*
X1121883Y482500D01*
X1122883Y485833D01*
G01X1126400D02*
Y482500D01*
G01Y487167D02*
X1126233Y487250D01*
Y487417D01*
X1126400Y487500D01*
X1126567Y487417D01*
Y487250D01*
X1126400Y487167D01*
G01X1132000Y487500D02*
Y482500D01*
G01X1130833Y485833D02*
X1133167D01*
G01X1136183Y482500D02*
Y487500D01*
G01Y485083D02*
X1136600Y485500D01*
X1137017Y485750D01*
X1137683Y485833D01*
X1138183Y485750D01*
X1138767Y485417D01*
X1139017Y484917D01*
Y482500D01*
G01X1150467D02*
X1147133Y484167D01*
X1150467Y485833D01*
G01X1160000Y482500D02*
X1160583Y482583D01*
X1161250Y482833D01*
X1161667Y483250D01*
X1161833Y483833D01*
X1161667Y484417D01*
X1161167Y484917D01*
X1160417Y485167D01*
X1159583D01*
X1159083Y485333D01*
X1158667Y485750D01*
X1158500Y486333D01*
X1158750Y486917D01*
X1159333Y487333D01*
X1160000Y487500D01*
X1160667Y487333D01*
X1161250Y486917D01*
X1161500Y486333D01*
X1161333Y485750D01*
X1160917Y485333D01*
X1160417Y485167D01*
X1159583D01*
X1158833Y484917D01*
X1158333Y484417D01*
X1158167Y483833D01*
X1158333Y483250D01*
X1158750Y482833D01*
X1159417Y482583D01*
X1160000Y482500D01*
G01X1165600Y487500D02*
X1164933Y487333D01*
X1164433Y486917D01*
X1164100Y486417D01*
X1163850Y485750D01*
X1163767Y485000D01*
X1163850Y484250D01*
X1164100Y483583D01*
X1164433Y483083D01*
X1164933Y482667D01*
X1165600Y482500D01*
X1166267Y482667D01*
X1166767Y483083D01*
X1167100Y483583D01*
X1167350Y484250D01*
X1167433Y485000D01*
X1167350Y485750D01*
X1167100Y486417D01*
X1166767Y486917D01*
X1166267Y487333D01*
X1165600Y487500D01*
G01X1175300Y482333D02*
X1178300Y487500D01*
G01X1175300D02*
X1174800Y487333D01*
X1174550Y487083D01*
X1174383Y486583D01*
X1174550Y486083D01*
X1174800Y485833D01*
X1175300Y485667D01*
X1175800Y485833D01*
X1176050Y486083D01*
X1176217Y486583D01*
X1176050Y487083D01*
X1175800Y487333D01*
X1175300Y487500D01*
G01X1178300Y484167D02*
X1177800Y484000D01*
X1177550Y483750D01*
X1177383Y483250D01*
X1177550Y482750D01*
X1177800Y482500D01*
X1178300Y482333D01*
X1178800Y482500D01*
X1179050Y482750D01*
X1179217Y483250D01*
X1179050Y483750D01*
X1178800Y484000D01*
X1178300Y484167D01*
G01X1186750Y483083D02*
X1187167Y482750D01*
X1187750Y482500D01*
X1188250D01*
X1188750Y482667D01*
X1189083Y482917D01*
X1189250Y483250D01*
X1189167Y483750D01*
X1188833Y484000D01*
X1187333Y484500D01*
X1187000Y485083D01*
X1187167Y485500D01*
X1187500Y485750D01*
X1188000Y485833D01*
X1188500Y485750D01*
X1189000Y485500D01*
G01X1193600Y482500D02*
X1193100Y482583D01*
X1192600Y482917D01*
X1192267Y483500D01*
X1192100Y484167D01*
X1192267Y484833D01*
X1192600Y485417D01*
X1193100Y485750D01*
X1193600Y485833D01*
X1194100Y485750D01*
X1194600Y485417D01*
X1194933Y484833D01*
X1195017Y484167D01*
X1194933Y483500D01*
X1194600Y482917D01*
X1194100Y482583D01*
X1193600Y482500D01*
G01X1199200D02*
Y487500D01*
G01X1206300D02*
Y482500D01*
G01Y483250D02*
X1205967Y482833D01*
X1205467Y482583D01*
X1204883Y482500D01*
X1204217Y482667D01*
X1203717Y483083D01*
X1203383Y483583D01*
X1203300Y484167D01*
X1203383Y484750D01*
X1203717Y485250D01*
X1204217Y485667D01*
X1204883Y485833D01*
X1205467Y485750D01*
X1205883Y485583D01*
X1206300Y485250D01*
G01X1209150Y484750D02*
X1211817D01*
X1211567Y485333D01*
X1211150Y485667D01*
X1210567Y485833D01*
X1209983Y485750D01*
X1209483Y485500D01*
X1209150Y484917D01*
X1208983Y484417D01*
Y483917D01*
X1209150Y483417D01*
X1209567Y482917D01*
X1210067Y482583D01*
X1210650Y482500D01*
X1211233Y482667D01*
X1211817Y483167D01*
G01X1214833Y482500D02*
Y485833D01*
G01Y485167D02*
X1215250Y485500D01*
X1215667Y485750D01*
X1216250Y485833D01*
X1216667Y485750D01*
X1217167Y485500D01*
G01X1224700Y482500D02*
Y485833D01*
G01Y484917D02*
X1224950Y485333D01*
X1225367Y485667D01*
X1225950Y485833D01*
X1226533Y485667D01*
X1226950Y485333D01*
X1227200Y484917D01*
Y482500D01*
G01Y484917D02*
X1227450Y485333D01*
X1227867Y485667D01*
X1228450Y485833D01*
X1229033Y485667D01*
X1229450Y485333D01*
X1229700Y484833D01*
Y482500D01*
G01X1234300D02*
Y485833D01*
G01Y485250D02*
X1233967Y485583D01*
X1233467Y485750D01*
X1232883Y485833D01*
X1232300Y485667D01*
X1231800Y485333D01*
X1231467Y484833D01*
X1231300Y484167D01*
X1231467Y483500D01*
X1231800Y483000D01*
X1232300Y482667D01*
X1232883Y482500D01*
X1233467Y482583D01*
X1233967Y482833D01*
X1234300Y483167D01*
G01X1237150Y483083D02*
X1237567Y482750D01*
X1238150Y482500D01*
X1238650D01*
X1239150Y482667D01*
X1239483Y482917D01*
X1239650Y483250D01*
X1239567Y483750D01*
X1239233Y484000D01*
X1237733Y484500D01*
X1237400Y485083D01*
X1237567Y485500D01*
X1237900Y485750D01*
X1238400Y485833D01*
X1238900Y485750D01*
X1239400Y485500D01*
G01X1242583Y482500D02*
Y487500D01*
G01X1245250Y485833D02*
X1242583Y483917D01*
G01X1243667Y484667D02*
X1245417Y482500D01*
G01X1035500Y491500D02*
Y496500D01*
G01Y494000D02*
X1035917Y494500D01*
X1036417Y494750D01*
X1036917Y494833D01*
X1037667Y494667D01*
X1038167Y494333D01*
X1038500Y493750D01*
Y493083D01*
X1038333Y492417D01*
X1038000Y491917D01*
X1037417Y491583D01*
X1036917Y491500D01*
X1036417Y491583D01*
X1035917Y491833D01*
X1035500Y492250D01*
G01X1042600Y491333D02*
X1042433Y491417D01*
Y491583D01*
X1042600Y491667D01*
X1042767Y491583D01*
Y491417D01*
X1042600Y491333D01*
G01X1048867Y494167D02*
X1049200Y494417D01*
X1049450Y494833D01*
X1049617Y495417D01*
X1049450Y495917D01*
X1049117Y496250D01*
X1048533Y496500D01*
X1046283D01*
Y491500D01*
X1049033D01*
X1049617Y491833D01*
X1049950Y492333D01*
X1050117Y492917D01*
X1049950Y493500D01*
X1049450Y494000D01*
X1048867Y494167D01*
X1046283D01*
G01X1053800Y491500D02*
X1053300Y491583D01*
X1052800Y491917D01*
X1052467Y492500D01*
X1052300Y493167D01*
X1052467Y493833D01*
X1052800Y494417D01*
X1053300Y494750D01*
X1053800Y494833D01*
X1054300Y494750D01*
X1054800Y494417D01*
X1055133Y493833D01*
X1055217Y493167D01*
X1055133Y492500D01*
X1054800Y491917D01*
X1054300Y491583D01*
X1053800Y491500D01*
G01X1060900D02*
Y494833D01*
G01Y494250D02*
X1060567Y494583D01*
X1060067Y494750D01*
X1059483Y494833D01*
X1058900Y494667D01*
X1058400Y494333D01*
X1058067Y493833D01*
X1057900Y493167D01*
X1058067Y492500D01*
X1058400Y492000D01*
X1058900Y491667D01*
X1059483Y491500D01*
X1060067Y491583D01*
X1060567Y491833D01*
X1060900Y492167D01*
G01X1063833Y491500D02*
Y494833D01*
G01Y494167D02*
X1064250Y494500D01*
X1064667Y494750D01*
X1065250Y494833D01*
X1065667Y494750D01*
X1066167Y494500D01*
G01X1072100Y496500D02*
Y491500D01*
G01Y492250D02*
X1071767Y491833D01*
X1071267Y491583D01*
X1070683Y491500D01*
X1070017Y491667D01*
X1069517Y492083D01*
X1069183Y492583D01*
X1069100Y493167D01*
X1069183Y493750D01*
X1069517Y494250D01*
X1070017Y494667D01*
X1070683Y494833D01*
X1071267Y494750D01*
X1071683Y494583D01*
X1072100Y494250D01*
G01X1081800Y496500D02*
Y491500D01*
G01X1080633Y494833D02*
X1082967D01*
G01X1085983Y491500D02*
Y496500D01*
G01Y494083D02*
X1086400Y494500D01*
X1086817Y494750D01*
X1087483Y494833D01*
X1087983Y494750D01*
X1088567Y494417D01*
X1088817Y493917D01*
Y491500D01*
G01X1093000Y494833D02*
Y491500D01*
G01Y496167D02*
X1092833Y496250D01*
Y496417D01*
X1093000Y496500D01*
X1093167Y496417D01*
Y496250D01*
X1093000Y496167D01*
G01X1099933Y494417D02*
X1099350Y494750D01*
X1098850Y494833D01*
X1098183Y494667D01*
X1097683Y494333D01*
X1097350Y493750D01*
X1097267Y493167D01*
X1097350Y492583D01*
X1097683Y492083D01*
X1098183Y491667D01*
X1098850Y491500D01*
X1099433Y491667D01*
X1099933Y492000D01*
G01X1102783Y491500D02*
Y496500D01*
G01X1105450Y494833D02*
X1102783Y492917D01*
G01X1103867Y493667D02*
X1105617Y491500D01*
G01X1108383D02*
Y494833D01*
G01Y494000D02*
X1108717Y494417D01*
X1109217Y494750D01*
X1109883Y494833D01*
X1110467Y494750D01*
X1110967Y494417D01*
X1111217Y493833D01*
Y491500D01*
G01X1114150Y493750D02*
X1116817D01*
X1116567Y494333D01*
X1116150Y494667D01*
X1115567Y494833D01*
X1114983Y494750D01*
X1114483Y494500D01*
X1114150Y493917D01*
X1113983Y493417D01*
Y492917D01*
X1114150Y492417D01*
X1114567Y491917D01*
X1115067Y491583D01*
X1115650Y491500D01*
X1116233Y491667D01*
X1116817Y492167D01*
G01X1119750Y492083D02*
X1120167Y491750D01*
X1120750Y491500D01*
X1121250D01*
X1121750Y491667D01*
X1122083Y491917D01*
X1122250Y492250D01*
X1122167Y492750D01*
X1121833Y493000D01*
X1120333Y493500D01*
X1120000Y494083D01*
X1120167Y494500D01*
X1120500Y494750D01*
X1121000Y494833D01*
X1121500Y494750D01*
X1122000Y494500D01*
G01X1125350Y492083D02*
X1125767Y491750D01*
X1126350Y491500D01*
X1126850D01*
X1127350Y491667D01*
X1127683Y491917D01*
X1127850Y492250D01*
X1127767Y492750D01*
X1127433Y493000D01*
X1125933Y493500D01*
X1125600Y494083D01*
X1125767Y494500D01*
X1126100Y494750D01*
X1126600Y494833D01*
X1127100Y494750D01*
X1127600Y494500D01*
G01X1139467Y491500D02*
X1136133Y493167D01*
X1139467Y494833D01*
G01X1149000Y496500D02*
X1148333Y496333D01*
X1147833Y495917D01*
X1147500Y495417D01*
X1147250Y494750D01*
X1147167Y494000D01*
X1147250Y493250D01*
X1147500Y492583D01*
X1147833Y492083D01*
X1148333Y491667D01*
X1149000Y491500D01*
X1149667Y491667D01*
X1150167Y492083D01*
X1150500Y492583D01*
X1150750Y493250D01*
X1150833Y494000D01*
X1150750Y494750D01*
X1150500Y495417D01*
X1150167Y495917D01*
X1149667Y496333D01*
X1149000Y496500D01*
G01X1154600Y491333D02*
X1154433Y491417D01*
Y491583D01*
X1154600Y491667D01*
X1154767Y491583D01*
Y491417D01*
X1154600Y491333D01*
G01X1158783Y492083D02*
X1159367Y491667D01*
X1160033Y491500D01*
X1160700Y491667D01*
X1161283Y492167D01*
X1161700Y492917D01*
X1161867Y493667D01*
Y494583D01*
X1161700Y495333D01*
X1161283Y496000D01*
X1160783Y496333D01*
X1160200Y496500D01*
X1159533Y496333D01*
X1159033Y496000D01*
X1158700Y495500D01*
X1158533Y494833D01*
X1158700Y494250D01*
X1159117Y493667D01*
X1159617Y493333D01*
X1160200Y493250D01*
X1160867Y493417D01*
X1161367Y493833D01*
X1161867Y494583D01*
G01X1163300Y491500D02*
Y494833D01*
G01Y493917D02*
X1163550Y494333D01*
X1163967Y494667D01*
X1164550Y494833D01*
X1165133Y494667D01*
X1165550Y494333D01*
X1165800Y493917D01*
Y491500D01*
G01Y493917D02*
X1166050Y494333D01*
X1166467Y494667D01*
X1167050Y494833D01*
X1167633Y494667D01*
X1168050Y494333D01*
X1168300Y493833D01*
Y491500D01*
G01X1168900D02*
Y494833D01*
G01Y493917D02*
X1169150Y494333D01*
X1169567Y494667D01*
X1170150Y494833D01*
X1170733Y494667D01*
X1171150Y494333D01*
X1171400Y493917D01*
Y491500D01*
G01Y493917D02*
X1171650Y494333D01*
X1172067Y494667D01*
X1172650Y494833D01*
X1173233Y494667D01*
X1173650Y494333D01*
X1173900Y493833D01*
Y491500D01*
G01X1177000Y491333D02*
X1176833Y491417D01*
Y491583D01*
X1177000Y491667D01*
X1177167Y491583D01*
Y491417D01*
X1177000Y491333D01*
G01Y493583D02*
X1176833Y493667D01*
Y493833D01*
X1177000Y493917D01*
X1177167Y493833D01*
Y493667D01*
X1177000Y493583D01*
G01X1045500Y504833D02*
X1047000Y501500D01*
X1048500Y504833D01*
G01X1052600D02*
Y501500D01*
G01Y506167D02*
X1052433Y506250D01*
Y506417D01*
X1052600Y506500D01*
X1052767Y506417D01*
Y506250D01*
X1052600Y506167D01*
G01X1059700Y501500D02*
Y504833D01*
G01Y504250D02*
X1059367Y504583D01*
X1058867Y504750D01*
X1058283Y504833D01*
X1057700Y504667D01*
X1057200Y504333D01*
X1056867Y503833D01*
X1056700Y503167D01*
X1056867Y502500D01*
X1057200Y502000D01*
X1057700Y501667D01*
X1058283Y501500D01*
X1058867Y501583D01*
X1059367Y501833D01*
X1059700Y502167D01*
G01X1068150Y502083D02*
X1068567Y501750D01*
X1069150Y501500D01*
X1069650D01*
X1070150Y501667D01*
X1070483Y501917D01*
X1070650Y502250D01*
X1070567Y502750D01*
X1070233Y503000D01*
X1068733Y503500D01*
X1068400Y504083D01*
X1068567Y504500D01*
X1068900Y504750D01*
X1069400Y504833D01*
X1069900Y504750D01*
X1070400Y504500D01*
G01X1073583Y501500D02*
Y506500D01*
G01Y504083D02*
X1074000Y504500D01*
X1074417Y504750D01*
X1075083Y504833D01*
X1075583Y504750D01*
X1076167Y504417D01*
X1076417Y503917D01*
Y501500D01*
G01X1082100D02*
Y504833D01*
G01Y504250D02*
X1081767Y504583D01*
X1081267Y504750D01*
X1080683Y504833D01*
X1080100Y504667D01*
X1079600Y504333D01*
X1079267Y503833D01*
X1079100Y503167D01*
X1079267Y502500D01*
X1079600Y502000D01*
X1080100Y501667D01*
X1080683Y501500D01*
X1081267Y501583D01*
X1081767Y501833D01*
X1082100Y502167D01*
G01X1086200Y501500D02*
Y506500D01*
G01X1091800Y501500D02*
Y506500D01*
G01X1101500Y501500D02*
Y506500D01*
G01Y504000D02*
X1101917Y504500D01*
X1102417Y504750D01*
X1102917Y504833D01*
X1103667Y504667D01*
X1104167Y504333D01*
X1104500Y503750D01*
Y503083D01*
X1104333Y502417D01*
X1104000Y501917D01*
X1103417Y501583D01*
X1102917Y501500D01*
X1102417Y501583D01*
X1101917Y501833D01*
X1101500Y502250D01*
G01X1107350Y503750D02*
X1110017D01*
X1109767Y504333D01*
X1109350Y504667D01*
X1108767Y504833D01*
X1108183Y504750D01*
X1107683Y504500D01*
X1107350Y503917D01*
X1107183Y503417D01*
Y502917D01*
X1107350Y502417D01*
X1107767Y501917D01*
X1108267Y501583D01*
X1108850Y501500D01*
X1109433Y501667D01*
X1110017Y502167D01*
G01X1118300Y499833D02*
Y504833D01*
G01Y504083D02*
X1118717Y504500D01*
X1119133Y504750D01*
X1119800Y504833D01*
X1120383Y504750D01*
X1120967Y504333D01*
X1121217Y503750D01*
X1121300Y503167D01*
X1121217Y502583D01*
X1120967Y502000D01*
X1120467Y501667D01*
X1119800Y501500D01*
X1119217Y501583D01*
X1118633Y501833D01*
X1118300Y502167D01*
G01X1125400Y501500D02*
Y506500D01*
G01X1129583Y504833D02*
Y502500D01*
X1129917Y501917D01*
X1130417Y501583D01*
X1131000Y501500D01*
X1131583Y501583D01*
X1132083Y501917D01*
X1132417Y502500D01*
G01Y501500D02*
Y504833D01*
G01X1135433Y500250D02*
X1136017Y499917D01*
X1136683Y499833D01*
X1137267Y499917D01*
X1137767Y500333D01*
X1138100Y500917D01*
Y504833D01*
G01Y504167D02*
X1137767Y504500D01*
X1137267Y504750D01*
X1136683Y504833D01*
X1136017Y504667D01*
X1135600Y504333D01*
X1135267Y503750D01*
X1135100Y503167D01*
X1135183Y502667D01*
X1135517Y502083D01*
X1136017Y501667D01*
X1136683Y501500D01*
X1137183Y501583D01*
X1137767Y501917D01*
X1138100Y502250D01*
G01X1141033Y500250D02*
X1141617Y499917D01*
X1142283Y499833D01*
X1142867Y499917D01*
X1143367Y500333D01*
X1143700Y500917D01*
Y504833D01*
G01Y504167D02*
X1143367Y504500D01*
X1142867Y504750D01*
X1142283Y504833D01*
X1141617Y504667D01*
X1141200Y504333D01*
X1140867Y503750D01*
X1140700Y503167D01*
X1140783Y502667D01*
X1141117Y502083D01*
X1141617Y501667D01*
X1142283Y501500D01*
X1142783Y501583D01*
X1143367Y501917D01*
X1143700Y502250D01*
G01X1146550Y503750D02*
X1149217D01*
X1148967Y504333D01*
X1148550Y504667D01*
X1147967Y504833D01*
X1147383Y504750D01*
X1146883Y504500D01*
X1146550Y503917D01*
X1146383Y503417D01*
Y502917D01*
X1146550Y502417D01*
X1146967Y501917D01*
X1147467Y501583D01*
X1148050Y501500D01*
X1148633Y501667D01*
X1149217Y502167D01*
G01X1154900Y506500D02*
Y501500D01*
G01Y502250D02*
X1154567Y501833D01*
X1154067Y501583D01*
X1153483Y501500D01*
X1152817Y501667D01*
X1152317Y502083D01*
X1151983Y502583D01*
X1151900Y503167D01*
X1151983Y503750D01*
X1152317Y504250D01*
X1152817Y504667D01*
X1153483Y504833D01*
X1154067Y504750D01*
X1154483Y504583D01*
X1154900Y504250D01*
G01X1162517Y504833D02*
X1163517Y501500D01*
X1164600Y504833D01*
X1165683Y501500D01*
X1166683Y504833D01*
G01X1170200D02*
Y501500D01*
G01Y506167D02*
X1170033Y506250D01*
Y506417D01*
X1170200Y506500D01*
X1170367Y506417D01*
Y506250D01*
X1170200Y506167D01*
G01X1175800Y506500D02*
Y501500D01*
G01X1174633Y504833D02*
X1176967D01*
G01X1179983Y501500D02*
Y506500D01*
G01Y504083D02*
X1180400Y504500D01*
X1180817Y504750D01*
X1181483Y504833D01*
X1181983Y504750D01*
X1182567Y504417D01*
X1182817Y503917D01*
Y501500D01*
G01X1194267D02*
X1190933Y503167D01*
X1194267Y504833D01*
G01X1201967Y502250D02*
X1202467Y501833D01*
X1203050Y501583D01*
X1203800Y501500D01*
X1204550Y501667D01*
X1205133Y502000D01*
X1205550Y502583D01*
X1205633Y503250D01*
X1205467Y503917D01*
X1205050Y504333D01*
X1204467Y504667D01*
X1203883Y504750D01*
X1203300Y504667D01*
X1202550Y504333D01*
X1202800Y506500D01*
X1205050D01*
G01X1209400D02*
X1208733Y506333D01*
X1208233Y505917D01*
X1207900Y505417D01*
X1207650Y504750D01*
X1207567Y504000D01*
X1207650Y503250D01*
X1207900Y502583D01*
X1208233Y502083D01*
X1208733Y501667D01*
X1209400Y501500D01*
X1210067Y501667D01*
X1210567Y502083D01*
X1210900Y502583D01*
X1211150Y503250D01*
X1211233Y504000D01*
X1211150Y504750D01*
X1210900Y505417D01*
X1210567Y505917D01*
X1210067Y506333D01*
X1209400Y506500D01*
G01X1219100Y501333D02*
X1222100Y506500D01*
G01X1219100D02*
X1218600Y506333D01*
X1218350Y506083D01*
X1218183Y505583D01*
X1218350Y505083D01*
X1218600Y504833D01*
X1219100Y504667D01*
X1219600Y504833D01*
X1219850Y505083D01*
X1220017Y505583D01*
X1219850Y506083D01*
X1219600Y506333D01*
X1219100Y506500D01*
G01X1222100Y503167D02*
X1221600Y503000D01*
X1221350Y502750D01*
X1221183Y502250D01*
X1221350Y501750D01*
X1221600Y501500D01*
X1222100Y501333D01*
X1222600Y501500D01*
X1222850Y501750D01*
X1223017Y502250D01*
X1222850Y502750D01*
X1222600Y503000D01*
X1222100Y503167D01*
G01X1230550Y502083D02*
X1230967Y501750D01*
X1231550Y501500D01*
X1232050D01*
X1232550Y501667D01*
X1232883Y501917D01*
X1233050Y502250D01*
X1232967Y502750D01*
X1232633Y503000D01*
X1231133Y503500D01*
X1230800Y504083D01*
X1230967Y504500D01*
X1231300Y504750D01*
X1231800Y504833D01*
X1232300Y504750D01*
X1232800Y504500D01*
G01X1237400Y501500D02*
X1236900Y501583D01*
X1236400Y501917D01*
X1236067Y502500D01*
X1235900Y503167D01*
X1236067Y503833D01*
X1236400Y504417D01*
X1236900Y504750D01*
X1237400Y504833D01*
X1237900Y504750D01*
X1238400Y504417D01*
X1238733Y503833D01*
X1238817Y503167D01*
X1238733Y502500D01*
X1238400Y501917D01*
X1237900Y501583D01*
X1237400Y501500D01*
G01X1243000D02*
Y506500D01*
G01X1250100D02*
Y501500D01*
G01Y502250D02*
X1249767Y501833D01*
X1249267Y501583D01*
X1248683Y501500D01*
X1248017Y501667D01*
X1247517Y502083D01*
X1247183Y502583D01*
X1247100Y503167D01*
X1247183Y503750D01*
X1247517Y504250D01*
X1248017Y504667D01*
X1248683Y504833D01*
X1249267Y504750D01*
X1249683Y504583D01*
X1250100Y504250D01*
G01X1252950Y503750D02*
X1255617D01*
X1255367Y504333D01*
X1254950Y504667D01*
X1254367Y504833D01*
X1253783Y504750D01*
X1253283Y504500D01*
X1252950Y503917D01*
X1252783Y503417D01*
Y502917D01*
X1252950Y502417D01*
X1253367Y501917D01*
X1253867Y501583D01*
X1254450Y501500D01*
X1255033Y501667D01*
X1255617Y502167D01*
G01X1258633Y501500D02*
Y504833D01*
G01Y504167D02*
X1259050Y504500D01*
X1259467Y504750D01*
X1260050Y504833D01*
X1260467Y504750D01*
X1260967Y504500D01*
G01X1268500Y501500D02*
Y504833D01*
G01Y503917D02*
X1268750Y504333D01*
X1269167Y504667D01*
X1269750Y504833D01*
X1270333Y504667D01*
X1270750Y504333D01*
X1271000Y503917D01*
Y501500D01*
G01Y503917D02*
X1271250Y504333D01*
X1271667Y504667D01*
X1272250Y504833D01*
X1272833Y504667D01*
X1273250Y504333D01*
X1273500Y503833D01*
Y501500D01*
G01X1278100D02*
Y504833D01*
G01Y504250D02*
X1277767Y504583D01*
X1277267Y504750D01*
X1276683Y504833D01*
X1276100Y504667D01*
X1275600Y504333D01*
X1275267Y503833D01*
X1275100Y503167D01*
X1275267Y502500D01*
X1275600Y502000D01*
X1276100Y501667D01*
X1276683Y501500D01*
X1277267Y501583D01*
X1277767Y501833D01*
X1278100Y502167D01*
G01X1280950Y502083D02*
X1281367Y501750D01*
X1281950Y501500D01*
X1282450D01*
X1282950Y501667D01*
X1283283Y501917D01*
X1283450Y502250D01*
X1283367Y502750D01*
X1283033Y503000D01*
X1281533Y503500D01*
X1281200Y504083D01*
X1281367Y504500D01*
X1281700Y504750D01*
X1282200Y504833D01*
X1282700Y504750D01*
X1283200Y504500D01*
G01X1286383Y501500D02*
Y506500D01*
G01X1289050Y504833D02*
X1286383Y502917D01*
G01X1287467Y503667D02*
X1289217Y501500D01*
G01X1293233Y500583D02*
X1293567Y501667D01*
G01X1023000Y424000D02*
Y429000D01*
X1022000Y428000D01*
G01Y424000D02*
X1024000D01*
G01X1028600Y423833D02*
X1028433Y423917D01*
Y424083D01*
X1028600Y424167D01*
X1028767Y424083D01*
Y423917D01*
X1028600Y423833D01*
G01X1032117Y429000D02*
X1034200Y424000D01*
X1036283Y429000D01*
G01X1039800Y427333D02*
Y424000D01*
G01Y428667D02*
X1039633Y428750D01*
Y428917D01*
X1039800Y429000D01*
X1039967Y428917D01*
Y428750D01*
X1039800Y428667D01*
G01X1046900Y424000D02*
Y427333D01*
G01Y426750D02*
X1046567Y427083D01*
X1046067Y427250D01*
X1045483Y427333D01*
X1044900Y427167D01*
X1044400Y426833D01*
X1044067Y426333D01*
X1043900Y425667D01*
X1044067Y425000D01*
X1044400Y424500D01*
X1044900Y424167D01*
X1045483Y424000D01*
X1046067Y424083D01*
X1046567Y424333D01*
X1046900Y424667D01*
G01X1055350Y424583D02*
X1055767Y424250D01*
X1056350Y424000D01*
X1056850D01*
X1057350Y424167D01*
X1057683Y424417D01*
X1057850Y424750D01*
X1057767Y425250D01*
X1057433Y425500D01*
X1055933Y426000D01*
X1055600Y426583D01*
X1055767Y427000D01*
X1056100Y427250D01*
X1056600Y427333D01*
X1057100Y427250D01*
X1057600Y427000D01*
G01X1060783Y424000D02*
Y429000D01*
G01Y426583D02*
X1061200Y427000D01*
X1061617Y427250D01*
X1062283Y427333D01*
X1062783Y427250D01*
X1063367Y426917D01*
X1063617Y426417D01*
Y424000D01*
G01X1067800D02*
X1067300Y424083D01*
X1066800Y424417D01*
X1066467Y425000D01*
X1066300Y425667D01*
X1066467Y426333D01*
X1066800Y426917D01*
X1067300Y427250D01*
X1067800Y427333D01*
X1068300Y427250D01*
X1068800Y426917D01*
X1069133Y426333D01*
X1069217Y425667D01*
X1069133Y425000D01*
X1068800Y424417D01*
X1068300Y424083D01*
X1067800Y424000D01*
G01X1071983Y427333D02*
Y425000D01*
X1072317Y424417D01*
X1072817Y424083D01*
X1073400Y424000D01*
X1073983Y424083D01*
X1074483Y424417D01*
X1074817Y425000D01*
G01Y424000D02*
Y427333D01*
G01X1079000Y424000D02*
Y429000D01*
G01X1086100D02*
Y424000D01*
G01Y424750D02*
X1085767Y424333D01*
X1085267Y424083D01*
X1084683Y424000D01*
X1084017Y424167D01*
X1083517Y424583D01*
X1083183Y425083D01*
X1083100Y425667D01*
X1083183Y426250D01*
X1083517Y426750D01*
X1084017Y427167D01*
X1084683Y427333D01*
X1085267Y427250D01*
X1085683Y427083D01*
X1086100Y426750D01*
G01X1094300Y424000D02*
Y429000D01*
G01Y426500D02*
X1094717Y427000D01*
X1095217Y427250D01*
X1095717Y427333D01*
X1096467Y427167D01*
X1096967Y426833D01*
X1097300Y426250D01*
Y425583D01*
X1097133Y424917D01*
X1096800Y424417D01*
X1096217Y424083D01*
X1095717Y424000D01*
X1095217Y424083D01*
X1094717Y424333D01*
X1094300Y424750D01*
G01X1100150Y426250D02*
X1102817D01*
X1102567Y426833D01*
X1102150Y427167D01*
X1101567Y427333D01*
X1100983Y427250D01*
X1100483Y427000D01*
X1100150Y426417D01*
X1099983Y425917D01*
Y425417D01*
X1100150Y424917D01*
X1100567Y424417D01*
X1101067Y424083D01*
X1101650Y424000D01*
X1102233Y424167D01*
X1102817Y424667D01*
G01X1111100Y422333D02*
Y427333D01*
G01Y426583D02*
X1111517Y427000D01*
X1111933Y427250D01*
X1112600Y427333D01*
X1113183Y427250D01*
X1113767Y426833D01*
X1114017Y426250D01*
X1114100Y425667D01*
X1114017Y425083D01*
X1113767Y424500D01*
X1113267Y424167D01*
X1112600Y424000D01*
X1112017Y424083D01*
X1111433Y424333D01*
X1111100Y424667D01*
G01X1118200Y424000D02*
Y429000D01*
G01X1122383Y427333D02*
Y425000D01*
X1122717Y424417D01*
X1123217Y424083D01*
X1123800Y424000D01*
X1124383Y424083D01*
X1124883Y424417D01*
X1125217Y425000D01*
G01Y424000D02*
Y427333D01*
G01X1128233Y422750D02*
X1128817Y422417D01*
X1129483Y422333D01*
X1130067Y422417D01*
X1130567Y422833D01*
X1130900Y423417D01*
Y427333D01*
G01Y426667D02*
X1130567Y427000D01*
X1130067Y427250D01*
X1129483Y427333D01*
X1128817Y427167D01*
X1128400Y426833D01*
X1128067Y426250D01*
X1127900Y425667D01*
X1127983Y425167D01*
X1128317Y424583D01*
X1128817Y424167D01*
X1129483Y424000D01*
X1129983Y424083D01*
X1130567Y424417D01*
X1130900Y424750D01*
G01X1133833Y422750D02*
X1134417Y422417D01*
X1135083Y422333D01*
X1135667Y422417D01*
X1136167Y422833D01*
X1136500Y423417D01*
Y427333D01*
G01Y426667D02*
X1136167Y427000D01*
X1135667Y427250D01*
X1135083Y427333D01*
X1134417Y427167D01*
X1134000Y426833D01*
X1133667Y426250D01*
X1133500Y425667D01*
X1133583Y425167D01*
X1133917Y424583D01*
X1134417Y424167D01*
X1135083Y424000D01*
X1135583Y424083D01*
X1136167Y424417D01*
X1136500Y424750D01*
G01X1139350Y426250D02*
X1142017D01*
X1141767Y426833D01*
X1141350Y427167D01*
X1140767Y427333D01*
X1140183Y427250D01*
X1139683Y427000D01*
X1139350Y426417D01*
X1139183Y425917D01*
Y425417D01*
X1139350Y424917D01*
X1139767Y424417D01*
X1140267Y424083D01*
X1140850Y424000D01*
X1141433Y424167D01*
X1142017Y424667D01*
G01X1147700Y429000D02*
Y424000D01*
G01Y424750D02*
X1147367Y424333D01*
X1146867Y424083D01*
X1146283Y424000D01*
X1145617Y424167D01*
X1145117Y424583D01*
X1144783Y425083D01*
X1144700Y425667D01*
X1144783Y426250D01*
X1145117Y426750D01*
X1145617Y427167D01*
X1146283Y427333D01*
X1146867Y427250D01*
X1147283Y427083D01*
X1147700Y426750D01*
G01X1155317Y427333D02*
X1156317Y424000D01*
X1157400Y427333D01*
X1158483Y424000D01*
X1159483Y427333D01*
G01X1163000D02*
Y424000D01*
G01Y428667D02*
X1162833Y428750D01*
Y428917D01*
X1163000Y429000D01*
X1163167Y428917D01*
Y428750D01*
X1163000Y428667D01*
G01X1168600Y429000D02*
Y424000D01*
G01X1167433Y427333D02*
X1169767D01*
G01X1172783Y424000D02*
Y429000D01*
G01Y426583D02*
X1173200Y427000D01*
X1173617Y427250D01*
X1174283Y427333D01*
X1174783Y427250D01*
X1175367Y426917D01*
X1175617Y426417D01*
Y424000D01*
G01X1183733D02*
X1187067Y425667D01*
X1183733Y427333D01*
G01X1189583Y424583D02*
X1190167Y424167D01*
X1190833Y424000D01*
X1191500Y424167D01*
X1192083Y424667D01*
X1192500Y425417D01*
X1192667Y426167D01*
Y427083D01*
X1192500Y427833D01*
X1192083Y428500D01*
X1191583Y428833D01*
X1191000Y429000D01*
X1190333Y428833D01*
X1189833Y428500D01*
X1189500Y428000D01*
X1189333Y427333D01*
X1189500Y426750D01*
X1189917Y426167D01*
X1190417Y425833D01*
X1191000Y425750D01*
X1191667Y425917D01*
X1192167Y426333D01*
X1192667Y427083D01*
G01X1196600Y429000D02*
X1195933Y428833D01*
X1195433Y428417D01*
X1195100Y427917D01*
X1194850Y427250D01*
X1194767Y426500D01*
X1194850Y425750D01*
X1195100Y425083D01*
X1195433Y424583D01*
X1195933Y424167D01*
X1196600Y424000D01*
X1197267Y424167D01*
X1197767Y424583D01*
X1198100Y425083D01*
X1198350Y425750D01*
X1198433Y426500D01*
X1198350Y427250D01*
X1198100Y427917D01*
X1197767Y428417D01*
X1197267Y428833D01*
X1196600Y429000D01*
G01X1200700Y423833D02*
X1203700Y429000D01*
G01X1200700D02*
X1200200Y428833D01*
X1199950Y428583D01*
X1199783Y428083D01*
X1199950Y427583D01*
X1200200Y427333D01*
X1200700Y427167D01*
X1201200Y427333D01*
X1201450Y427583D01*
X1201617Y428083D01*
X1201450Y428583D01*
X1201200Y428833D01*
X1200700Y429000D01*
G01X1203700Y425667D02*
X1203200Y425500D01*
X1202950Y425250D01*
X1202783Y424750D01*
X1202950Y424250D01*
X1203200Y424000D01*
X1203700Y423833D01*
X1204200Y424000D01*
X1204450Y424250D01*
X1204617Y424750D01*
X1204450Y425250D01*
X1204200Y425500D01*
X1203700Y425667D01*
G01X1212233Y424000D02*
Y427333D01*
G01Y426667D02*
X1212650Y427000D01*
X1213067Y427250D01*
X1213650Y427333D01*
X1214067Y427250D01*
X1214567Y427000D01*
G01X1217750Y426250D02*
X1220417D01*
X1220167Y426833D01*
X1219750Y427167D01*
X1219167Y427333D01*
X1218583Y427250D01*
X1218083Y427000D01*
X1217750Y426417D01*
X1217583Y425917D01*
Y425417D01*
X1217750Y424917D01*
X1218167Y424417D01*
X1218667Y424083D01*
X1219250Y424000D01*
X1219833Y424167D01*
X1220417Y424667D01*
G01X1223350Y424583D02*
X1223767Y424250D01*
X1224350Y424000D01*
X1224850D01*
X1225350Y424167D01*
X1225683Y424417D01*
X1225850Y424750D01*
X1225767Y425250D01*
X1225433Y425500D01*
X1223933Y426000D01*
X1223600Y426583D01*
X1223767Y427000D01*
X1224100Y427250D01*
X1224600Y427333D01*
X1225100Y427250D01*
X1225600Y427000D01*
G01X1230200Y427333D02*
Y424000D01*
G01Y428667D02*
X1230033Y428750D01*
Y428917D01*
X1230200Y429000D01*
X1230367Y428917D01*
Y428750D01*
X1230200Y428667D01*
G01X1234383Y424000D02*
Y427333D01*
G01Y426500D02*
X1234717Y426917D01*
X1235217Y427250D01*
X1235883Y427333D01*
X1236467Y427250D01*
X1236967Y426917D01*
X1237217Y426333D01*
Y424000D01*
G01X1246417Y422500D02*
X1247583Y423667D01*
Y424833D01*
X1246417D01*
Y423667D01*
X1247583D01*
G01Y425667D02*
Y426833D01*
X1246417D01*
Y425667D01*
X1247583D01*
G01X1250767Y424000D02*
Y429000D01*
X1252433D01*
X1253100Y428750D01*
X1253600Y428417D01*
X1254017Y427917D01*
X1254350Y427333D01*
X1254433Y426500D01*
X1254350Y425667D01*
X1254017Y425083D01*
X1253600Y424583D01*
X1253100Y424250D01*
X1252433Y424000D01*
X1250767D01*
G01X1258200D02*
X1257700Y424083D01*
X1257200Y424417D01*
X1256867Y425000D01*
X1256700Y425667D01*
X1256867Y426333D01*
X1257200Y426917D01*
X1257700Y427250D01*
X1258200Y427333D01*
X1258700Y427250D01*
X1259200Y426917D01*
X1259533Y426333D01*
X1259617Y425667D01*
X1259533Y425000D01*
X1259200Y424417D01*
X1258700Y424083D01*
X1258200Y424000D01*
G01X1267983D02*
Y427333D01*
G01Y426500D02*
X1268317Y426917D01*
X1268817Y427250D01*
X1269483Y427333D01*
X1270067Y427250D01*
X1270567Y426917D01*
X1270817Y426333D01*
Y424000D01*
G01X1275000D02*
X1274500Y424083D01*
X1274000Y424417D01*
X1273667Y425000D01*
X1273500Y425667D01*
X1273667Y426333D01*
X1274000Y426917D01*
X1274500Y427250D01*
X1275000Y427333D01*
X1275500Y427250D01*
X1276000Y426917D01*
X1276333Y426333D01*
X1276417Y425667D01*
X1276333Y425000D01*
X1276000Y424417D01*
X1275500Y424083D01*
X1275000Y424000D01*
G01X1280600Y429000D02*
Y424000D01*
G01X1279433Y427333D02*
X1281767D01*
G01X1293300Y424000D02*
Y427333D01*
G01Y426750D02*
X1292967Y427083D01*
X1292467Y427250D01*
X1291883Y427333D01*
X1291300Y427167D01*
X1290800Y426833D01*
X1290467Y426333D01*
X1290300Y425667D01*
X1290467Y425000D01*
X1290800Y424500D01*
X1291300Y424167D01*
X1291883Y424000D01*
X1292467Y424083D01*
X1292967Y424333D01*
X1293300Y424667D01*
G01X1297400Y424000D02*
Y429000D01*
G01X1303000Y424000D02*
Y429000D01*
G01X1308600Y424000D02*
X1308100Y424083D01*
X1307600Y424417D01*
X1307267Y425000D01*
X1307100Y425667D01*
X1307267Y426333D01*
X1307600Y426917D01*
X1308100Y427250D01*
X1308600Y427333D01*
X1309100Y427250D01*
X1309600Y426917D01*
X1309933Y426333D01*
X1310017Y425667D01*
X1309933Y425000D01*
X1309600Y424417D01*
X1309100Y424083D01*
X1308600Y424000D01*
G01X1312117Y427333D02*
X1313117Y424000D01*
X1314200Y427333D01*
X1315283Y424000D01*
X1316283Y427333D01*
G01X1025417Y445500D02*
X1027500Y440500D01*
X1029583Y445500D01*
G01X1033100Y443833D02*
Y440500D01*
G01Y445167D02*
X1032933Y445250D01*
Y445417D01*
X1033100Y445500D01*
X1033267Y445417D01*
Y445250D01*
X1033100Y445167D01*
G01X1040200Y440500D02*
Y443833D01*
G01Y443250D02*
X1039867Y443583D01*
X1039367Y443750D01*
X1038783Y443833D01*
X1038200Y443667D01*
X1037700Y443333D01*
X1037367Y442833D01*
X1037200Y442167D01*
X1037367Y441500D01*
X1037700Y441000D01*
X1038200Y440667D01*
X1038783Y440500D01*
X1039367Y440583D01*
X1039867Y440833D01*
X1040200Y441167D01*
G01X1048650Y441083D02*
X1049067Y440750D01*
X1049650Y440500D01*
X1050150D01*
X1050650Y440667D01*
X1050983Y440917D01*
X1051150Y441250D01*
X1051067Y441750D01*
X1050733Y442000D01*
X1049233Y442500D01*
X1048900Y443083D01*
X1049067Y443500D01*
X1049400Y443750D01*
X1049900Y443833D01*
X1050400Y443750D01*
X1050900Y443500D01*
G01X1054083Y440500D02*
Y445500D01*
G01Y443083D02*
X1054500Y443500D01*
X1054917Y443750D01*
X1055583Y443833D01*
X1056083Y443750D01*
X1056667Y443417D01*
X1056917Y442917D01*
Y440500D01*
G01X1061100D02*
X1060600Y440583D01*
X1060100Y440917D01*
X1059767Y441500D01*
X1059600Y442167D01*
X1059767Y442833D01*
X1060100Y443417D01*
X1060600Y443750D01*
X1061100Y443833D01*
X1061600Y443750D01*
X1062100Y443417D01*
X1062433Y442833D01*
X1062517Y442167D01*
X1062433Y441500D01*
X1062100Y440917D01*
X1061600Y440583D01*
X1061100Y440500D01*
G01X1065283Y443833D02*
Y441500D01*
X1065617Y440917D01*
X1066117Y440583D01*
X1066700Y440500D01*
X1067283Y440583D01*
X1067783Y440917D01*
X1068117Y441500D01*
G01Y440500D02*
Y443833D01*
G01X1072300Y440500D02*
Y445500D01*
G01X1079400D02*
Y440500D01*
G01Y441250D02*
X1079067Y440833D01*
X1078567Y440583D01*
X1077983Y440500D01*
X1077317Y440667D01*
X1076817Y441083D01*
X1076483Y441583D01*
X1076400Y442167D01*
X1076483Y442750D01*
X1076817Y443250D01*
X1077317Y443667D01*
X1077983Y443833D01*
X1078567Y443750D01*
X1078983Y443583D01*
X1079400Y443250D01*
G01X1087600Y440500D02*
Y445500D01*
G01Y443000D02*
X1088017Y443500D01*
X1088517Y443750D01*
X1089017Y443833D01*
X1089767Y443667D01*
X1090267Y443333D01*
X1090600Y442750D01*
Y442083D01*
X1090433Y441417D01*
X1090100Y440917D01*
X1089517Y440583D01*
X1089017Y440500D01*
X1088517Y440583D01*
X1088017Y440833D01*
X1087600Y441250D01*
G01X1093450Y442750D02*
X1096117D01*
X1095867Y443333D01*
X1095450Y443667D01*
X1094867Y443833D01*
X1094283Y443750D01*
X1093783Y443500D01*
X1093450Y442917D01*
X1093283Y442417D01*
Y441917D01*
X1093450Y441417D01*
X1093867Y440917D01*
X1094367Y440583D01*
X1094950Y440500D01*
X1095533Y440667D01*
X1096117Y441167D01*
G01X1104400Y438833D02*
Y443833D01*
G01Y443083D02*
X1104817Y443500D01*
X1105233Y443750D01*
X1105900Y443833D01*
X1106483Y443750D01*
X1107067Y443333D01*
X1107317Y442750D01*
X1107400Y442167D01*
X1107317Y441583D01*
X1107067Y441000D01*
X1106567Y440667D01*
X1105900Y440500D01*
X1105317Y440583D01*
X1104733Y440833D01*
X1104400Y441167D01*
G01X1111500Y440500D02*
Y445500D01*
G01X1115683Y443833D02*
Y441500D01*
X1116017Y440917D01*
X1116517Y440583D01*
X1117100Y440500D01*
X1117683Y440583D01*
X1118183Y440917D01*
X1118517Y441500D01*
G01Y440500D02*
Y443833D01*
G01X1121533Y439250D02*
X1122117Y438917D01*
X1122783Y438833D01*
X1123367Y438917D01*
X1123867Y439333D01*
X1124200Y439917D01*
Y443833D01*
G01Y443167D02*
X1123867Y443500D01*
X1123367Y443750D01*
X1122783Y443833D01*
X1122117Y443667D01*
X1121700Y443333D01*
X1121367Y442750D01*
X1121200Y442167D01*
X1121283Y441667D01*
X1121617Y441083D01*
X1122117Y440667D01*
X1122783Y440500D01*
X1123283Y440583D01*
X1123867Y440917D01*
X1124200Y441250D01*
G01X1127133Y439250D02*
X1127717Y438917D01*
X1128383Y438833D01*
X1128967Y438917D01*
X1129467Y439333D01*
X1129800Y439917D01*
Y443833D01*
G01Y443167D02*
X1129467Y443500D01*
X1128967Y443750D01*
X1128383Y443833D01*
X1127717Y443667D01*
X1127300Y443333D01*
X1126967Y442750D01*
X1126800Y442167D01*
X1126883Y441667D01*
X1127217Y441083D01*
X1127717Y440667D01*
X1128383Y440500D01*
X1128883Y440583D01*
X1129467Y440917D01*
X1129800Y441250D01*
G01X1132650Y442750D02*
X1135317D01*
X1135067Y443333D01*
X1134650Y443667D01*
X1134067Y443833D01*
X1133483Y443750D01*
X1132983Y443500D01*
X1132650Y442917D01*
X1132483Y442417D01*
Y441917D01*
X1132650Y441417D01*
X1133067Y440917D01*
X1133567Y440583D01*
X1134150Y440500D01*
X1134733Y440667D01*
X1135317Y441167D01*
G01X1141000Y445500D02*
Y440500D01*
G01Y441250D02*
X1140667Y440833D01*
X1140167Y440583D01*
X1139583Y440500D01*
X1138917Y440667D01*
X1138417Y441083D01*
X1138083Y441583D01*
X1138000Y442167D01*
X1138083Y442750D01*
X1138417Y443250D01*
X1138917Y443667D01*
X1139583Y443833D01*
X1140167Y443750D01*
X1140583Y443583D01*
X1141000Y443250D01*
G01X1148617Y443833D02*
X1149617Y440500D01*
X1150700Y443833D01*
X1151783Y440500D01*
X1152783Y443833D01*
G01X1156300D02*
Y440500D01*
G01Y445167D02*
X1156133Y445250D01*
Y445417D01*
X1156300Y445500D01*
X1156467Y445417D01*
Y445250D01*
X1156300Y445167D01*
G01X1161900Y445500D02*
Y440500D01*
G01X1160733Y443833D02*
X1163067D01*
G01X1166083Y440500D02*
Y445500D01*
G01Y443083D02*
X1166500Y443500D01*
X1166917Y443750D01*
X1167583Y443833D01*
X1168083Y443750D01*
X1168667Y443417D01*
X1168917Y442917D01*
Y440500D01*
G01X1177033D02*
X1180367Y442167D01*
X1177033Y443833D01*
G01X1182883Y441083D02*
X1183467Y440667D01*
X1184133Y440500D01*
X1184800Y440667D01*
X1185383Y441167D01*
X1185800Y441917D01*
X1185967Y442667D01*
Y443583D01*
X1185800Y444333D01*
X1185383Y445000D01*
X1184883Y445333D01*
X1184300Y445500D01*
X1183633Y445333D01*
X1183133Y445000D01*
X1182800Y444500D01*
X1182633Y443833D01*
X1182800Y443250D01*
X1183217Y442667D01*
X1183717Y442333D01*
X1184300Y442250D01*
X1184967Y442417D01*
X1185467Y442833D01*
X1185967Y443583D01*
G01X1189900Y445500D02*
X1189233Y445333D01*
X1188733Y444917D01*
X1188400Y444417D01*
X1188150Y443750D01*
X1188067Y443000D01*
X1188150Y442250D01*
X1188400Y441583D01*
X1188733Y441083D01*
X1189233Y440667D01*
X1189900Y440500D01*
X1190567Y440667D01*
X1191067Y441083D01*
X1191400Y441583D01*
X1191650Y442250D01*
X1191733Y443000D01*
X1191650Y443750D01*
X1191400Y444417D01*
X1191067Y444917D01*
X1190567Y445333D01*
X1189900Y445500D01*
G01X1194000Y440333D02*
X1197000Y445500D01*
G01X1194000D02*
X1193500Y445333D01*
X1193250Y445083D01*
X1193083Y444583D01*
X1193250Y444083D01*
X1193500Y443833D01*
X1194000Y443667D01*
X1194500Y443833D01*
X1194750Y444083D01*
X1194917Y444583D01*
X1194750Y445083D01*
X1194500Y445333D01*
X1194000Y445500D01*
G01X1197000Y442167D02*
X1196500Y442000D01*
X1196250Y441750D01*
X1196083Y441250D01*
X1196250Y440750D01*
X1196500Y440500D01*
X1197000Y440333D01*
X1197500Y440500D01*
X1197750Y440750D01*
X1197917Y441250D01*
X1197750Y441750D01*
X1197500Y442000D01*
X1197000Y442167D01*
G01X1205533Y440500D02*
Y443833D01*
G01Y443167D02*
X1205950Y443500D01*
X1206367Y443750D01*
X1206950Y443833D01*
X1207367Y443750D01*
X1207867Y443500D01*
G01X1211050Y442750D02*
X1213717D01*
X1213467Y443333D01*
X1213050Y443667D01*
X1212467Y443833D01*
X1211883Y443750D01*
X1211383Y443500D01*
X1211050Y442917D01*
X1210883Y442417D01*
Y441917D01*
X1211050Y441417D01*
X1211467Y440917D01*
X1211967Y440583D01*
X1212550Y440500D01*
X1213133Y440667D01*
X1213717Y441167D01*
G01X1216650Y441083D02*
X1217067Y440750D01*
X1217650Y440500D01*
X1218150D01*
X1218650Y440667D01*
X1218983Y440917D01*
X1219150Y441250D01*
X1219067Y441750D01*
X1218733Y442000D01*
X1217233Y442500D01*
X1216900Y443083D01*
X1217067Y443500D01*
X1217400Y443750D01*
X1217900Y443833D01*
X1218400Y443750D01*
X1218900Y443500D01*
G01X1223500Y443833D02*
Y440500D01*
G01Y445167D02*
X1223333Y445250D01*
Y445417D01*
X1223500Y445500D01*
X1223667Y445417D01*
Y445250D01*
X1223500Y445167D01*
G01X1227683Y440500D02*
Y443833D01*
G01Y443000D02*
X1228017Y443417D01*
X1228517Y443750D01*
X1229183Y443833D01*
X1229767Y443750D01*
X1230267Y443417D01*
X1230517Y442833D01*
Y440500D01*
G01X1023917Y466500D02*
X1026000Y461500D01*
X1028083Y466500D01*
G01X1031600Y464833D02*
Y461500D01*
G01Y466167D02*
X1031433Y466250D01*
Y466417D01*
X1031600Y466500D01*
X1031767Y466417D01*
Y466250D01*
X1031600Y466167D01*
G01X1038700Y461500D02*
Y464833D01*
G01Y464250D02*
X1038367Y464583D01*
X1037867Y464750D01*
X1037283Y464833D01*
X1036700Y464667D01*
X1036200Y464333D01*
X1035867Y463833D01*
X1035700Y463167D01*
X1035867Y462500D01*
X1036200Y462000D01*
X1036700Y461667D01*
X1037283Y461500D01*
X1037867Y461583D01*
X1038367Y461833D01*
X1038700Y462167D01*
G01X1047150Y462083D02*
X1047567Y461750D01*
X1048150Y461500D01*
X1048650D01*
X1049150Y461667D01*
X1049483Y461917D01*
X1049650Y462250D01*
X1049567Y462750D01*
X1049233Y463000D01*
X1047733Y463500D01*
X1047400Y464083D01*
X1047567Y464500D01*
X1047900Y464750D01*
X1048400Y464833D01*
X1048900Y464750D01*
X1049400Y464500D01*
G01X1052583Y461500D02*
Y466500D01*
G01Y464083D02*
X1053000Y464500D01*
X1053417Y464750D01*
X1054083Y464833D01*
X1054583Y464750D01*
X1055167Y464417D01*
X1055417Y463917D01*
Y461500D01*
G01X1059600D02*
X1059100Y461583D01*
X1058600Y461917D01*
X1058267Y462500D01*
X1058100Y463167D01*
X1058267Y463833D01*
X1058600Y464417D01*
X1059100Y464750D01*
X1059600Y464833D01*
X1060100Y464750D01*
X1060600Y464417D01*
X1060933Y463833D01*
X1061017Y463167D01*
X1060933Y462500D01*
X1060600Y461917D01*
X1060100Y461583D01*
X1059600Y461500D01*
G01X1063783Y464833D02*
Y462500D01*
X1064117Y461917D01*
X1064617Y461583D01*
X1065200Y461500D01*
X1065783Y461583D01*
X1066283Y461917D01*
X1066617Y462500D01*
G01Y461500D02*
Y464833D01*
G01X1070800Y461500D02*
Y466500D01*
G01X1077900D02*
Y461500D01*
G01Y462250D02*
X1077567Y461833D01*
X1077067Y461583D01*
X1076483Y461500D01*
X1075817Y461667D01*
X1075317Y462083D01*
X1074983Y462583D01*
X1074900Y463167D01*
X1074983Y463750D01*
X1075317Y464250D01*
X1075817Y464667D01*
X1076483Y464833D01*
X1077067Y464750D01*
X1077483Y464583D01*
X1077900Y464250D01*
G01X1086100Y461500D02*
Y466500D01*
G01Y464000D02*
X1086517Y464500D01*
X1087017Y464750D01*
X1087517Y464833D01*
X1088267Y464667D01*
X1088767Y464333D01*
X1089100Y463750D01*
Y463083D01*
X1088933Y462417D01*
X1088600Y461917D01*
X1088017Y461583D01*
X1087517Y461500D01*
X1087017Y461583D01*
X1086517Y461833D01*
X1086100Y462250D01*
G01X1091950Y463750D02*
X1094617D01*
X1094367Y464333D01*
X1093950Y464667D01*
X1093367Y464833D01*
X1092783Y464750D01*
X1092283Y464500D01*
X1091950Y463917D01*
X1091783Y463417D01*
Y462917D01*
X1091950Y462417D01*
X1092367Y461917D01*
X1092867Y461583D01*
X1093450Y461500D01*
X1094033Y461667D01*
X1094617Y462167D01*
G01X1102900Y459833D02*
Y464833D01*
G01Y464083D02*
X1103317Y464500D01*
X1103733Y464750D01*
X1104400Y464833D01*
X1104983Y464750D01*
X1105567Y464333D01*
X1105817Y463750D01*
X1105900Y463167D01*
X1105817Y462583D01*
X1105567Y462000D01*
X1105067Y461667D01*
X1104400Y461500D01*
X1103817Y461583D01*
X1103233Y461833D01*
X1102900Y462167D01*
G01X1110000Y461500D02*
Y466500D01*
G01X1114183Y464833D02*
Y462500D01*
X1114517Y461917D01*
X1115017Y461583D01*
X1115600Y461500D01*
X1116183Y461583D01*
X1116683Y461917D01*
X1117017Y462500D01*
G01Y461500D02*
Y464833D01*
G01X1120033Y460250D02*
X1120617Y459917D01*
X1121283Y459833D01*
X1121867Y459917D01*
X1122367Y460333D01*
X1122700Y460917D01*
Y464833D01*
G01Y464167D02*
X1122367Y464500D01*
X1121867Y464750D01*
X1121283Y464833D01*
X1120617Y464667D01*
X1120200Y464333D01*
X1119867Y463750D01*
X1119700Y463167D01*
X1119783Y462667D01*
X1120117Y462083D01*
X1120617Y461667D01*
X1121283Y461500D01*
X1121783Y461583D01*
X1122367Y461917D01*
X1122700Y462250D01*
G01X1125633Y460250D02*
X1126217Y459917D01*
X1126883Y459833D01*
X1127467Y459917D01*
X1127967Y460333D01*
X1128300Y460917D01*
Y464833D01*
G01Y464167D02*
X1127967Y464500D01*
X1127467Y464750D01*
X1126883Y464833D01*
X1126217Y464667D01*
X1125800Y464333D01*
X1125467Y463750D01*
X1125300Y463167D01*
X1125383Y462667D01*
X1125717Y462083D01*
X1126217Y461667D01*
X1126883Y461500D01*
X1127383Y461583D01*
X1127967Y461917D01*
X1128300Y462250D01*
G01X1131150Y463750D02*
X1133817D01*
X1133567Y464333D01*
X1133150Y464667D01*
X1132567Y464833D01*
X1131983Y464750D01*
X1131483Y464500D01*
X1131150Y463917D01*
X1130983Y463417D01*
Y462917D01*
X1131150Y462417D01*
X1131567Y461917D01*
X1132067Y461583D01*
X1132650Y461500D01*
X1133233Y461667D01*
X1133817Y462167D01*
G01X1139500Y466500D02*
Y461500D01*
G01Y462250D02*
X1139167Y461833D01*
X1138667Y461583D01*
X1138083Y461500D01*
X1137417Y461667D01*
X1136917Y462083D01*
X1136583Y462583D01*
X1136500Y463167D01*
X1136583Y463750D01*
X1136917Y464250D01*
X1137417Y464667D01*
X1138083Y464833D01*
X1138667Y464750D01*
X1139083Y464583D01*
X1139500Y464250D01*
G01X1150200Y461500D02*
Y466500D01*
X1147117Y462917D01*
X1151283D01*
G01X1154800Y466500D02*
X1154133Y466333D01*
X1153633Y465917D01*
X1153300Y465417D01*
X1153050Y464750D01*
X1152967Y464000D01*
X1153050Y463250D01*
X1153300Y462583D01*
X1153633Y462083D01*
X1154133Y461667D01*
X1154800Y461500D01*
X1155467Y461667D01*
X1155967Y462083D01*
X1156300Y462583D01*
X1156550Y463250D01*
X1156633Y464000D01*
X1156550Y464750D01*
X1156300Y465417D01*
X1155967Y465917D01*
X1155467Y466333D01*
X1154800Y466500D01*
G01X1158900Y461333D02*
X1161900Y466500D01*
G01X1158900D02*
X1158400Y466333D01*
X1158150Y466083D01*
X1157983Y465583D01*
X1158150Y465083D01*
X1158400Y464833D01*
X1158900Y464667D01*
X1159400Y464833D01*
X1159650Y465083D01*
X1159817Y465583D01*
X1159650Y466083D01*
X1159400Y466333D01*
X1158900Y466500D01*
G01X1161900Y463167D02*
X1161400Y463000D01*
X1161150Y462750D01*
X1160983Y462250D01*
X1161150Y461750D01*
X1161400Y461500D01*
X1161900Y461333D01*
X1162400Y461500D01*
X1162650Y461750D01*
X1162817Y462250D01*
X1162650Y462750D01*
X1162400Y463000D01*
X1161900Y463167D01*
G01X1169100D02*
X1169933Y464833D01*
X1170767D01*
X1172433Y461500D01*
X1173267D01*
X1174100Y463167D01*
G01X1182800Y461500D02*
Y466500D01*
X1181800Y465500D01*
G01Y461500D02*
X1183800D01*
G01X1188400Y466500D02*
X1187733Y466333D01*
X1187233Y465917D01*
X1186900Y465417D01*
X1186650Y464750D01*
X1186567Y464000D01*
X1186650Y463250D01*
X1186900Y462583D01*
X1187233Y462083D01*
X1187733Y461667D01*
X1188400Y461500D01*
X1189067Y461667D01*
X1189567Y462083D01*
X1189900Y462583D01*
X1190150Y463250D01*
X1190233Y464000D01*
X1190150Y464750D01*
X1189900Y465417D01*
X1189567Y465917D01*
X1189067Y466333D01*
X1188400Y466500D01*
G01X1194000D02*
X1193333Y466333D01*
X1192833Y465917D01*
X1192500Y465417D01*
X1192250Y464750D01*
X1192167Y464000D01*
X1192250Y463250D01*
X1192500Y462583D01*
X1192833Y462083D01*
X1193333Y461667D01*
X1194000Y461500D01*
X1194667Y461667D01*
X1195167Y462083D01*
X1195500Y462583D01*
X1195750Y463250D01*
X1195833Y464000D01*
X1195750Y464750D01*
X1195500Y465417D01*
X1195167Y465917D01*
X1194667Y466333D01*
X1194000Y466500D01*
G01X1198100Y461333D02*
X1201100Y466500D01*
G01X1198100D02*
X1197600Y466333D01*
X1197350Y466083D01*
X1197183Y465583D01*
X1197350Y465083D01*
X1197600Y464833D01*
X1198100Y464667D01*
X1198600Y464833D01*
X1198850Y465083D01*
X1199017Y465583D01*
X1198850Y466083D01*
X1198600Y466333D01*
X1198100Y466500D01*
G01X1201100Y463167D02*
X1200600Y463000D01*
X1200350Y462750D01*
X1200183Y462250D01*
X1200350Y461750D01*
X1200600Y461500D01*
X1201100Y461333D01*
X1201600Y461500D01*
X1201850Y461750D01*
X1202017Y462250D01*
X1201850Y462750D01*
X1201600Y463000D01*
X1201100Y463167D01*
G01X1209550Y462083D02*
X1209967Y461750D01*
X1210550Y461500D01*
X1211050D01*
X1211550Y461667D01*
X1211883Y461917D01*
X1212050Y462250D01*
X1211967Y462750D01*
X1211633Y463000D01*
X1210133Y463500D01*
X1209800Y464083D01*
X1209967Y464500D01*
X1210300Y464750D01*
X1210800Y464833D01*
X1211300Y464750D01*
X1211800Y464500D01*
G01X1216400Y461500D02*
X1215900Y461583D01*
X1215400Y461917D01*
X1215067Y462500D01*
X1214900Y463167D01*
X1215067Y463833D01*
X1215400Y464417D01*
X1215900Y464750D01*
X1216400Y464833D01*
X1216900Y464750D01*
X1217400Y464417D01*
X1217733Y463833D01*
X1217817Y463167D01*
X1217733Y462500D01*
X1217400Y461917D01*
X1216900Y461583D01*
X1216400Y461500D01*
G01X1222000D02*
Y466500D01*
G01X1229100D02*
Y461500D01*
G01Y462250D02*
X1228767Y461833D01*
X1228267Y461583D01*
X1227683Y461500D01*
X1227017Y461667D01*
X1226517Y462083D01*
X1226183Y462583D01*
X1226100Y463167D01*
X1226183Y463750D01*
X1226517Y464250D01*
X1227017Y464667D01*
X1227683Y464833D01*
X1228267Y464750D01*
X1228683Y464583D01*
X1229100Y464250D01*
G01X1231950Y463750D02*
X1234617D01*
X1234367Y464333D01*
X1233950Y464667D01*
X1233367Y464833D01*
X1232783Y464750D01*
X1232283Y464500D01*
X1231950Y463917D01*
X1231783Y463417D01*
Y462917D01*
X1231950Y462417D01*
X1232367Y461917D01*
X1232867Y461583D01*
X1233450Y461500D01*
X1234033Y461667D01*
X1234617Y462167D01*
G01X1237633Y461500D02*
Y464833D01*
G01Y464167D02*
X1238050Y464500D01*
X1238467Y464750D01*
X1239050Y464833D01*
X1239467Y464750D01*
X1239967Y464500D01*
G01X1247500Y461500D02*
Y464833D01*
G01Y463917D02*
X1247750Y464333D01*
X1248167Y464667D01*
X1248750Y464833D01*
X1249333Y464667D01*
X1249750Y464333D01*
X1250000Y463917D01*
Y461500D01*
G01Y463917D02*
X1250250Y464333D01*
X1250667Y464667D01*
X1251250Y464833D01*
X1251833Y464667D01*
X1252250Y464333D01*
X1252500Y463833D01*
Y461500D01*
G01X1257100D02*
Y464833D01*
G01Y464250D02*
X1256767Y464583D01*
X1256267Y464750D01*
X1255683Y464833D01*
X1255100Y464667D01*
X1254600Y464333D01*
X1254267Y463833D01*
X1254100Y463167D01*
X1254267Y462500D01*
X1254600Y462000D01*
X1255100Y461667D01*
X1255683Y461500D01*
X1256267Y461583D01*
X1256767Y461833D01*
X1257100Y462167D01*
G01X1259950Y462083D02*
X1260367Y461750D01*
X1260950Y461500D01*
X1261450D01*
X1261950Y461667D01*
X1262283Y461917D01*
X1262450Y462250D01*
X1262367Y462750D01*
X1262033Y463000D01*
X1260533Y463500D01*
X1260200Y464083D01*
X1260367Y464500D01*
X1260700Y464750D01*
X1261200Y464833D01*
X1261700Y464750D01*
X1262200Y464500D01*
G01X1265383Y461500D02*
Y466500D01*
G01X1268050Y464833D02*
X1265383Y462917D01*
G01X1266467Y463667D02*
X1268217Y461500D01*
G01X1046500Y485833D02*
X1048000Y482500D01*
X1049500Y485833D01*
G01X1053600D02*
Y482500D01*
G01Y487167D02*
X1053433Y487250D01*
Y487417D01*
X1053600Y487500D01*
X1053767Y487417D01*
Y487250D01*
X1053600Y487167D01*
G01X1060700Y482500D02*
Y485833D01*
G01Y485250D02*
X1060367Y485583D01*
X1059867Y485750D01*
X1059283Y485833D01*
X1058700Y485667D01*
X1058200Y485333D01*
X1057867Y484833D01*
X1057700Y484167D01*
X1057867Y483500D01*
X1058200Y483000D01*
X1058700Y482667D01*
X1059283Y482500D01*
X1059867Y482583D01*
X1060367Y482833D01*
X1060700Y483167D01*
G01X1069150Y483083D02*
X1069567Y482750D01*
X1070150Y482500D01*
X1070650D01*
X1071150Y482667D01*
X1071483Y482917D01*
X1071650Y483250D01*
X1071567Y483750D01*
X1071233Y484000D01*
X1069733Y484500D01*
X1069400Y485083D01*
X1069567Y485500D01*
X1069900Y485750D01*
X1070400Y485833D01*
X1070900Y485750D01*
X1071400Y485500D01*
G01X1074583Y482500D02*
Y487500D01*
G01Y485083D02*
X1075000Y485500D01*
X1075417Y485750D01*
X1076083Y485833D01*
X1076583Y485750D01*
X1077167Y485417D01*
X1077417Y484917D01*
Y482500D01*
G01X1083100D02*
Y485833D01*
G01Y485250D02*
X1082767Y485583D01*
X1082267Y485750D01*
X1081683Y485833D01*
X1081100Y485667D01*
X1080600Y485333D01*
X1080267Y484833D01*
X1080100Y484167D01*
X1080267Y483500D01*
X1080600Y483000D01*
X1081100Y482667D01*
X1081683Y482500D01*
X1082267Y482583D01*
X1082767Y482833D01*
X1083100Y483167D01*
G01X1087200Y482500D02*
Y487500D01*
G01X1092800Y482500D02*
Y487500D01*
G01X1102500Y482500D02*
Y487500D01*
G01Y485000D02*
X1102917Y485500D01*
X1103417Y485750D01*
X1103917Y485833D01*
X1104667Y485667D01*
X1105167Y485333D01*
X1105500Y484750D01*
Y484083D01*
X1105333Y483417D01*
X1105000Y482917D01*
X1104417Y482583D01*
X1103917Y482500D01*
X1103417Y482583D01*
X1102917Y482833D01*
X1102500Y483250D01*
G01X1108350Y484750D02*
X1111017D01*
X1110767Y485333D01*
X1110350Y485667D01*
X1109767Y485833D01*
X1109183Y485750D01*
X1108683Y485500D01*
X1108350Y484917D01*
X1108183Y484417D01*
Y483917D01*
X1108350Y483417D01*
X1108767Y482917D01*
X1109267Y482583D01*
X1109850Y482500D01*
X1110433Y482667D01*
X1111017Y483167D01*
G01X1118717Y485833D02*
X1119717Y482500D01*
X1120800Y485833D01*
X1121883Y482500D01*
X1122883Y485833D01*
G01X1126400D02*
Y482500D01*
G01Y487167D02*
X1126233Y487250D01*
Y487417D01*
X1126400Y487500D01*
X1126567Y487417D01*
Y487250D01*
X1126400Y487167D01*
G01X1132000Y487500D02*
Y482500D01*
G01X1130833Y485833D02*
X1133167D01*
G01X1136183Y482500D02*
Y487500D01*
G01Y485083D02*
X1136600Y485500D01*
X1137017Y485750D01*
X1137683Y485833D01*
X1138183Y485750D01*
X1138767Y485417D01*
X1139017Y484917D01*
Y482500D01*
G01X1150467D02*
X1147133Y484167D01*
X1150467Y485833D01*
G01X1160000Y482500D02*
X1160583Y482583D01*
X1161250Y482833D01*
X1161667Y483250D01*
X1161833Y483833D01*
X1161667Y484417D01*
X1161167Y484917D01*
X1160417Y485167D01*
X1159583D01*
X1159083Y485333D01*
X1158667Y485750D01*
X1158500Y486333D01*
X1158750Y486917D01*
X1159333Y487333D01*
X1160000Y487500D01*
X1160667Y487333D01*
X1161250Y486917D01*
X1161500Y486333D01*
X1161333Y485750D01*
X1160917Y485333D01*
X1160417Y485167D01*
X1159583D01*
X1158833Y484917D01*
X1158333Y484417D01*
X1158167Y483833D01*
X1158333Y483250D01*
X1158750Y482833D01*
X1159417Y482583D01*
X1160000Y482500D01*
G01X1165600Y487500D02*
X1164933Y487333D01*
X1164433Y486917D01*
X1164100Y486417D01*
X1163850Y485750D01*
X1163767Y485000D01*
X1163850Y484250D01*
X1164100Y483583D01*
X1164433Y483083D01*
X1164933Y482667D01*
X1165600Y482500D01*
X1166267Y482667D01*
X1166767Y483083D01*
X1167100Y483583D01*
X1167350Y484250D01*
X1167433Y485000D01*
X1167350Y485750D01*
X1167100Y486417D01*
X1166767Y486917D01*
X1166267Y487333D01*
X1165600Y487500D01*
G01X1175300Y482333D02*
X1178300Y487500D01*
G01X1175300D02*
X1174800Y487333D01*
X1174550Y487083D01*
X1174383Y486583D01*
X1174550Y486083D01*
X1174800Y485833D01*
X1175300Y485667D01*
X1175800Y485833D01*
X1176050Y486083D01*
X1176217Y486583D01*
X1176050Y487083D01*
X1175800Y487333D01*
X1175300Y487500D01*
G01X1178300Y484167D02*
X1177800Y484000D01*
X1177550Y483750D01*
X1177383Y483250D01*
X1177550Y482750D01*
X1177800Y482500D01*
X1178300Y482333D01*
X1178800Y482500D01*
X1179050Y482750D01*
X1179217Y483250D01*
X1179050Y483750D01*
X1178800Y484000D01*
X1178300Y484167D01*
G01X1186750Y483083D02*
X1187167Y482750D01*
X1187750Y482500D01*
X1188250D01*
X1188750Y482667D01*
X1189083Y482917D01*
X1189250Y483250D01*
X1189167Y483750D01*
X1188833Y484000D01*
X1187333Y484500D01*
X1187000Y485083D01*
X1187167Y485500D01*
X1187500Y485750D01*
X1188000Y485833D01*
X1188500Y485750D01*
X1189000Y485500D01*
G01X1193600Y482500D02*
X1193100Y482583D01*
X1192600Y482917D01*
X1192267Y483500D01*
X1192100Y484167D01*
X1192267Y484833D01*
X1192600Y485417D01*
X1193100Y485750D01*
X1193600Y485833D01*
X1194100Y485750D01*
X1194600Y485417D01*
X1194933Y484833D01*
X1195017Y484167D01*
X1194933Y483500D01*
X1194600Y482917D01*
X1194100Y482583D01*
X1193600Y482500D01*
G01X1199200D02*
Y487500D01*
G01X1206300D02*
Y482500D01*
G01Y483250D02*
X1205967Y482833D01*
X1205467Y482583D01*
X1204883Y482500D01*
X1204217Y482667D01*
X1203717Y483083D01*
X1203383Y483583D01*
X1203300Y484167D01*
X1203383Y484750D01*
X1203717Y485250D01*
X1204217Y485667D01*
X1204883Y485833D01*
X1205467Y485750D01*
X1205883Y485583D01*
X1206300Y485250D01*
G01X1209150Y484750D02*
X1211817D01*
X1211567Y485333D01*
X1211150Y485667D01*
X1210567Y485833D01*
X1209983Y485750D01*
X1209483Y485500D01*
X1209150Y484917D01*
X1208983Y484417D01*
Y483917D01*
X1209150Y483417D01*
X1209567Y482917D01*
X1210067Y482583D01*
X1210650Y482500D01*
X1211233Y482667D01*
X1211817Y483167D01*
G01X1214833Y482500D02*
Y485833D01*
G01Y485167D02*
X1215250Y485500D01*
X1215667Y485750D01*
X1216250Y485833D01*
X1216667Y485750D01*
X1217167Y485500D01*
G01X1224700Y482500D02*
Y485833D01*
G01Y484917D02*
X1224950Y485333D01*
X1225367Y485667D01*
X1225950Y485833D01*
X1226533Y485667D01*
X1226950Y485333D01*
X1227200Y484917D01*
Y482500D01*
G01Y484917D02*
X1227450Y485333D01*
X1227867Y485667D01*
X1228450Y485833D01*
X1229033Y485667D01*
X1229450Y485333D01*
X1229700Y484833D01*
Y482500D01*
G01X1234300D02*
Y485833D01*
G01Y485250D02*
X1233967Y485583D01*
X1233467Y485750D01*
X1232883Y485833D01*
X1232300Y485667D01*
X1231800Y485333D01*
X1231467Y484833D01*
X1231300Y484167D01*
X1231467Y483500D01*
X1231800Y483000D01*
X1232300Y482667D01*
X1232883Y482500D01*
X1233467Y482583D01*
X1233967Y482833D01*
X1234300Y483167D01*
G01X1237150Y483083D02*
X1237567Y482750D01*
X1238150Y482500D01*
X1238650D01*
X1239150Y482667D01*
X1239483Y482917D01*
X1239650Y483250D01*
X1239567Y483750D01*
X1239233Y484000D01*
X1237733Y484500D01*
X1237400Y485083D01*
X1237567Y485500D01*
X1237900Y485750D01*
X1238400Y485833D01*
X1238900Y485750D01*
X1239400Y485500D01*
G01X1242583Y482500D02*
Y487500D01*
G01X1245250Y485833D02*
X1242583Y483917D01*
G01X1243667Y484667D02*
X1245417Y482500D01*
G01X1035500Y491500D02*
Y496500D01*
G01Y494000D02*
X1035917Y494500D01*
X1036417Y494750D01*
X1036917Y494833D01*
X1037667Y494667D01*
X1038167Y494333D01*
X1038500Y493750D01*
Y493083D01*
X1038333Y492417D01*
X1038000Y491917D01*
X1037417Y491583D01*
X1036917Y491500D01*
X1036417Y491583D01*
X1035917Y491833D01*
X1035500Y492250D01*
G01X1042600Y491333D02*
X1042433Y491417D01*
Y491583D01*
X1042600Y491667D01*
X1042767Y491583D01*
Y491417D01*
X1042600Y491333D01*
G01X1048867Y494167D02*
X1049200Y494417D01*
X1049450Y494833D01*
X1049617Y495417D01*
X1049450Y495917D01*
X1049117Y496250D01*
X1048533Y496500D01*
X1046283D01*
Y491500D01*
X1049033D01*
X1049617Y491833D01*
X1049950Y492333D01*
X1050117Y492917D01*
X1049950Y493500D01*
X1049450Y494000D01*
X1048867Y494167D01*
X1046283D01*
G01X1053800Y491500D02*
X1053300Y491583D01*
X1052800Y491917D01*
X1052467Y492500D01*
X1052300Y493167D01*
X1052467Y493833D01*
X1052800Y494417D01*
X1053300Y494750D01*
X1053800Y494833D01*
X1054300Y494750D01*
X1054800Y494417D01*
X1055133Y493833D01*
X1055217Y493167D01*
X1055133Y492500D01*
X1054800Y491917D01*
X1054300Y491583D01*
X1053800Y491500D01*
G01X1060900D02*
Y494833D01*
G01Y494250D02*
X1060567Y494583D01*
X1060067Y494750D01*
X1059483Y494833D01*
X1058900Y494667D01*
X1058400Y494333D01*
X1058067Y493833D01*
X1057900Y493167D01*
X1058067Y492500D01*
X1058400Y492000D01*
X1058900Y491667D01*
X1059483Y491500D01*
X1060067Y491583D01*
X1060567Y491833D01*
X1060900Y492167D01*
G01X1063833Y491500D02*
Y494833D01*
G01Y494167D02*
X1064250Y494500D01*
X1064667Y494750D01*
X1065250Y494833D01*
X1065667Y494750D01*
X1066167Y494500D01*
G01X1072100Y496500D02*
Y491500D01*
G01Y492250D02*
X1071767Y491833D01*
X1071267Y491583D01*
X1070683Y491500D01*
X1070017Y491667D01*
X1069517Y492083D01*
X1069183Y492583D01*
X1069100Y493167D01*
X1069183Y493750D01*
X1069517Y494250D01*
X1070017Y494667D01*
X1070683Y494833D01*
X1071267Y494750D01*
X1071683Y494583D01*
X1072100Y494250D01*
G01X1081800Y496500D02*
Y491500D01*
G01X1080633Y494833D02*
X1082967D01*
G01X1085983Y491500D02*
Y496500D01*
G01Y494083D02*
X1086400Y494500D01*
X1086817Y494750D01*
X1087483Y494833D01*
X1087983Y494750D01*
X1088567Y494417D01*
X1088817Y493917D01*
Y491500D01*
G01X1093000Y494833D02*
Y491500D01*
G01Y496167D02*
X1092833Y496250D01*
Y496417D01*
X1093000Y496500D01*
X1093167Y496417D01*
Y496250D01*
X1093000Y496167D01*
G01X1099933Y494417D02*
X1099350Y494750D01*
X1098850Y494833D01*
X1098183Y494667D01*
X1097683Y494333D01*
X1097350Y493750D01*
X1097267Y493167D01*
X1097350Y492583D01*
X1097683Y492083D01*
X1098183Y491667D01*
X1098850Y491500D01*
X1099433Y491667D01*
X1099933Y492000D01*
G01X1102783Y491500D02*
Y496500D01*
G01X1105450Y494833D02*
X1102783Y492917D01*
G01X1103867Y493667D02*
X1105617Y491500D01*
G01X1108383D02*
Y494833D01*
G01Y494000D02*
X1108717Y494417D01*
X1109217Y494750D01*
X1109883Y494833D01*
X1110467Y494750D01*
X1110967Y494417D01*
X1111217Y493833D01*
Y491500D01*
G01X1114150Y493750D02*
X1116817D01*
X1116567Y494333D01*
X1116150Y494667D01*
X1115567Y494833D01*
X1114983Y494750D01*
X1114483Y494500D01*
X1114150Y493917D01*
X1113983Y493417D01*
Y492917D01*
X1114150Y492417D01*
X1114567Y491917D01*
X1115067Y491583D01*
X1115650Y491500D01*
X1116233Y491667D01*
X1116817Y492167D01*
G01X1119750Y492083D02*
X1120167Y491750D01*
X1120750Y491500D01*
X1121250D01*
X1121750Y491667D01*
X1122083Y491917D01*
X1122250Y492250D01*
X1122167Y492750D01*
X1121833Y493000D01*
X1120333Y493500D01*
X1120000Y494083D01*
X1120167Y494500D01*
X1120500Y494750D01*
X1121000Y494833D01*
X1121500Y494750D01*
X1122000Y494500D01*
G01X1125350Y492083D02*
X1125767Y491750D01*
X1126350Y491500D01*
X1126850D01*
X1127350Y491667D01*
X1127683Y491917D01*
X1127850Y492250D01*
X1127767Y492750D01*
X1127433Y493000D01*
X1125933Y493500D01*
X1125600Y494083D01*
X1125767Y494500D01*
X1126100Y494750D01*
X1126600Y494833D01*
X1127100Y494750D01*
X1127600Y494500D01*
G01X1139467Y491500D02*
X1136133Y493167D01*
X1139467Y494833D01*
G01X1149000Y496500D02*
X1148333Y496333D01*
X1147833Y495917D01*
X1147500Y495417D01*
X1147250Y494750D01*
X1147167Y494000D01*
X1147250Y493250D01*
X1147500Y492583D01*
X1147833Y492083D01*
X1148333Y491667D01*
X1149000Y491500D01*
X1149667Y491667D01*
X1150167Y492083D01*
X1150500Y492583D01*
X1150750Y493250D01*
X1150833Y494000D01*
X1150750Y494750D01*
X1150500Y495417D01*
X1150167Y495917D01*
X1149667Y496333D01*
X1149000Y496500D01*
G01X1154600Y491333D02*
X1154433Y491417D01*
Y491583D01*
X1154600Y491667D01*
X1154767Y491583D01*
Y491417D01*
X1154600Y491333D01*
G01X1158783Y492083D02*
X1159367Y491667D01*
X1160033Y491500D01*
X1160700Y491667D01*
X1161283Y492167D01*
X1161700Y492917D01*
X1161867Y493667D01*
Y494583D01*
X1161700Y495333D01*
X1161283Y496000D01*
X1160783Y496333D01*
X1160200Y496500D01*
X1159533Y496333D01*
X1159033Y496000D01*
X1158700Y495500D01*
X1158533Y494833D01*
X1158700Y494250D01*
X1159117Y493667D01*
X1159617Y493333D01*
X1160200Y493250D01*
X1160867Y493417D01*
X1161367Y493833D01*
X1161867Y494583D01*
G01X1163300Y491500D02*
Y494833D01*
G01Y493917D02*
X1163550Y494333D01*
X1163967Y494667D01*
X1164550Y494833D01*
X1165133Y494667D01*
X1165550Y494333D01*
X1165800Y493917D01*
Y491500D01*
G01Y493917D02*
X1166050Y494333D01*
X1166467Y494667D01*
X1167050Y494833D01*
X1167633Y494667D01*
X1168050Y494333D01*
X1168300Y493833D01*
Y491500D01*
G01X1168900D02*
Y494833D01*
G01Y493917D02*
X1169150Y494333D01*
X1169567Y494667D01*
X1170150Y494833D01*
X1170733Y494667D01*
X1171150Y494333D01*
X1171400Y493917D01*
Y491500D01*
G01Y493917D02*
X1171650Y494333D01*
X1172067Y494667D01*
X1172650Y494833D01*
X1173233Y494667D01*
X1173650Y494333D01*
X1173900Y493833D01*
Y491500D01*
G01X1177000Y491333D02*
X1176833Y491417D01*
Y491583D01*
X1177000Y491667D01*
X1177167Y491583D01*
Y491417D01*
X1177000Y491333D01*
G01Y493583D02*
X1176833Y493667D01*
Y493833D01*
X1177000Y493917D01*
X1177167Y493833D01*
Y493667D01*
X1177000Y493583D01*
G01X1045500Y504833D02*
X1047000Y501500D01*
X1048500Y504833D01*
G01X1052600D02*
Y501500D01*
G01Y506167D02*
X1052433Y506250D01*
Y506417D01*
X1052600Y506500D01*
X1052767Y506417D01*
Y506250D01*
X1052600Y506167D01*
G01X1059700Y501500D02*
Y504833D01*
G01Y504250D02*
X1059367Y504583D01*
X1058867Y504750D01*
X1058283Y504833D01*
X1057700Y504667D01*
X1057200Y504333D01*
X1056867Y503833D01*
X1056700Y503167D01*
X1056867Y502500D01*
X1057200Y502000D01*
X1057700Y501667D01*
X1058283Y501500D01*
X1058867Y501583D01*
X1059367Y501833D01*
X1059700Y502167D01*
G01X1068150Y502083D02*
X1068567Y501750D01*
X1069150Y501500D01*
X1069650D01*
X1070150Y501667D01*
X1070483Y501917D01*
X1070650Y502250D01*
X1070567Y502750D01*
X1070233Y503000D01*
X1068733Y503500D01*
X1068400Y504083D01*
X1068567Y504500D01*
X1068900Y504750D01*
X1069400Y504833D01*
X1069900Y504750D01*
X1070400Y504500D01*
G01X1073583Y501500D02*
Y506500D01*
G01Y504083D02*
X1074000Y504500D01*
X1074417Y504750D01*
X1075083Y504833D01*
X1075583Y504750D01*
X1076167Y504417D01*
X1076417Y503917D01*
Y501500D01*
G01X1082100D02*
Y504833D01*
G01Y504250D02*
X1081767Y504583D01*
X1081267Y504750D01*
X1080683Y504833D01*
X1080100Y504667D01*
X1079600Y504333D01*
X1079267Y503833D01*
X1079100Y503167D01*
X1079267Y502500D01*
X1079600Y502000D01*
X1080100Y501667D01*
X1080683Y501500D01*
X1081267Y501583D01*
X1081767Y501833D01*
X1082100Y502167D01*
G01X1086200Y501500D02*
Y506500D01*
G01X1091800Y501500D02*
Y506500D01*
G01X1101500Y501500D02*
Y506500D01*
G01Y504000D02*
X1101917Y504500D01*
X1102417Y504750D01*
X1102917Y504833D01*
X1103667Y504667D01*
X1104167Y504333D01*
X1104500Y503750D01*
Y503083D01*
X1104333Y502417D01*
X1104000Y501917D01*
X1103417Y501583D01*
X1102917Y501500D01*
X1102417Y501583D01*
X1101917Y501833D01*
X1101500Y502250D01*
G01X1107350Y503750D02*
X1110017D01*
X1109767Y504333D01*
X1109350Y504667D01*
X1108767Y504833D01*
X1108183Y504750D01*
X1107683Y504500D01*
X1107350Y503917D01*
X1107183Y503417D01*
Y502917D01*
X1107350Y502417D01*
X1107767Y501917D01*
X1108267Y501583D01*
X1108850Y501500D01*
X1109433Y501667D01*
X1110017Y502167D01*
G01X1118300Y499833D02*
Y504833D01*
G01Y504083D02*
X1118717Y504500D01*
X1119133Y504750D01*
X1119800Y504833D01*
X1120383Y504750D01*
X1120967Y504333D01*
X1121217Y503750D01*
X1121300Y503167D01*
X1121217Y502583D01*
X1120967Y502000D01*
X1120467Y501667D01*
X1119800Y501500D01*
X1119217Y501583D01*
X1118633Y501833D01*
X1118300Y502167D01*
G01X1125400Y501500D02*
Y506500D01*
G01X1129583Y504833D02*
Y502500D01*
X1129917Y501917D01*
X1130417Y501583D01*
X1131000Y501500D01*
X1131583Y501583D01*
X1132083Y501917D01*
X1132417Y502500D01*
G01Y501500D02*
Y504833D01*
G01X1135433Y500250D02*
X1136017Y499917D01*
X1136683Y499833D01*
X1137267Y499917D01*
X1137767Y500333D01*
X1138100Y500917D01*
Y504833D01*
G01Y504167D02*
X1137767Y504500D01*
X1137267Y504750D01*
X1136683Y504833D01*
X1136017Y504667D01*
X1135600Y504333D01*
X1135267Y503750D01*
X1135100Y503167D01*
X1135183Y502667D01*
X1135517Y502083D01*
X1136017Y501667D01*
X1136683Y501500D01*
X1137183Y501583D01*
X1137767Y501917D01*
X1138100Y502250D01*
G01X1141033Y500250D02*
X1141617Y499917D01*
X1142283Y499833D01*
X1142867Y499917D01*
X1143367Y500333D01*
X1143700Y500917D01*
Y504833D01*
G01Y504167D02*
X1143367Y504500D01*
X1142867Y504750D01*
X1142283Y504833D01*
X1141617Y504667D01*
X1141200Y504333D01*
X1140867Y503750D01*
X1140700Y503167D01*
X1140783Y502667D01*
X1141117Y502083D01*
X1141617Y501667D01*
X1142283Y501500D01*
X1142783Y501583D01*
X1143367Y501917D01*
X1143700Y502250D01*
G01X1146550Y503750D02*
X1149217D01*
X1148967Y504333D01*
X1148550Y504667D01*
X1147967Y504833D01*
X1147383Y504750D01*
X1146883Y504500D01*
X1146550Y503917D01*
X1146383Y503417D01*
Y502917D01*
X1146550Y502417D01*
X1146967Y501917D01*
X1147467Y501583D01*
X1148050Y501500D01*
X1148633Y501667D01*
X1149217Y502167D01*
G01X1154900Y506500D02*
Y501500D01*
G01Y502250D02*
X1154567Y501833D01*
X1154067Y501583D01*
X1153483Y501500D01*
X1152817Y501667D01*
X1152317Y502083D01*
X1151983Y502583D01*
X1151900Y503167D01*
X1151983Y503750D01*
X1152317Y504250D01*
X1152817Y504667D01*
X1153483Y504833D01*
X1154067Y504750D01*
X1154483Y504583D01*
X1154900Y504250D01*
G01X1162517Y504833D02*
X1163517Y501500D01*
X1164600Y504833D01*
X1165683Y501500D01*
X1166683Y504833D01*
G01X1170200D02*
Y501500D01*
G01Y506167D02*
X1170033Y506250D01*
Y506417D01*
X1170200Y506500D01*
X1170367Y506417D01*
Y506250D01*
X1170200Y506167D01*
G01X1175800Y506500D02*
Y501500D01*
G01X1174633Y504833D02*
X1176967D01*
G01X1179983Y501500D02*
Y506500D01*
G01Y504083D02*
X1180400Y504500D01*
X1180817Y504750D01*
X1181483Y504833D01*
X1181983Y504750D01*
X1182567Y504417D01*
X1182817Y503917D01*
Y501500D01*
G01X1194267D02*
X1190933Y503167D01*
X1194267Y504833D01*
G01X1201967Y502250D02*
X1202467Y501833D01*
X1203050Y501583D01*
X1203800Y501500D01*
X1204550Y501667D01*
X1205133Y502000D01*
X1205550Y502583D01*
X1205633Y503250D01*
X1205467Y503917D01*
X1205050Y504333D01*
X1204467Y504667D01*
X1203883Y504750D01*
X1203300Y504667D01*
X1202550Y504333D01*
X1202800Y506500D01*
X1205050D01*
G01X1209400D02*
X1208733Y506333D01*
X1208233Y505917D01*
X1207900Y505417D01*
X1207650Y504750D01*
X1207567Y504000D01*
X1207650Y503250D01*
X1207900Y502583D01*
X1208233Y502083D01*
X1208733Y501667D01*
X1209400Y501500D01*
X1210067Y501667D01*
X1210567Y502083D01*
X1210900Y502583D01*
X1211150Y503250D01*
X1211233Y504000D01*
X1211150Y504750D01*
X1210900Y505417D01*
X1210567Y505917D01*
X1210067Y506333D01*
X1209400Y506500D01*
G01X1219100Y501333D02*
X1222100Y506500D01*
G01X1219100D02*
X1218600Y506333D01*
X1218350Y506083D01*
X1218183Y505583D01*
X1218350Y505083D01*
X1218600Y504833D01*
X1219100Y504667D01*
X1219600Y504833D01*
X1219850Y505083D01*
X1220017Y505583D01*
X1219850Y506083D01*
X1219600Y506333D01*
X1219100Y506500D01*
G01X1222100Y503167D02*
X1221600Y503000D01*
X1221350Y502750D01*
X1221183Y502250D01*
X1221350Y501750D01*
X1221600Y501500D01*
X1222100Y501333D01*
X1222600Y501500D01*
X1222850Y501750D01*
X1223017Y502250D01*
X1222850Y502750D01*
X1222600Y503000D01*
X1222100Y503167D01*
G01X1230550Y502083D02*
X1230967Y501750D01*
X1231550Y501500D01*
X1232050D01*
X1232550Y501667D01*
X1232883Y501917D01*
X1233050Y502250D01*
X1232967Y502750D01*
X1232633Y503000D01*
X1231133Y503500D01*
X1230800Y504083D01*
X1230967Y504500D01*
X1231300Y504750D01*
X1231800Y504833D01*
X1232300Y504750D01*
X1232800Y504500D01*
G01X1237400Y501500D02*
X1236900Y501583D01*
X1236400Y501917D01*
X1236067Y502500D01*
X1235900Y503167D01*
X1236067Y503833D01*
X1236400Y504417D01*
X1236900Y504750D01*
X1237400Y504833D01*
X1237900Y504750D01*
X1238400Y504417D01*
X1238733Y503833D01*
X1238817Y503167D01*
X1238733Y502500D01*
X1238400Y501917D01*
X1237900Y501583D01*
X1237400Y501500D01*
G01X1243000D02*
Y506500D01*
G01X1250100D02*
Y501500D01*
G01Y502250D02*
X1249767Y501833D01*
X1249267Y501583D01*
X1248683Y501500D01*
X1248017Y501667D01*
X1247517Y502083D01*
X1247183Y502583D01*
X1247100Y503167D01*
X1247183Y503750D01*
X1247517Y504250D01*
X1248017Y504667D01*
X1248683Y504833D01*
X1249267Y504750D01*
X1249683Y504583D01*
X1250100Y504250D01*
G01X1252950Y503750D02*
X1255617D01*
X1255367Y504333D01*
X1254950Y504667D01*
X1254367Y504833D01*
X1253783Y504750D01*
X1253283Y504500D01*
X1252950Y503917D01*
X1252783Y503417D01*
Y502917D01*
X1252950Y502417D01*
X1253367Y501917D01*
X1253867Y501583D01*
X1254450Y501500D01*
X1255033Y501667D01*
X1255617Y502167D01*
G01X1258633Y501500D02*
Y504833D01*
G01Y504167D02*
X1259050Y504500D01*
X1259467Y504750D01*
X1260050Y504833D01*
X1260467Y504750D01*
X1260967Y504500D01*
G01X1268500Y501500D02*
Y504833D01*
G01Y503917D02*
X1268750Y504333D01*
X1269167Y504667D01*
X1269750Y504833D01*
X1270333Y504667D01*
X1270750Y504333D01*
X1271000Y503917D01*
Y501500D01*
G01Y503917D02*
X1271250Y504333D01*
X1271667Y504667D01*
X1272250Y504833D01*
X1272833Y504667D01*
X1273250Y504333D01*
X1273500Y503833D01*
Y501500D01*
G01X1278100D02*
Y504833D01*
G01Y504250D02*
X1277767Y504583D01*
X1277267Y504750D01*
X1276683Y504833D01*
X1276100Y504667D01*
X1275600Y504333D01*
X1275267Y503833D01*
X1275100Y503167D01*
X1275267Y502500D01*
X1275600Y502000D01*
X1276100Y501667D01*
X1276683Y501500D01*
X1277267Y501583D01*
X1277767Y501833D01*
X1278100Y502167D01*
G01X1280950Y502083D02*
X1281367Y501750D01*
X1281950Y501500D01*
X1282450D01*
X1282950Y501667D01*
X1283283Y501917D01*
X1283450Y502250D01*
X1283367Y502750D01*
X1283033Y503000D01*
X1281533Y503500D01*
X1281200Y504083D01*
X1281367Y504500D01*
X1281700Y504750D01*
X1282200Y504833D01*
X1282700Y504750D01*
X1283200Y504500D01*
G01X1286383Y501500D02*
Y506500D01*
G01X1289050Y504833D02*
X1286383Y502917D01*
G01X1287467Y503667D02*
X1289217Y501500D01*
G01X1293233Y500583D02*
X1293567Y501667D01*
G01X1038500Y510500D02*
Y513833D01*
G01Y513250D02*
X1038167Y513583D01*
X1037667Y513750D01*
X1037083Y513833D01*
X1036500Y513667D01*
X1036000Y513333D01*
X1035667Y512833D01*
X1035500Y512167D01*
X1035667Y511500D01*
X1036000Y511000D01*
X1036500Y510667D01*
X1037083Y510500D01*
X1037667Y510583D01*
X1038167Y510833D01*
X1038500Y511167D01*
G01X1042600Y510333D02*
X1042433Y510417D01*
Y510583D01*
X1042600Y510667D01*
X1042767Y510583D01*
Y510417D01*
X1042600Y510333D01*
G01X1048867Y513167D02*
X1049200Y513417D01*
X1049450Y513833D01*
X1049617Y514417D01*
X1049450Y514917D01*
X1049117Y515250D01*
X1048533Y515500D01*
X1046283D01*
Y510500D01*
X1049033D01*
X1049617Y510833D01*
X1049950Y511333D01*
X1050117Y511917D01*
X1049950Y512500D01*
X1049450Y513000D01*
X1048867Y513167D01*
X1046283D01*
G01X1053800Y510500D02*
X1053300Y510583D01*
X1052800Y510917D01*
X1052467Y511500D01*
X1052300Y512167D01*
X1052467Y512833D01*
X1052800Y513417D01*
X1053300Y513750D01*
X1053800Y513833D01*
X1054300Y513750D01*
X1054800Y513417D01*
X1055133Y512833D01*
X1055217Y512167D01*
X1055133Y511500D01*
X1054800Y510917D01*
X1054300Y510583D01*
X1053800Y510500D01*
G01X1060900D02*
Y513833D01*
G01Y513250D02*
X1060567Y513583D01*
X1060067Y513750D01*
X1059483Y513833D01*
X1058900Y513667D01*
X1058400Y513333D01*
X1058067Y512833D01*
X1057900Y512167D01*
X1058067Y511500D01*
X1058400Y511000D01*
X1058900Y510667D01*
X1059483Y510500D01*
X1060067Y510583D01*
X1060567Y510833D01*
X1060900Y511167D01*
G01X1063833Y510500D02*
Y513833D01*
G01Y513167D02*
X1064250Y513500D01*
X1064667Y513750D01*
X1065250Y513833D01*
X1065667Y513750D01*
X1066167Y513500D01*
G01X1072100Y515500D02*
Y510500D01*
G01Y511250D02*
X1071767Y510833D01*
X1071267Y510583D01*
X1070683Y510500D01*
X1070017Y510667D01*
X1069517Y511083D01*
X1069183Y511583D01*
X1069100Y512167D01*
X1069183Y512750D01*
X1069517Y513250D01*
X1070017Y513667D01*
X1070683Y513833D01*
X1071267Y513750D01*
X1071683Y513583D01*
X1072100Y513250D01*
G01X1081800Y515500D02*
Y510500D01*
G01X1080633Y513833D02*
X1082967D01*
G01X1085983Y510500D02*
Y515500D01*
G01Y513083D02*
X1086400Y513500D01*
X1086817Y513750D01*
X1087483Y513833D01*
X1087983Y513750D01*
X1088567Y513417D01*
X1088817Y512917D01*
Y510500D01*
G01X1093000Y513833D02*
Y510500D01*
G01Y515167D02*
X1092833Y515250D01*
Y515417D01*
X1093000Y515500D01*
X1093167Y515417D01*
Y515250D01*
X1093000Y515167D01*
G01X1099933Y513417D02*
X1099350Y513750D01*
X1098850Y513833D01*
X1098183Y513667D01*
X1097683Y513333D01*
X1097350Y512750D01*
X1097267Y512167D01*
X1097350Y511583D01*
X1097683Y511083D01*
X1098183Y510667D01*
X1098850Y510500D01*
X1099433Y510667D01*
X1099933Y511000D01*
G01X1102783Y510500D02*
Y515500D01*
G01X1105450Y513833D02*
X1102783Y511917D01*
G01X1103867Y512667D02*
X1105617Y510500D01*
G01X1108383D02*
Y513833D01*
G01Y513000D02*
X1108717Y513417D01*
X1109217Y513750D01*
X1109883Y513833D01*
X1110467Y513750D01*
X1110967Y513417D01*
X1111217Y512833D01*
Y510500D01*
G01X1114150Y512750D02*
X1116817D01*
X1116567Y513333D01*
X1116150Y513667D01*
X1115567Y513833D01*
X1114983Y513750D01*
X1114483Y513500D01*
X1114150Y512917D01*
X1113983Y512417D01*
Y511917D01*
X1114150Y511417D01*
X1114567Y510917D01*
X1115067Y510583D01*
X1115650Y510500D01*
X1116233Y510667D01*
X1116817Y511167D01*
G01X1119750Y511083D02*
X1120167Y510750D01*
X1120750Y510500D01*
X1121250D01*
X1121750Y510667D01*
X1122083Y510917D01*
X1122250Y511250D01*
X1122167Y511750D01*
X1121833Y512000D01*
X1120333Y512500D01*
X1120000Y513083D01*
X1120167Y513500D01*
X1120500Y513750D01*
X1121000Y513833D01*
X1121500Y513750D01*
X1122000Y513500D01*
G01X1125350Y511083D02*
X1125767Y510750D01*
X1126350Y510500D01*
X1126850D01*
X1127350Y510667D01*
X1127683Y510917D01*
X1127850Y511250D01*
X1127767Y511750D01*
X1127433Y512000D01*
X1125933Y512500D01*
X1125600Y513083D01*
X1125767Y513500D01*
X1126100Y513750D01*
X1126600Y513833D01*
X1127100Y513750D01*
X1127600Y513500D01*
G01X1130533Y510500D02*
X1133867Y512167D01*
X1130533Y513833D01*
G01X1136717Y511417D02*
X1138883D01*
G01Y512917D02*
X1136717D01*
G01X1149000Y515500D02*
X1148333Y515333D01*
X1147833Y514917D01*
X1147500Y514417D01*
X1147250Y513750D01*
X1147167Y513000D01*
X1147250Y512250D01*
X1147500Y511583D01*
X1147833Y511083D01*
X1148333Y510667D01*
X1149000Y510500D01*
X1149667Y510667D01*
X1150167Y511083D01*
X1150500Y511583D01*
X1150750Y512250D01*
X1150833Y513000D01*
X1150750Y513750D01*
X1150500Y514417D01*
X1150167Y514917D01*
X1149667Y515333D01*
X1149000Y515500D01*
G01X1154600Y510333D02*
X1154433Y510417D01*
Y510583D01*
X1154600Y510667D01*
X1154767Y510583D01*
Y510417D01*
X1154600Y510333D01*
G01X1158783Y511083D02*
X1159367Y510667D01*
X1160033Y510500D01*
X1160700Y510667D01*
X1161283Y511167D01*
X1161700Y511917D01*
X1161867Y512667D01*
Y513583D01*
X1161700Y514333D01*
X1161283Y515000D01*
X1160783Y515333D01*
X1160200Y515500D01*
X1159533Y515333D01*
X1159033Y515000D01*
X1158700Y514500D01*
X1158533Y513833D01*
X1158700Y513250D01*
X1159117Y512667D01*
X1159617Y512333D01*
X1160200Y512250D01*
X1160867Y512417D01*
X1161367Y512833D01*
X1161867Y513583D01*
G01X1163300Y510500D02*
Y513833D01*
G01Y512917D02*
X1163550Y513333D01*
X1163967Y513667D01*
X1164550Y513833D01*
X1165133Y513667D01*
X1165550Y513333D01*
X1165800Y512917D01*
Y510500D01*
G01Y512917D02*
X1166050Y513333D01*
X1166467Y513667D01*
X1167050Y513833D01*
X1167633Y513667D01*
X1168050Y513333D01*
X1168300Y512833D01*
Y510500D01*
G01X1171400Y510333D02*
X1171233Y510417D01*
Y510583D01*
X1171400Y510667D01*
X1171567Y510583D01*
Y510417D01*
X1171400Y510333D01*
G01Y512583D02*
X1171233Y512667D01*
Y512833D01*
X1171400Y512917D01*
X1171567Y512833D01*
Y512667D01*
X1171400Y512583D01*
G01X1034250Y520500D02*
Y525500D01*
G01X1037750D02*
Y520500D01*
G01Y523000D02*
X1034250D01*
G01X1043100Y520500D02*
Y523833D01*
G01Y523250D02*
X1042767Y523583D01*
X1042267Y523750D01*
X1041683Y523833D01*
X1041100Y523667D01*
X1040600Y523333D01*
X1040267Y522833D01*
X1040100Y522167D01*
X1040267Y521500D01*
X1040600Y521000D01*
X1041100Y520667D01*
X1041683Y520500D01*
X1042267Y520583D01*
X1042767Y520833D01*
X1043100Y521167D01*
G01X1047200Y520500D02*
Y525500D01*
G01X1052300Y520500D02*
Y524750D01*
X1052467Y525167D01*
X1052800Y525417D01*
X1053300Y525500D01*
X1053800Y525333D01*
X1054050Y524917D01*
G01X1053050Y523500D02*
X1051383D01*
G01X1057317Y522167D02*
X1059483D01*
G01X1062500Y518833D02*
Y523833D01*
G01Y523083D02*
X1062917Y523500D01*
X1063333Y523750D01*
X1064000Y523833D01*
X1064583Y523750D01*
X1065167Y523333D01*
X1065417Y522750D01*
X1065500Y522167D01*
X1065417Y521583D01*
X1065167Y521000D01*
X1064667Y520667D01*
X1064000Y520500D01*
X1063417Y520583D01*
X1062833Y520833D01*
X1062500Y521167D01*
G01X1069600Y520500D02*
Y525500D01*
G01X1073783Y523833D02*
Y521500D01*
X1074117Y520917D01*
X1074617Y520583D01*
X1075200Y520500D01*
X1075783Y520583D01*
X1076283Y520917D01*
X1076617Y521500D01*
G01Y520500D02*
Y523833D01*
G01X1079633Y519250D02*
X1080217Y518917D01*
X1080883Y518833D01*
X1081467Y518917D01*
X1081967Y519333D01*
X1082300Y519917D01*
Y523833D01*
G01Y523167D02*
X1081967Y523500D01*
X1081467Y523750D01*
X1080883Y523833D01*
X1080217Y523667D01*
X1079800Y523333D01*
X1079467Y522750D01*
X1079300Y522167D01*
X1079383Y521667D01*
X1079717Y521083D01*
X1080217Y520667D01*
X1080883Y520500D01*
X1081383Y520583D01*
X1081967Y520917D01*
X1082300Y521250D01*
G01X1085233Y519250D02*
X1085817Y518917D01*
X1086483Y518833D01*
X1087067Y518917D01*
X1087567Y519333D01*
X1087900Y519917D01*
Y523833D01*
G01Y523167D02*
X1087567Y523500D01*
X1087067Y523750D01*
X1086483Y523833D01*
X1085817Y523667D01*
X1085400Y523333D01*
X1085067Y522750D01*
X1084900Y522167D01*
X1084983Y521667D01*
X1085317Y521083D01*
X1085817Y520667D01*
X1086483Y520500D01*
X1086983Y520583D01*
X1087567Y520917D01*
X1087900Y521250D01*
G01X1092000Y523833D02*
Y520500D01*
G01Y525167D02*
X1091833Y525250D01*
Y525417D01*
X1092000Y525500D01*
X1092167Y525417D01*
Y525250D01*
X1092000Y525167D01*
G01X1096183Y520500D02*
Y523833D01*
G01Y523000D02*
X1096517Y523417D01*
X1097017Y523750D01*
X1097683Y523833D01*
X1098267Y523750D01*
X1098767Y523417D01*
X1099017Y522833D01*
Y520500D01*
G01X1102033Y519250D02*
X1102617Y518917D01*
X1103283Y518833D01*
X1103867Y518917D01*
X1104367Y519333D01*
X1104700Y519917D01*
Y523833D01*
G01Y523167D02*
X1104367Y523500D01*
X1103867Y523750D01*
X1103283Y523833D01*
X1102617Y523667D01*
X1102200Y523333D01*
X1101867Y522750D01*
X1101700Y522167D01*
X1101783Y521667D01*
X1102117Y521083D01*
X1102617Y520667D01*
X1103283Y520500D01*
X1103783Y520583D01*
X1104367Y520917D01*
X1104700Y521250D01*
G01X1114400Y520333D02*
X1114233Y520417D01*
Y520583D01*
X1114400Y520667D01*
X1114567Y520583D01*
Y520417D01*
X1114400Y520333D01*
G01Y522583D02*
X1114233Y522667D01*
Y522833D01*
X1114400Y522917D01*
X1114567Y522833D01*
Y522667D01*
X1114400Y522583D01*
G01X1125600Y525500D02*
Y520500D01*
G01X1124433Y523833D02*
X1126767D01*
G01X1129783Y520500D02*
Y525500D01*
G01Y523083D02*
X1130200Y523500D01*
X1130617Y523750D01*
X1131283Y523833D01*
X1131783Y523750D01*
X1132367Y523417D01*
X1132617Y522917D01*
Y520500D01*
G01X1135550Y522750D02*
X1138217D01*
X1137967Y523333D01*
X1137550Y523667D01*
X1136967Y523833D01*
X1136383Y523750D01*
X1135883Y523500D01*
X1135550Y522917D01*
X1135383Y522417D01*
Y521917D01*
X1135550Y521417D01*
X1135967Y520917D01*
X1136467Y520583D01*
X1137050Y520500D01*
X1137633Y520667D01*
X1138217Y521167D01*
G01X1146500Y518833D02*
Y523833D01*
G01Y523083D02*
X1146917Y523500D01*
X1147333Y523750D01*
X1148000Y523833D01*
X1148583Y523750D01*
X1149167Y523333D01*
X1149417Y522750D01*
X1149500Y522167D01*
X1149417Y521583D01*
X1149167Y521000D01*
X1148667Y520667D01*
X1148000Y520500D01*
X1147417Y520583D01*
X1146833Y520833D01*
X1146500Y521167D01*
G01X1153600Y520500D02*
Y525500D01*
G01X1157783Y523833D02*
Y521500D01*
X1158117Y520917D01*
X1158617Y520583D01*
X1159200Y520500D01*
X1159783Y520583D01*
X1160283Y520917D01*
X1160617Y521500D01*
G01Y520500D02*
Y523833D01*
G01X1163633Y519250D02*
X1164217Y518917D01*
X1164883Y518833D01*
X1165467Y518917D01*
X1165967Y519333D01*
X1166300Y519917D01*
Y523833D01*
G01Y523167D02*
X1165967Y523500D01*
X1165467Y523750D01*
X1164883Y523833D01*
X1164217Y523667D01*
X1163800Y523333D01*
X1163467Y522750D01*
X1163300Y522167D01*
X1163383Y521667D01*
X1163717Y521083D01*
X1164217Y520667D01*
X1164883Y520500D01*
X1165383Y520583D01*
X1165967Y520917D01*
X1166300Y521250D01*
G01X1169233Y519250D02*
X1169817Y518917D01*
X1170483Y518833D01*
X1171067Y518917D01*
X1171567Y519333D01*
X1171900Y519917D01*
Y523833D01*
G01Y523167D02*
X1171567Y523500D01*
X1171067Y523750D01*
X1170483Y523833D01*
X1169817Y523667D01*
X1169400Y523333D01*
X1169067Y522750D01*
X1168900Y522167D01*
X1168983Y521667D01*
X1169317Y521083D01*
X1169817Y520667D01*
X1170483Y520500D01*
X1170983Y520583D01*
X1171567Y520917D01*
X1171900Y521250D01*
G01X1176000Y523833D02*
Y520500D01*
G01Y525167D02*
X1175833Y525250D01*
Y525417D01*
X1176000Y525500D01*
X1176167Y525417D01*
Y525250D01*
X1176000Y525167D01*
G01X1180183Y520500D02*
Y523833D01*
G01Y523000D02*
X1180517Y523417D01*
X1181017Y523750D01*
X1181683Y523833D01*
X1182267Y523750D01*
X1182767Y523417D01*
X1183017Y522833D01*
Y520500D01*
G01X1186033Y519250D02*
X1186617Y518917D01*
X1187283Y518833D01*
X1187867Y518917D01*
X1188367Y519333D01*
X1188700Y519917D01*
Y523833D01*
G01Y523167D02*
X1188367Y523500D01*
X1187867Y523750D01*
X1187283Y523833D01*
X1186617Y523667D01*
X1186200Y523333D01*
X1185867Y522750D01*
X1185700Y522167D01*
X1185783Y521667D01*
X1186117Y521083D01*
X1186617Y520667D01*
X1187283Y520500D01*
X1187783Y520583D01*
X1188367Y520917D01*
X1188700Y521250D01*
G01X1197233Y520500D02*
Y523833D01*
G01Y523167D02*
X1197650Y523500D01*
X1198067Y523750D01*
X1198650Y523833D01*
X1199067Y523750D01*
X1199567Y523500D01*
G01X1205500Y520500D02*
Y523833D01*
G01Y523250D02*
X1205167Y523583D01*
X1204667Y523750D01*
X1204083Y523833D01*
X1203500Y523667D01*
X1203000Y523333D01*
X1202667Y522833D01*
X1202500Y522167D01*
X1202667Y521500D01*
X1203000Y521000D01*
X1203500Y520667D01*
X1204083Y520500D01*
X1204667Y520583D01*
X1205167Y520833D01*
X1205500Y521167D01*
G01X1209600Y525500D02*
Y520500D01*
G01X1208433Y523833D02*
X1210767D01*
G01X1215200D02*
Y520500D01*
G01Y525167D02*
X1215033Y525250D01*
Y525417D01*
X1215200Y525500D01*
X1215367Y525417D01*
Y525250D01*
X1215200Y525167D01*
G01X1220800Y520500D02*
X1220300Y520583D01*
X1219800Y520917D01*
X1219467Y521500D01*
X1219300Y522167D01*
X1219467Y522833D01*
X1219800Y523417D01*
X1220300Y523750D01*
X1220800Y523833D01*
X1221300Y523750D01*
X1221800Y523417D01*
X1222133Y522833D01*
X1222217Y522167D01*
X1222133Y521500D01*
X1221800Y520917D01*
X1221300Y520583D01*
X1220800Y520500D01*
G01X1230500Y518833D02*
Y523833D01*
G01Y523083D02*
X1230917Y523500D01*
X1231333Y523750D01*
X1232000Y523833D01*
X1232583Y523750D01*
X1233167Y523333D01*
X1233417Y522750D01*
X1233500Y522167D01*
X1233417Y521583D01*
X1233167Y521000D01*
X1232667Y520667D01*
X1232000Y520500D01*
X1231417Y520583D01*
X1230833Y520833D01*
X1230500Y521167D01*
G01X1236350Y522750D02*
X1239017D01*
X1238767Y523333D01*
X1238350Y523667D01*
X1237767Y523833D01*
X1237183Y523750D01*
X1236683Y523500D01*
X1236350Y522917D01*
X1236183Y522417D01*
Y521917D01*
X1236350Y521417D01*
X1236767Y520917D01*
X1237267Y520583D01*
X1237850Y520500D01*
X1238433Y520667D01*
X1239017Y521167D01*
G01X1242033Y520500D02*
Y523833D01*
G01Y523167D02*
X1242450Y523500D01*
X1242867Y523750D01*
X1243450Y523833D01*
X1243867Y523750D01*
X1244367Y523500D01*
G01X1253900Y520500D02*
Y524750D01*
X1254067Y525167D01*
X1254400Y525417D01*
X1254900Y525500D01*
X1255400Y525333D01*
X1255650Y524917D01*
G01X1254650Y523500D02*
X1252983D01*
G01X1260000Y520500D02*
X1259500Y520583D01*
X1259000Y520917D01*
X1258667Y521500D01*
X1258500Y522167D01*
X1258667Y522833D01*
X1259000Y523417D01*
X1259500Y523750D01*
X1260000Y523833D01*
X1260500Y523750D01*
X1261000Y523417D01*
X1261333Y522833D01*
X1261417Y522167D01*
X1261333Y521500D01*
X1261000Y520917D01*
X1260500Y520583D01*
X1260000Y520500D01*
G01X1265600D02*
Y525500D01*
G01X1271200Y520500D02*
Y525500D01*
G01X1276800Y520500D02*
X1276300Y520583D01*
X1275800Y520917D01*
X1275467Y521500D01*
X1275300Y522167D01*
X1275467Y522833D01*
X1275800Y523417D01*
X1276300Y523750D01*
X1276800Y523833D01*
X1277300Y523750D01*
X1277800Y523417D01*
X1278133Y522833D01*
X1278217Y522167D01*
X1278133Y521500D01*
X1277800Y520917D01*
X1277300Y520583D01*
X1276800Y520500D01*
G01X1280317Y523833D02*
X1281317Y520500D01*
X1282400Y523833D01*
X1283483Y520500D01*
X1284483Y523833D01*
G01X1288000D02*
Y520500D01*
G01Y525167D02*
X1287833Y525250D01*
Y525417D01*
X1288000Y525500D01*
X1288167Y525417D01*
Y525250D01*
X1288000Y525167D01*
G01X1292183Y520500D02*
Y523833D01*
G01Y523000D02*
X1292517Y523417D01*
X1293017Y523750D01*
X1293683Y523833D01*
X1294267Y523750D01*
X1294767Y523417D01*
X1295017Y522833D01*
Y520500D01*
G01X1298033Y519250D02*
X1298617Y518917D01*
X1299283Y518833D01*
X1299867Y518917D01*
X1300367Y519333D01*
X1300700Y519917D01*
Y523833D01*
G01Y523167D02*
X1300367Y523500D01*
X1299867Y523750D01*
X1299283Y523833D01*
X1298617Y523667D01*
X1298200Y523333D01*
X1297867Y522750D01*
X1297700Y522167D01*
X1297783Y521667D01*
X1298117Y521083D01*
X1298617Y520667D01*
X1299283Y520500D01*
X1299783Y520583D01*
X1300367Y520917D01*
X1300700Y521250D01*
G01X1304800Y520333D02*
X1304633Y520417D01*
Y520583D01*
X1304800Y520667D01*
X1304967Y520583D01*
Y520417D01*
X1304800Y520333D01*
G01Y522583D02*
X1304633Y522667D01*
Y522833D01*
X1304800Y522917D01*
X1304967Y522833D01*
Y522667D01*
X1304800Y522583D01*
G01X1033500Y529500D02*
Y534500D01*
G01Y532000D02*
X1033917Y532500D01*
X1034417Y532750D01*
X1034917Y532833D01*
X1035667Y532667D01*
X1036167Y532333D01*
X1036500Y531750D01*
Y531083D01*
X1036333Y530417D01*
X1036000Y529917D01*
X1035417Y529583D01*
X1034917Y529500D01*
X1034417Y529583D01*
X1033917Y529833D01*
X1033500Y530250D01*
G01X1039350Y531750D02*
X1042017D01*
X1041767Y532333D01*
X1041350Y532667D01*
X1040767Y532833D01*
X1040183Y532750D01*
X1039683Y532500D01*
X1039350Y531917D01*
X1039183Y531417D01*
Y530917D01*
X1039350Y530417D01*
X1039767Y529917D01*
X1040267Y529583D01*
X1040850Y529500D01*
X1041433Y529667D01*
X1042017Y530167D01*
G01X1051300Y529500D02*
Y533750D01*
X1051467Y534167D01*
X1051800Y534417D01*
X1052300Y534500D01*
X1052800Y534333D01*
X1053050Y533917D01*
G01X1052050Y532500D02*
X1050383D01*
G01X1056233Y529500D02*
Y532833D01*
G01Y532167D02*
X1056650Y532500D01*
X1057067Y532750D01*
X1057650Y532833D01*
X1058067Y532750D01*
X1058567Y532500D01*
G01X1061750Y531750D02*
X1064417D01*
X1064167Y532333D01*
X1063750Y532667D01*
X1063167Y532833D01*
X1062583Y532750D01*
X1062083Y532500D01*
X1061750Y531917D01*
X1061583Y531417D01*
Y530917D01*
X1061750Y530417D01*
X1062167Y529917D01*
X1062667Y529583D01*
X1063250Y529500D01*
X1063833Y529667D01*
X1064417Y530167D01*
G01X1067350Y531750D02*
X1070017D01*
X1069767Y532333D01*
X1069350Y532667D01*
X1068767Y532833D01*
X1068183Y532750D01*
X1067683Y532500D01*
X1067350Y531917D01*
X1067183Y531417D01*
Y530917D01*
X1067350Y530417D01*
X1067767Y529917D01*
X1068267Y529583D01*
X1068850Y529500D01*
X1069433Y529667D01*
X1070017Y530167D01*
G01X1079300Y529500D02*
Y533750D01*
X1079467Y534167D01*
X1079800Y534417D01*
X1080300Y534500D01*
X1080800Y534333D01*
X1081050Y533917D01*
G01X1080050Y532500D02*
X1078383D01*
G01X1084233Y529500D02*
Y532833D01*
G01Y532167D02*
X1084650Y532500D01*
X1085067Y532750D01*
X1085650Y532833D01*
X1086067Y532750D01*
X1086567Y532500D01*
G01X1091000Y529500D02*
X1090500Y529583D01*
X1090000Y529917D01*
X1089667Y530500D01*
X1089500Y531167D01*
X1089667Y531833D01*
X1090000Y532417D01*
X1090500Y532750D01*
X1091000Y532833D01*
X1091500Y532750D01*
X1092000Y532417D01*
X1092333Y531833D01*
X1092417Y531167D01*
X1092333Y530500D01*
X1092000Y529917D01*
X1091500Y529583D01*
X1091000Y529500D01*
G01X1094100D02*
Y532833D01*
G01Y531917D02*
X1094350Y532333D01*
X1094767Y532667D01*
X1095350Y532833D01*
X1095933Y532667D01*
X1096350Y532333D01*
X1096600Y531917D01*
Y529500D01*
G01Y531917D02*
X1096850Y532333D01*
X1097267Y532667D01*
X1097850Y532833D01*
X1098433Y532667D01*
X1098850Y532333D01*
X1099100Y531833D01*
Y529500D01*
G01X1106550Y530083D02*
X1106967Y529750D01*
X1107550Y529500D01*
X1108050D01*
X1108550Y529667D01*
X1108883Y529917D01*
X1109050Y530250D01*
X1108967Y530750D01*
X1108633Y531000D01*
X1107133Y531500D01*
X1106800Y532083D01*
X1106967Y532500D01*
X1107300Y532750D01*
X1107800Y532833D01*
X1108300Y532750D01*
X1108800Y532500D01*
G01X1113400Y529500D02*
X1112900Y529583D01*
X1112400Y529917D01*
X1112067Y530500D01*
X1111900Y531167D01*
X1112067Y531833D01*
X1112400Y532417D01*
X1112900Y532750D01*
X1113400Y532833D01*
X1113900Y532750D01*
X1114400Y532417D01*
X1114733Y531833D01*
X1114817Y531167D01*
X1114733Y530500D01*
X1114400Y529917D01*
X1113900Y529583D01*
X1113400Y529500D01*
G01X1119000D02*
Y534500D01*
G01X1126100D02*
Y529500D01*
G01Y530250D02*
X1125767Y529833D01*
X1125267Y529583D01*
X1124683Y529500D01*
X1124017Y529667D01*
X1123517Y530083D01*
X1123183Y530583D01*
X1123100Y531167D01*
X1123183Y531750D01*
X1123517Y532250D01*
X1124017Y532667D01*
X1124683Y532833D01*
X1125267Y532750D01*
X1125683Y532583D01*
X1126100Y532250D01*
G01X1128950Y531750D02*
X1131617D01*
X1131367Y532333D01*
X1130950Y532667D01*
X1130367Y532833D01*
X1129783Y532750D01*
X1129283Y532500D01*
X1128950Y531917D01*
X1128783Y531417D01*
Y530917D01*
X1128950Y530417D01*
X1129367Y529917D01*
X1129867Y529583D01*
X1130450Y529500D01*
X1131033Y529667D01*
X1131617Y530167D01*
G01X1134633Y529500D02*
Y532833D01*
G01Y532167D02*
X1135050Y532500D01*
X1135467Y532750D01*
X1136050Y532833D01*
X1136467Y532750D01*
X1136967Y532500D01*
G01X1144500Y529500D02*
Y532833D01*
G01Y531917D02*
X1144750Y532333D01*
X1145167Y532667D01*
X1145750Y532833D01*
X1146333Y532667D01*
X1146750Y532333D01*
X1147000Y531917D01*
Y529500D01*
G01Y531917D02*
X1147250Y532333D01*
X1147667Y532667D01*
X1148250Y532833D01*
X1148833Y532667D01*
X1149250Y532333D01*
X1149500Y531833D01*
Y529500D01*
G01X1154100D02*
Y532833D01*
G01Y532250D02*
X1153767Y532583D01*
X1153267Y532750D01*
X1152683Y532833D01*
X1152100Y532667D01*
X1151600Y532333D01*
X1151267Y531833D01*
X1151100Y531167D01*
X1151267Y530500D01*
X1151600Y530000D01*
X1152100Y529667D01*
X1152683Y529500D01*
X1153267Y529583D01*
X1153767Y529833D01*
X1154100Y530167D01*
G01X1156950Y530083D02*
X1157367Y529750D01*
X1157950Y529500D01*
X1158450D01*
X1158950Y529667D01*
X1159283Y529917D01*
X1159450Y530250D01*
X1159367Y530750D01*
X1159033Y531000D01*
X1157533Y531500D01*
X1157200Y532083D01*
X1157367Y532500D01*
X1157700Y532750D01*
X1158200Y532833D01*
X1158700Y532750D01*
X1159200Y532500D01*
G01X1162383Y529500D02*
Y534500D01*
G01X1165050Y532833D02*
X1162383Y530917D01*
G01X1163467Y531667D02*
X1165217Y529500D01*
G01X1169400Y529333D02*
X1169233Y529417D01*
Y529583D01*
X1169400Y529667D01*
X1169567Y529583D01*
Y529417D01*
X1169400Y529333D01*
G01X1020417Y542667D02*
X1020917Y543167D01*
X1021500Y543417D01*
X1022167Y543500D01*
X1023000Y543333D01*
X1023583Y542917D01*
X1023750Y542417D01*
X1023667Y541917D01*
X1023333Y541500D01*
X1021667Y540667D01*
X1020917Y540083D01*
X1020417Y539250D01*
X1020250Y538500D01*
X1023750D01*
G01X1027600Y538333D02*
X1027433Y538417D01*
Y538583D01*
X1027600Y538667D01*
X1027767Y538583D01*
Y538417D01*
X1027600Y538333D01*
G01X1033200Y543500D02*
Y538500D01*
G01X1031283Y543500D02*
X1035117D01*
G01X1037383Y538500D02*
Y543500D01*
G01Y541083D02*
X1037800Y541500D01*
X1038217Y541750D01*
X1038883Y541833D01*
X1039383Y541750D01*
X1039967Y541417D01*
X1040217Y540917D01*
Y538500D01*
G01X1043150Y540750D02*
X1045817D01*
X1045567Y541333D01*
X1045150Y541667D01*
X1044567Y541833D01*
X1043983Y541750D01*
X1043483Y541500D01*
X1043150Y540917D01*
X1042983Y540417D01*
Y539917D01*
X1043150Y539417D01*
X1043567Y538917D01*
X1044067Y538583D01*
X1044650Y538500D01*
X1045233Y538667D01*
X1045817Y539167D01*
G01X1054350Y539083D02*
X1054767Y538750D01*
X1055350Y538500D01*
X1055850D01*
X1056350Y538667D01*
X1056683Y538917D01*
X1056850Y539250D01*
X1056767Y539750D01*
X1056433Y540000D01*
X1054933Y540500D01*
X1054600Y541083D01*
X1054767Y541500D01*
X1055100Y541750D01*
X1055600Y541833D01*
X1056100Y541750D01*
X1056600Y541500D01*
G01X1061200Y541833D02*
Y538500D01*
G01Y543167D02*
X1061033Y543250D01*
Y543417D01*
X1061200Y543500D01*
X1061367Y543417D01*
Y543250D01*
X1061200Y543167D01*
G01X1068300Y543500D02*
Y538500D01*
G01Y539250D02*
X1067967Y538833D01*
X1067467Y538583D01*
X1066883Y538500D01*
X1066217Y538667D01*
X1065717Y539083D01*
X1065383Y539583D01*
X1065300Y540167D01*
X1065383Y540750D01*
X1065717Y541250D01*
X1066217Y541667D01*
X1066883Y541833D01*
X1067467Y541750D01*
X1067883Y541583D01*
X1068300Y541250D01*
G01X1071150Y540750D02*
X1073817D01*
X1073567Y541333D01*
X1073150Y541667D01*
X1072567Y541833D01*
X1071983Y541750D01*
X1071483Y541500D01*
X1071150Y540917D01*
X1070983Y540417D01*
Y539917D01*
X1071150Y539417D01*
X1071567Y538917D01*
X1072067Y538583D01*
X1072650Y538500D01*
X1073233Y538667D01*
X1073817Y539167D01*
G01X1081517Y541833D02*
X1082517Y538500D01*
X1083600Y541833D01*
X1084683Y538500D01*
X1085683Y541833D01*
G01X1089200D02*
Y538500D01*
G01Y543167D02*
X1089033Y543250D01*
Y543417D01*
X1089200Y543500D01*
X1089367Y543417D01*
Y543250D01*
X1089200Y543167D01*
G01X1094800Y543500D02*
Y538500D01*
G01X1093633Y541833D02*
X1095967D01*
G01X1098983Y538500D02*
Y543500D01*
G01Y541083D02*
X1099400Y541500D01*
X1099817Y541750D01*
X1100483Y541833D01*
X1100983Y541750D01*
X1101567Y541417D01*
X1101817Y540917D01*
Y538500D01*
G01X1110350Y539083D02*
X1110767Y538750D01*
X1111350Y538500D01*
X1111850D01*
X1112350Y538667D01*
X1112683Y538917D01*
X1112850Y539250D01*
X1112767Y539750D01*
X1112433Y540000D01*
X1110933Y540500D01*
X1110600Y541083D01*
X1110767Y541500D01*
X1111100Y541750D01*
X1111600Y541833D01*
X1112100Y541750D01*
X1112600Y541500D01*
G01X1117200Y538500D02*
X1116700Y538583D01*
X1116200Y538917D01*
X1115867Y539500D01*
X1115700Y540167D01*
X1115867Y540833D01*
X1116200Y541417D01*
X1116700Y541750D01*
X1117200Y541833D01*
X1117700Y541750D01*
X1118200Y541417D01*
X1118533Y540833D01*
X1118617Y540167D01*
X1118533Y539500D01*
X1118200Y538917D01*
X1117700Y538583D01*
X1117200Y538500D01*
G01X1122800D02*
Y543500D01*
G01X1129900D02*
Y538500D01*
G01Y539250D02*
X1129567Y538833D01*
X1129067Y538583D01*
X1128483Y538500D01*
X1127817Y538667D01*
X1127317Y539083D01*
X1126983Y539583D01*
X1126900Y540167D01*
X1126983Y540750D01*
X1127317Y541250D01*
X1127817Y541667D01*
X1128483Y541833D01*
X1129067Y541750D01*
X1129483Y541583D01*
X1129900Y541250D01*
G01X1132750Y540750D02*
X1135417D01*
X1135167Y541333D01*
X1134750Y541667D01*
X1134167Y541833D01*
X1133583Y541750D01*
X1133083Y541500D01*
X1132750Y540917D01*
X1132583Y540417D01*
Y539917D01*
X1132750Y539417D01*
X1133167Y538917D01*
X1133667Y538583D01*
X1134250Y538500D01*
X1134833Y538667D01*
X1135417Y539167D01*
G01X1138433Y538500D02*
Y541833D01*
G01Y541167D02*
X1138850Y541500D01*
X1139267Y541750D01*
X1139850Y541833D01*
X1140267Y541750D01*
X1140767Y541500D01*
G01X1148300Y538500D02*
Y541833D01*
G01Y540917D02*
X1148550Y541333D01*
X1148967Y541667D01*
X1149550Y541833D01*
X1150133Y541667D01*
X1150550Y541333D01*
X1150800Y540917D01*
Y538500D01*
G01Y540917D02*
X1151050Y541333D01*
X1151467Y541667D01*
X1152050Y541833D01*
X1152633Y541667D01*
X1153050Y541333D01*
X1153300Y540833D01*
Y538500D01*
G01X1157900D02*
Y541833D01*
G01Y541250D02*
X1157567Y541583D01*
X1157067Y541750D01*
X1156483Y541833D01*
X1155900Y541667D01*
X1155400Y541333D01*
X1155067Y540833D01*
X1154900Y540167D01*
X1155067Y539500D01*
X1155400Y539000D01*
X1155900Y538667D01*
X1156483Y538500D01*
X1157067Y538583D01*
X1157567Y538833D01*
X1157900Y539167D01*
G01X1160750Y539083D02*
X1161167Y538750D01*
X1161750Y538500D01*
X1162250D01*
X1162750Y538667D01*
X1163083Y538917D01*
X1163250Y539250D01*
X1163167Y539750D01*
X1162833Y540000D01*
X1161333Y540500D01*
X1161000Y541083D01*
X1161167Y541500D01*
X1161500Y541750D01*
X1162000Y541833D01*
X1162500Y541750D01*
X1163000Y541500D01*
G01X1166183Y538500D02*
Y543500D01*
G01X1168850Y541833D02*
X1166183Y539917D01*
G01X1167267Y540667D02*
X1169017Y538500D01*
G01X1177300Y536833D02*
Y541833D01*
G01Y541083D02*
X1177717Y541500D01*
X1178133Y541750D01*
X1178800Y541833D01*
X1179383Y541750D01*
X1179967Y541333D01*
X1180217Y540750D01*
X1180300Y540167D01*
X1180217Y539583D01*
X1179967Y539000D01*
X1179467Y538667D01*
X1178800Y538500D01*
X1178217Y538583D01*
X1177633Y538833D01*
X1177300Y539167D01*
G01X1185900Y538500D02*
Y541833D01*
G01Y541250D02*
X1185567Y541583D01*
X1185067Y541750D01*
X1184483Y541833D01*
X1183900Y541667D01*
X1183400Y541333D01*
X1183067Y540833D01*
X1182900Y540167D01*
X1183067Y539500D01*
X1183400Y539000D01*
X1183900Y538667D01*
X1184483Y538500D01*
X1185067Y538583D01*
X1185567Y538833D01*
X1185900Y539167D01*
G01X1191500Y543500D02*
Y538500D01*
G01Y539250D02*
X1191167Y538833D01*
X1190667Y538583D01*
X1190083Y538500D01*
X1189417Y538667D01*
X1188917Y539083D01*
X1188583Y539583D01*
X1188500Y540167D01*
X1188583Y540750D01*
X1188917Y541250D01*
X1189417Y541667D01*
X1190083Y541833D01*
X1190667Y541750D01*
X1191083Y541583D01*
X1191500Y541250D01*
G01X1195433Y537583D02*
X1195767Y538667D01*
G01X1206800Y543500D02*
Y538500D01*
G01X1205633Y541833D02*
X1207967D01*
G01X1210983Y538500D02*
Y543500D01*
G01Y541083D02*
X1211400Y541500D01*
X1211817Y541750D01*
X1212483Y541833D01*
X1212983Y541750D01*
X1213567Y541417D01*
X1213817Y540917D01*
Y538500D01*
G01X1216750Y540750D02*
X1219417D01*
X1219167Y541333D01*
X1218750Y541667D01*
X1218167Y541833D01*
X1217583Y541750D01*
X1217083Y541500D01*
X1216750Y540917D01*
X1216583Y540417D01*
Y539917D01*
X1216750Y539417D01*
X1217167Y538917D01*
X1217667Y538583D01*
X1218250Y538500D01*
X1218833Y538667D01*
X1219417Y539167D01*
G01X1230700Y538500D02*
Y541833D01*
G01Y541250D02*
X1230367Y541583D01*
X1229867Y541750D01*
X1229283Y541833D01*
X1228700Y541667D01*
X1228200Y541333D01*
X1227867Y540833D01*
X1227700Y540167D01*
X1227867Y539500D01*
X1228200Y539000D01*
X1228700Y538667D01*
X1229283Y538500D01*
X1229867Y538583D01*
X1230367Y538833D01*
X1230700Y539167D01*
G01X1233383Y538500D02*
Y541833D01*
G01Y541000D02*
X1233717Y541417D01*
X1234217Y541750D01*
X1234883Y541833D01*
X1235467Y541750D01*
X1235967Y541417D01*
X1236217Y540833D01*
Y538500D01*
G01X1238983D02*
Y541833D01*
G01Y541000D02*
X1239317Y541417D01*
X1239817Y541750D01*
X1240483Y541833D01*
X1241067Y541750D01*
X1241567Y541417D01*
X1241817Y540833D01*
Y538500D01*
G01X1244583Y541833D02*
Y539500D01*
X1244917Y538917D01*
X1245417Y538583D01*
X1246000Y538500D01*
X1246583Y538583D01*
X1247083Y538917D01*
X1247417Y539500D01*
G01Y538500D02*
Y541833D01*
G01X1253100Y538500D02*
Y541833D01*
G01Y541250D02*
X1252767Y541583D01*
X1252267Y541750D01*
X1251683Y541833D01*
X1251100Y541667D01*
X1250600Y541333D01*
X1250267Y540833D01*
X1250100Y540167D01*
X1250267Y539500D01*
X1250600Y539000D01*
X1251100Y538667D01*
X1251683Y538500D01*
X1252267Y538583D01*
X1252767Y538833D01*
X1253100Y539167D01*
G01X1257200Y538500D02*
Y543500D01*
G01X1267233Y538500D02*
Y541833D01*
G01Y541167D02*
X1267650Y541500D01*
X1268067Y541750D01*
X1268650Y541833D01*
X1269067Y541750D01*
X1269567Y541500D01*
G01X1274000Y541833D02*
Y538500D01*
G01Y543167D02*
X1273833Y543250D01*
Y543417D01*
X1274000Y543500D01*
X1274167Y543417D01*
Y543250D01*
X1274000Y543167D01*
G01X1278183Y538500D02*
Y541833D01*
G01Y541000D02*
X1278517Y541417D01*
X1279017Y541750D01*
X1279683Y541833D01*
X1280267Y541750D01*
X1280767Y541417D01*
X1281017Y540833D01*
Y538500D01*
G01X1284033Y537250D02*
X1284617Y536917D01*
X1285283Y536833D01*
X1285867Y536917D01*
X1286367Y537333D01*
X1286700Y537917D01*
Y541833D01*
G01Y541167D02*
X1286367Y541500D01*
X1285867Y541750D01*
X1285283Y541833D01*
X1284617Y541667D01*
X1284200Y541333D01*
X1283867Y540750D01*
X1283700Y540167D01*
X1283783Y539667D01*
X1284117Y539083D01*
X1284617Y538667D01*
X1285283Y538500D01*
X1285783Y538583D01*
X1286367Y538917D01*
X1286700Y539250D01*
G01X1295150Y539083D02*
X1295567Y538750D01*
X1296150Y538500D01*
X1296650D01*
X1297150Y538667D01*
X1297483Y538917D01*
X1297650Y539250D01*
X1297567Y539750D01*
X1297233Y540000D01*
X1295733Y540500D01*
X1295400Y541083D01*
X1295567Y541500D01*
X1295900Y541750D01*
X1296400Y541833D01*
X1296900Y541750D01*
X1297400Y541500D01*
G01X1300583Y538500D02*
Y543500D01*
G01Y541083D02*
X1301000Y541500D01*
X1301417Y541750D01*
X1302083Y541833D01*
X1302583Y541750D01*
X1303167Y541417D01*
X1303417Y540917D01*
Y538500D01*
G01X1307600D02*
X1307100Y538583D01*
X1306600Y538917D01*
X1306267Y539500D01*
X1306100Y540167D01*
X1306267Y540833D01*
X1306600Y541417D01*
X1307100Y541750D01*
X1307600Y541833D01*
X1308100Y541750D01*
X1308600Y541417D01*
X1308933Y540833D01*
X1309017Y540167D01*
X1308933Y539500D01*
X1308600Y538917D01*
X1308100Y538583D01*
X1307600Y538500D01*
G01X1311783Y541833D02*
Y539500D01*
X1312117Y538917D01*
X1312617Y538583D01*
X1313200Y538500D01*
X1313783Y538583D01*
X1314283Y538917D01*
X1314617Y539500D01*
G01Y538500D02*
Y541833D01*
G01X1318800Y538500D02*
Y543500D01*
G01X1325900D02*
Y538500D01*
G01Y539250D02*
X1325567Y538833D01*
X1325067Y538583D01*
X1324483Y538500D01*
X1323817Y538667D01*
X1323317Y539083D01*
X1322983Y539583D01*
X1322900Y540167D01*
X1322983Y540750D01*
X1323317Y541250D01*
X1323817Y541667D01*
X1324483Y541833D01*
X1325067Y541750D01*
X1325483Y541583D01*
X1325900Y541250D01*
G01X1032500Y552500D02*
Y557500D01*
G01Y555000D02*
X1032917Y555500D01*
X1033417Y555750D01*
X1033917Y555833D01*
X1034667Y555667D01*
X1035167Y555333D01*
X1035500Y554750D01*
Y554083D01*
X1035333Y553417D01*
X1035000Y552917D01*
X1034417Y552583D01*
X1033917Y552500D01*
X1033417Y552583D01*
X1032917Y552833D01*
X1032500Y553250D01*
G01X1038350Y554750D02*
X1041017D01*
X1040767Y555333D01*
X1040350Y555667D01*
X1039767Y555833D01*
X1039183Y555750D01*
X1038683Y555500D01*
X1038350Y554917D01*
X1038183Y554417D01*
Y553917D01*
X1038350Y553417D01*
X1038767Y552917D01*
X1039267Y552583D01*
X1039850Y552500D01*
X1040433Y552667D01*
X1041017Y553167D01*
G01X1050800Y557500D02*
Y552500D01*
G01X1049633Y555833D02*
X1051967D01*
G01X1055150Y554750D02*
X1057817D01*
X1057567Y555333D01*
X1057150Y555667D01*
X1056567Y555833D01*
X1055983Y555750D01*
X1055483Y555500D01*
X1055150Y554917D01*
X1054983Y554417D01*
Y553917D01*
X1055150Y553417D01*
X1055567Y552917D01*
X1056067Y552583D01*
X1056650Y552500D01*
X1057233Y552667D01*
X1057817Y553167D01*
G01X1060583Y552500D02*
Y555833D01*
G01Y555000D02*
X1060917Y555417D01*
X1061417Y555750D01*
X1062083Y555833D01*
X1062667Y555750D01*
X1063167Y555417D01*
X1063417Y554833D01*
Y552500D01*
G01X1067600Y557500D02*
Y552500D01*
G01X1066433Y555833D02*
X1068767D01*
G01X1071950Y554750D02*
X1074617D01*
X1074367Y555333D01*
X1073950Y555667D01*
X1073367Y555833D01*
X1072783Y555750D01*
X1072283Y555500D01*
X1071950Y554917D01*
X1071783Y554417D01*
Y553917D01*
X1071950Y553417D01*
X1072367Y552917D01*
X1072867Y552583D01*
X1073450Y552500D01*
X1074033Y552667D01*
X1074617Y553167D01*
G01X1080300Y557500D02*
Y552500D01*
G01Y553250D02*
X1079967Y552833D01*
X1079467Y552583D01*
X1078883Y552500D01*
X1078217Y552667D01*
X1077717Y553083D01*
X1077383Y553583D01*
X1077300Y554167D01*
X1077383Y554750D01*
X1077717Y555250D01*
X1078217Y555667D01*
X1078883Y555833D01*
X1079467Y555750D01*
X1079883Y555583D01*
X1080300Y555250D01*
G01X1087917Y555833D02*
X1088917Y552500D01*
X1090000Y555833D01*
X1091083Y552500D01*
X1092083Y555833D01*
G01X1095600D02*
Y552500D01*
G01Y557167D02*
X1095433Y557250D01*
Y557417D01*
X1095600Y557500D01*
X1095767Y557417D01*
Y557250D01*
X1095600Y557167D01*
G01X1101200Y557500D02*
Y552500D01*
G01X1100033Y555833D02*
X1102367D01*
G01X1105383Y552500D02*
Y557500D01*
G01Y555083D02*
X1105800Y555500D01*
X1106217Y555750D01*
X1106883Y555833D01*
X1107383Y555750D01*
X1107967Y555417D01*
X1108217Y554917D01*
Y552500D01*
G01X1116750Y553083D02*
X1117167Y552750D01*
X1117750Y552500D01*
X1118250D01*
X1118750Y552667D01*
X1119083Y552917D01*
X1119250Y553250D01*
X1119167Y553750D01*
X1118833Y554000D01*
X1117333Y554500D01*
X1117000Y555083D01*
X1117167Y555500D01*
X1117500Y555750D01*
X1118000Y555833D01*
X1118500Y555750D01*
X1119000Y555500D01*
G01X1123600Y552500D02*
X1123100Y552583D01*
X1122600Y552917D01*
X1122267Y553500D01*
X1122100Y554167D01*
X1122267Y554833D01*
X1122600Y555417D01*
X1123100Y555750D01*
X1123600Y555833D01*
X1124100Y555750D01*
X1124600Y555417D01*
X1124933Y554833D01*
X1125017Y554167D01*
X1124933Y553500D01*
X1124600Y552917D01*
X1124100Y552583D01*
X1123600Y552500D01*
G01X1129200D02*
Y557500D01*
G01X1136300D02*
Y552500D01*
G01Y553250D02*
X1135967Y552833D01*
X1135467Y552583D01*
X1134883Y552500D01*
X1134217Y552667D01*
X1133717Y553083D01*
X1133383Y553583D01*
X1133300Y554167D01*
X1133383Y554750D01*
X1133717Y555250D01*
X1134217Y555667D01*
X1134883Y555833D01*
X1135467Y555750D01*
X1135883Y555583D01*
X1136300Y555250D01*
G01X1139150Y554750D02*
X1141817D01*
X1141567Y555333D01*
X1141150Y555667D01*
X1140567Y555833D01*
X1139983Y555750D01*
X1139483Y555500D01*
X1139150Y554917D01*
X1138983Y554417D01*
Y553917D01*
X1139150Y553417D01*
X1139567Y552917D01*
X1140067Y552583D01*
X1140650Y552500D01*
X1141233Y552667D01*
X1141817Y553167D01*
G01X1144833Y552500D02*
Y555833D01*
G01Y555167D02*
X1145250Y555500D01*
X1145667Y555750D01*
X1146250Y555833D01*
X1146667Y555750D01*
X1147167Y555500D01*
G01X1154700Y552500D02*
Y555833D01*
G01Y554917D02*
X1154950Y555333D01*
X1155367Y555667D01*
X1155950Y555833D01*
X1156533Y555667D01*
X1156950Y555333D01*
X1157200Y554917D01*
Y552500D01*
G01Y554917D02*
X1157450Y555333D01*
X1157867Y555667D01*
X1158450Y555833D01*
X1159033Y555667D01*
X1159450Y555333D01*
X1159700Y554833D01*
Y552500D01*
G01X1164300D02*
Y555833D01*
G01Y555250D02*
X1163967Y555583D01*
X1163467Y555750D01*
X1162883Y555833D01*
X1162300Y555667D01*
X1161800Y555333D01*
X1161467Y554833D01*
X1161300Y554167D01*
X1161467Y553500D01*
X1161800Y553000D01*
X1162300Y552667D01*
X1162883Y552500D01*
X1163467Y552583D01*
X1163967Y552833D01*
X1164300Y553167D01*
G01X1167150Y553083D02*
X1167567Y552750D01*
X1168150Y552500D01*
X1168650D01*
X1169150Y552667D01*
X1169483Y552917D01*
X1169650Y553250D01*
X1169567Y553750D01*
X1169233Y554000D01*
X1167733Y554500D01*
X1167400Y555083D01*
X1167567Y555500D01*
X1167900Y555750D01*
X1168400Y555833D01*
X1168900Y555750D01*
X1169400Y555500D01*
G01X1172583Y552500D02*
Y557500D01*
G01X1175250Y555833D02*
X1172583Y553917D01*
G01X1173667Y554667D02*
X1175417Y552500D01*
G01X1179600Y552333D02*
X1179433Y552417D01*
Y552583D01*
X1179600Y552667D01*
X1179767Y552583D01*
Y552417D01*
X1179600Y552333D01*
G01X1034000Y566500D02*
Y561500D01*
G01X1032833Y564833D02*
X1035167D01*
G01X1039600Y561500D02*
X1039100Y561583D01*
X1038600Y561917D01*
X1038267Y562500D01*
X1038100Y563167D01*
X1038267Y563833D01*
X1038600Y564417D01*
X1039100Y564750D01*
X1039600Y564833D01*
X1040100Y564750D01*
X1040600Y564417D01*
X1040933Y563833D01*
X1041017Y563167D01*
X1040933Y562500D01*
X1040600Y561917D01*
X1040100Y561583D01*
X1039600Y561500D01*
G01X1049300D02*
Y566500D01*
G01Y564000D02*
X1049717Y564500D01*
X1050217Y564750D01*
X1050717Y564833D01*
X1051467Y564667D01*
X1051967Y564333D01*
X1052300Y563750D01*
Y563083D01*
X1052133Y562417D01*
X1051800Y561917D01*
X1051217Y561583D01*
X1050717Y561500D01*
X1050217Y561583D01*
X1049717Y561833D01*
X1049300Y562250D01*
G01X1055150Y563750D02*
X1057817D01*
X1057567Y564333D01*
X1057150Y564667D01*
X1056567Y564833D01*
X1055983Y564750D01*
X1055483Y564500D01*
X1055150Y563917D01*
X1054983Y563417D01*
Y562917D01*
X1055150Y562417D01*
X1055567Y561917D01*
X1056067Y561583D01*
X1056650Y561500D01*
X1057233Y561667D01*
X1057817Y562167D01*
G01X1068933Y564417D02*
X1068350Y564750D01*
X1067850Y564833D01*
X1067183Y564667D01*
X1066683Y564333D01*
X1066350Y563750D01*
X1066267Y563167D01*
X1066350Y562583D01*
X1066683Y562083D01*
X1067183Y561667D01*
X1067850Y561500D01*
X1068433Y561667D01*
X1068933Y562000D01*
G01X1073200Y561500D02*
X1072700Y561583D01*
X1072200Y561917D01*
X1071867Y562500D01*
X1071700Y563167D01*
X1071867Y563833D01*
X1072200Y564417D01*
X1072700Y564750D01*
X1073200Y564833D01*
X1073700Y564750D01*
X1074200Y564417D01*
X1074533Y563833D01*
X1074617Y563167D01*
X1074533Y562500D01*
X1074200Y561917D01*
X1073700Y561583D01*
X1073200Y561500D01*
G01X1077300Y564833D02*
X1078800Y561500D01*
X1080300Y564833D01*
G01X1083150Y563750D02*
X1085817D01*
X1085567Y564333D01*
X1085150Y564667D01*
X1084567Y564833D01*
X1083983Y564750D01*
X1083483Y564500D01*
X1083150Y563917D01*
X1082983Y563417D01*
Y562917D01*
X1083150Y562417D01*
X1083567Y561917D01*
X1084067Y561583D01*
X1084650Y561500D01*
X1085233Y561667D01*
X1085817Y562167D01*
G01X1088833Y561500D02*
Y564833D01*
G01Y564167D02*
X1089250Y564500D01*
X1089667Y564750D01*
X1090250Y564833D01*
X1090667Y564750D01*
X1091167Y564500D01*
G01X1094350Y563750D02*
X1097017D01*
X1096767Y564333D01*
X1096350Y564667D01*
X1095767Y564833D01*
X1095183Y564750D01*
X1094683Y564500D01*
X1094350Y563917D01*
X1094183Y563417D01*
Y562917D01*
X1094350Y562417D01*
X1094767Y561917D01*
X1095267Y561583D01*
X1095850Y561500D01*
X1096433Y561667D01*
X1097017Y562167D01*
G01X1102700Y566500D02*
Y561500D01*
G01Y562250D02*
X1102367Y561833D01*
X1101867Y561583D01*
X1101283Y561500D01*
X1100617Y561667D01*
X1100117Y562083D01*
X1099783Y562583D01*
X1099700Y563167D01*
X1099783Y563750D01*
X1100117Y564250D01*
X1100617Y564667D01*
X1101283Y564833D01*
X1101867Y564750D01*
X1102283Y564583D01*
X1102700Y564250D01*
G01X1110900Y561500D02*
Y566500D01*
G01Y564000D02*
X1111317Y564500D01*
X1111817Y564750D01*
X1112317Y564833D01*
X1113067Y564667D01*
X1113567Y564333D01*
X1113900Y563750D01*
Y563083D01*
X1113733Y562417D01*
X1113400Y561917D01*
X1112817Y561583D01*
X1112317Y561500D01*
X1111817Y561583D01*
X1111317Y561833D01*
X1110900Y562250D01*
G01X1116250Y560000D02*
X1116750Y559833D01*
X1117417Y560000D01*
X1117833Y560333D01*
X1118167Y560750D01*
X1118667Y562083D01*
X1119750Y564833D01*
G01X1117083D02*
X1118667Y562083D01*
G01X1127950D02*
X1128367Y561750D01*
X1128950Y561500D01*
X1129450D01*
X1129950Y561667D01*
X1130283Y561917D01*
X1130450Y562250D01*
X1130367Y562750D01*
X1130033Y563000D01*
X1128533Y563500D01*
X1128200Y564083D01*
X1128367Y564500D01*
X1128700Y564750D01*
X1129200Y564833D01*
X1129700Y564750D01*
X1130200Y564500D01*
G01X1134800Y561500D02*
X1134300Y561583D01*
X1133800Y561917D01*
X1133467Y562500D01*
X1133300Y563167D01*
X1133467Y563833D01*
X1133800Y564417D01*
X1134300Y564750D01*
X1134800Y564833D01*
X1135300Y564750D01*
X1135800Y564417D01*
X1136133Y563833D01*
X1136217Y563167D01*
X1136133Y562500D01*
X1135800Y561917D01*
X1135300Y561583D01*
X1134800Y561500D01*
G01X1140400D02*
Y566500D01*
G01X1147500D02*
Y561500D01*
G01Y562250D02*
X1147167Y561833D01*
X1146667Y561583D01*
X1146083Y561500D01*
X1145417Y561667D01*
X1144917Y562083D01*
X1144583Y562583D01*
X1144500Y563167D01*
X1144583Y563750D01*
X1144917Y564250D01*
X1145417Y564667D01*
X1146083Y564833D01*
X1146667Y564750D01*
X1147083Y564583D01*
X1147500Y564250D01*
G01X1150350Y563750D02*
X1153017D01*
X1152767Y564333D01*
X1152350Y564667D01*
X1151767Y564833D01*
X1151183Y564750D01*
X1150683Y564500D01*
X1150350Y563917D01*
X1150183Y563417D01*
Y562917D01*
X1150350Y562417D01*
X1150767Y561917D01*
X1151267Y561583D01*
X1151850Y561500D01*
X1152433Y561667D01*
X1153017Y562167D01*
G01X1156033Y561500D02*
Y564833D01*
G01Y564167D02*
X1156450Y564500D01*
X1156867Y564750D01*
X1157450Y564833D01*
X1157867Y564750D01*
X1158367Y564500D01*
G01X1165900Y561500D02*
Y564833D01*
G01Y563917D02*
X1166150Y564333D01*
X1166567Y564667D01*
X1167150Y564833D01*
X1167733Y564667D01*
X1168150Y564333D01*
X1168400Y563917D01*
Y561500D01*
G01Y563917D02*
X1168650Y564333D01*
X1169067Y564667D01*
X1169650Y564833D01*
X1170233Y564667D01*
X1170650Y564333D01*
X1170900Y563833D01*
Y561500D01*
G01X1175500D02*
Y564833D01*
G01Y564250D02*
X1175167Y564583D01*
X1174667Y564750D01*
X1174083Y564833D01*
X1173500Y564667D01*
X1173000Y564333D01*
X1172667Y563833D01*
X1172500Y563167D01*
X1172667Y562500D01*
X1173000Y562000D01*
X1173500Y561667D01*
X1174083Y561500D01*
X1174667Y561583D01*
X1175167Y561833D01*
X1175500Y562167D01*
G01X1178350Y562083D02*
X1178767Y561750D01*
X1179350Y561500D01*
X1179850D01*
X1180350Y561667D01*
X1180683Y561917D01*
X1180850Y562250D01*
X1180767Y562750D01*
X1180433Y563000D01*
X1178933Y563500D01*
X1178600Y564083D01*
X1178767Y564500D01*
X1179100Y564750D01*
X1179600Y564833D01*
X1180100Y564750D01*
X1180600Y564500D01*
G01X1183783Y561500D02*
Y566500D01*
G01X1186450Y564833D02*
X1183783Y562917D01*
G01X1184867Y563667D02*
X1186617Y561500D01*
G01X1197900D02*
Y564833D01*
G01Y564250D02*
X1197567Y564583D01*
X1197067Y564750D01*
X1196483Y564833D01*
X1195900Y564667D01*
X1195400Y564333D01*
X1195067Y563833D01*
X1194900Y563167D01*
X1195067Y562500D01*
X1195400Y562000D01*
X1195900Y561667D01*
X1196483Y561500D01*
X1197067Y561583D01*
X1197567Y561833D01*
X1197900Y562167D01*
G01X1200583Y561500D02*
Y564833D01*
G01Y564000D02*
X1200917Y564417D01*
X1201417Y564750D01*
X1202083Y564833D01*
X1202667Y564750D01*
X1203167Y564417D01*
X1203417Y563833D01*
Y561500D01*
G01X1209100Y566500D02*
Y561500D01*
G01Y562250D02*
X1208767Y561833D01*
X1208267Y561583D01*
X1207683Y561500D01*
X1207017Y561667D01*
X1206517Y562083D01*
X1206183Y562583D01*
X1206100Y563167D01*
X1206183Y563750D01*
X1206517Y564250D01*
X1207017Y564667D01*
X1207683Y564833D01*
X1208267Y564750D01*
X1208683Y564583D01*
X1209100Y564250D01*
G01X1217383Y561500D02*
Y566500D01*
G01Y564083D02*
X1217800Y564500D01*
X1218217Y564750D01*
X1218883Y564833D01*
X1219383Y564750D01*
X1219967Y564417D01*
X1220217Y563917D01*
Y561500D01*
G01X1224400D02*
X1223900Y561583D01*
X1223400Y561917D01*
X1223067Y562500D01*
X1222900Y563167D01*
X1223067Y563833D01*
X1223400Y564417D01*
X1223900Y564750D01*
X1224400Y564833D01*
X1224900Y564750D01*
X1225400Y564417D01*
X1225733Y563833D01*
X1225817Y563167D01*
X1225733Y562500D01*
X1225400Y561917D01*
X1224900Y561583D01*
X1224400Y561500D01*
G01X1230000D02*
Y566500D01*
G01X1234350Y563750D02*
X1237017D01*
X1236767Y564333D01*
X1236350Y564667D01*
X1235767Y564833D01*
X1235183Y564750D01*
X1234683Y564500D01*
X1234350Y563917D01*
X1234183Y563417D01*
Y562917D01*
X1234350Y562417D01*
X1234767Y561917D01*
X1235267Y561583D01*
X1235850Y561500D01*
X1236433Y561667D01*
X1237017Y562167D01*
G01X1248300Y561500D02*
Y564833D01*
G01Y564250D02*
X1247967Y564583D01*
X1247467Y564750D01*
X1246883Y564833D01*
X1246300Y564667D01*
X1245800Y564333D01*
X1245467Y563833D01*
X1245300Y563167D01*
X1245467Y562500D01*
X1245800Y562000D01*
X1246300Y561667D01*
X1246883Y561500D01*
X1247467Y561583D01*
X1247967Y561833D01*
X1248300Y562167D01*
G01X1252400Y561500D02*
Y566500D01*
G01X1256750Y562083D02*
X1257167Y561750D01*
X1257750Y561500D01*
X1258250D01*
X1258750Y561667D01*
X1259083Y561917D01*
X1259250Y562250D01*
X1259167Y562750D01*
X1258833Y563000D01*
X1257333Y563500D01*
X1257000Y564083D01*
X1257167Y564500D01*
X1257500Y564750D01*
X1258000Y564833D01*
X1258500Y564750D01*
X1259000Y564500D01*
G01X1263600Y561500D02*
X1263100Y561583D01*
X1262600Y561917D01*
X1262267Y562500D01*
X1262100Y563167D01*
X1262267Y563833D01*
X1262600Y564417D01*
X1263100Y564750D01*
X1263600Y564833D01*
X1264100Y564750D01*
X1264600Y564417D01*
X1264933Y563833D01*
X1265017Y563167D01*
X1264933Y562500D01*
X1264600Y561917D01*
X1264100Y561583D01*
X1263600Y561500D01*
G01X1273383D02*
Y564833D01*
G01Y564000D02*
X1273717Y564417D01*
X1274217Y564750D01*
X1274883Y564833D01*
X1275467Y564750D01*
X1275967Y564417D01*
X1276217Y563833D01*
Y561500D01*
G01X1279150Y563750D02*
X1281817D01*
X1281567Y564333D01*
X1281150Y564667D01*
X1280567Y564833D01*
X1279983Y564750D01*
X1279483Y564500D01*
X1279150Y563917D01*
X1278983Y563417D01*
Y562917D01*
X1279150Y562417D01*
X1279567Y561917D01*
X1280067Y561583D01*
X1280650Y561500D01*
X1281233Y561667D01*
X1281817Y562167D01*
G01X1284750Y563750D02*
X1287417D01*
X1287167Y564333D01*
X1286750Y564667D01*
X1286167Y564833D01*
X1285583Y564750D01*
X1285083Y564500D01*
X1284750Y563917D01*
X1284583Y563417D01*
Y562917D01*
X1284750Y562417D01*
X1285167Y561917D01*
X1285667Y561583D01*
X1286250Y561500D01*
X1286833Y561667D01*
X1287417Y562167D01*
G01X1293100Y566500D02*
Y561500D01*
G01Y562250D02*
X1292767Y561833D01*
X1292267Y561583D01*
X1291683Y561500D01*
X1291017Y561667D01*
X1290517Y562083D01*
X1290183Y562583D01*
X1290100Y563167D01*
X1290183Y563750D01*
X1290517Y564250D01*
X1291017Y564667D01*
X1291683Y564833D01*
X1292267Y564750D01*
X1292683Y564583D01*
X1293100Y564250D01*
G01X1302800Y566500D02*
Y561500D01*
G01X1301633Y564833D02*
X1303967D01*
G01X1308400Y561500D02*
X1307900Y561583D01*
X1307400Y561917D01*
X1307067Y562500D01*
X1306900Y563167D01*
X1307067Y563833D01*
X1307400Y564417D01*
X1307900Y564750D01*
X1308400Y564833D01*
X1308900Y564750D01*
X1309400Y564417D01*
X1309733Y563833D01*
X1309817Y563167D01*
X1309733Y562500D01*
X1309400Y561917D01*
X1308900Y561583D01*
X1308400Y561500D01*
G01X1022000Y569500D02*
Y574500D01*
X1021000Y573500D01*
G01Y569500D02*
X1023000D01*
G01X1027600Y569333D02*
X1027433Y569417D01*
Y569583D01*
X1027600Y569667D01*
X1027767Y569583D01*
Y569417D01*
X1027600Y569333D01*
G01X1033200Y574500D02*
Y569500D01*
G01X1031283Y574500D02*
X1035117D01*
G01X1037383Y569500D02*
Y574500D01*
G01Y572083D02*
X1037800Y572500D01*
X1038217Y572750D01*
X1038883Y572833D01*
X1039383Y572750D01*
X1039967Y572417D01*
X1040217Y571917D01*
Y569500D01*
G01X1043150Y571750D02*
X1045817D01*
X1045567Y572333D01*
X1045150Y572667D01*
X1044567Y572833D01*
X1043983Y572750D01*
X1043483Y572500D01*
X1043150Y571917D01*
X1042983Y571417D01*
Y570917D01*
X1043150Y570417D01*
X1043567Y569917D01*
X1044067Y569583D01*
X1044650Y569500D01*
X1045233Y569667D01*
X1045817Y570167D01*
G01X1054350Y570083D02*
X1054767Y569750D01*
X1055350Y569500D01*
X1055850D01*
X1056350Y569667D01*
X1056683Y569917D01*
X1056850Y570250D01*
X1056767Y570750D01*
X1056433Y571000D01*
X1054933Y571500D01*
X1054600Y572083D01*
X1054767Y572500D01*
X1055100Y572750D01*
X1055600Y572833D01*
X1056100Y572750D01*
X1056600Y572500D01*
G01X1061200Y572833D02*
Y569500D01*
G01Y574167D02*
X1061033Y574250D01*
Y574417D01*
X1061200Y574500D01*
X1061367Y574417D01*
Y574250D01*
X1061200Y574167D01*
G01X1068300Y574500D02*
Y569500D01*
G01Y570250D02*
X1067967Y569833D01*
X1067467Y569583D01*
X1066883Y569500D01*
X1066217Y569667D01*
X1065717Y570083D01*
X1065383Y570583D01*
X1065300Y571167D01*
X1065383Y571750D01*
X1065717Y572250D01*
X1066217Y572667D01*
X1066883Y572833D01*
X1067467Y572750D01*
X1067883Y572583D01*
X1068300Y572250D01*
G01X1071150Y571750D02*
X1073817D01*
X1073567Y572333D01*
X1073150Y572667D01*
X1072567Y572833D01*
X1071983Y572750D01*
X1071483Y572500D01*
X1071150Y571917D01*
X1070983Y571417D01*
Y570917D01*
X1071150Y570417D01*
X1071567Y569917D01*
X1072067Y569583D01*
X1072650Y569500D01*
X1073233Y569667D01*
X1073817Y570167D01*
G01X1081517Y572833D02*
X1082517Y569500D01*
X1083600Y572833D01*
X1084683Y569500D01*
X1085683Y572833D01*
G01X1089200D02*
Y569500D01*
G01Y574167D02*
X1089033Y574250D01*
Y574417D01*
X1089200Y574500D01*
X1089367Y574417D01*
Y574250D01*
X1089200Y574167D01*
G01X1094800Y574500D02*
Y569500D01*
G01X1093633Y572833D02*
X1095967D01*
G01X1098983Y569500D02*
Y574500D01*
G01Y572083D02*
X1099400Y572500D01*
X1099817Y572750D01*
X1100483Y572833D01*
X1100983Y572750D01*
X1101567Y572417D01*
X1101817Y571917D01*
Y569500D01*
G01X1106000D02*
X1105500Y569583D01*
X1105000Y569917D01*
X1104667Y570500D01*
X1104500Y571167D01*
X1104667Y571833D01*
X1105000Y572417D01*
X1105500Y572750D01*
X1106000Y572833D01*
X1106500Y572750D01*
X1107000Y572417D01*
X1107333Y571833D01*
X1107417Y571167D01*
X1107333Y570500D01*
X1107000Y569917D01*
X1106500Y569583D01*
X1106000Y569500D01*
G01X1110183Y572833D02*
Y570500D01*
X1110517Y569917D01*
X1111017Y569583D01*
X1111600Y569500D01*
X1112183Y569583D01*
X1112683Y569917D01*
X1113017Y570500D01*
G01Y569500D02*
Y572833D01*
G01X1117200Y574500D02*
Y569500D01*
G01X1116033Y572833D02*
X1118367D01*
G01X1127150Y570083D02*
X1127567Y569750D01*
X1128150Y569500D01*
X1128650D01*
X1129150Y569667D01*
X1129483Y569917D01*
X1129650Y570250D01*
X1129567Y570750D01*
X1129233Y571000D01*
X1127733Y571500D01*
X1127400Y572083D01*
X1127567Y572500D01*
X1127900Y572750D01*
X1128400Y572833D01*
X1128900Y572750D01*
X1129400Y572500D01*
G01X1134000Y569500D02*
X1133500Y569583D01*
X1133000Y569917D01*
X1132667Y570500D01*
X1132500Y571167D01*
X1132667Y571833D01*
X1133000Y572417D01*
X1133500Y572750D01*
X1134000Y572833D01*
X1134500Y572750D01*
X1135000Y572417D01*
X1135333Y571833D01*
X1135417Y571167D01*
X1135333Y570500D01*
X1135000Y569917D01*
X1134500Y569583D01*
X1134000Y569500D01*
G01X1139600D02*
Y574500D01*
G01X1146700D02*
Y569500D01*
G01Y570250D02*
X1146367Y569833D01*
X1145867Y569583D01*
X1145283Y569500D01*
X1144617Y569667D01*
X1144117Y570083D01*
X1143783Y570583D01*
X1143700Y571167D01*
X1143783Y571750D01*
X1144117Y572250D01*
X1144617Y572667D01*
X1145283Y572833D01*
X1145867Y572750D01*
X1146283Y572583D01*
X1146700Y572250D01*
G01X1149550Y571750D02*
X1152217D01*
X1151967Y572333D01*
X1151550Y572667D01*
X1150967Y572833D01*
X1150383Y572750D01*
X1149883Y572500D01*
X1149550Y571917D01*
X1149383Y571417D01*
Y570917D01*
X1149550Y570417D01*
X1149967Y569917D01*
X1150467Y569583D01*
X1151050Y569500D01*
X1151633Y569667D01*
X1152217Y570167D01*
G01X1155233Y569500D02*
Y572833D01*
G01Y572167D02*
X1155650Y572500D01*
X1156067Y572750D01*
X1156650Y572833D01*
X1157067Y572750D01*
X1157567Y572500D01*
G01X1165100Y569500D02*
Y572833D01*
G01Y571917D02*
X1165350Y572333D01*
X1165767Y572667D01*
X1166350Y572833D01*
X1166933Y572667D01*
X1167350Y572333D01*
X1167600Y571917D01*
Y569500D01*
G01Y571917D02*
X1167850Y572333D01*
X1168267Y572667D01*
X1168850Y572833D01*
X1169433Y572667D01*
X1169850Y572333D01*
X1170100Y571833D01*
Y569500D01*
G01X1174700D02*
Y572833D01*
G01Y572250D02*
X1174367Y572583D01*
X1173867Y572750D01*
X1173283Y572833D01*
X1172700Y572667D01*
X1172200Y572333D01*
X1171867Y571833D01*
X1171700Y571167D01*
X1171867Y570500D01*
X1172200Y570000D01*
X1172700Y569667D01*
X1173283Y569500D01*
X1173867Y569583D01*
X1174367Y569833D01*
X1174700Y570167D01*
G01X1177550Y570083D02*
X1177967Y569750D01*
X1178550Y569500D01*
X1179050D01*
X1179550Y569667D01*
X1179883Y569917D01*
X1180050Y570250D01*
X1179967Y570750D01*
X1179633Y571000D01*
X1178133Y571500D01*
X1177800Y572083D01*
X1177967Y572500D01*
X1178300Y572750D01*
X1178800Y572833D01*
X1179300Y572750D01*
X1179800Y572500D01*
G01X1182983Y569500D02*
Y574500D01*
G01X1185650Y572833D02*
X1182983Y570917D01*
G01X1184067Y571667D02*
X1185817Y569500D01*
G01X1194100Y567833D02*
Y572833D01*
G01Y572083D02*
X1194517Y572500D01*
X1194933Y572750D01*
X1195600Y572833D01*
X1196183Y572750D01*
X1196767Y572333D01*
X1197017Y571750D01*
X1197100Y571167D01*
X1197017Y570583D01*
X1196767Y570000D01*
X1196267Y569667D01*
X1195600Y569500D01*
X1195017Y569583D01*
X1194433Y569833D01*
X1194100Y570167D01*
G01X1202700Y569500D02*
Y572833D01*
G01Y572250D02*
X1202367Y572583D01*
X1201867Y572750D01*
X1201283Y572833D01*
X1200700Y572667D01*
X1200200Y572333D01*
X1199867Y571833D01*
X1199700Y571167D01*
X1199867Y570500D01*
X1200200Y570000D01*
X1200700Y569667D01*
X1201283Y569500D01*
X1201867Y569583D01*
X1202367Y569833D01*
X1202700Y570167D01*
G01X1208300Y574500D02*
Y569500D01*
G01Y570250D02*
X1207967Y569833D01*
X1207467Y569583D01*
X1206883Y569500D01*
X1206217Y569667D01*
X1205717Y570083D01*
X1205383Y570583D01*
X1205300Y571167D01*
X1205383Y571750D01*
X1205717Y572250D01*
X1206217Y572667D01*
X1206883Y572833D01*
X1207467Y572750D01*
X1207883Y572583D01*
X1208300Y572250D01*
G01X1217833Y568583D02*
X1218167Y569667D01*
G01X1230700Y569500D02*
Y572833D01*
G01Y572250D02*
X1230367Y572583D01*
X1229867Y572750D01*
X1229283Y572833D01*
X1228700Y572667D01*
X1228200Y572333D01*
X1227867Y571833D01*
X1227700Y571167D01*
X1227867Y570500D01*
X1228200Y570000D01*
X1228700Y569667D01*
X1229283Y569500D01*
X1229867Y569583D01*
X1230367Y569833D01*
X1230700Y570167D01*
G01X1233383Y569500D02*
Y572833D01*
G01Y572000D02*
X1233717Y572417D01*
X1234217Y572750D01*
X1234883Y572833D01*
X1235467Y572750D01*
X1235967Y572417D01*
X1236217Y571833D01*
Y569500D01*
G01X1238983D02*
Y572833D01*
G01Y572000D02*
X1239317Y572417D01*
X1239817Y572750D01*
X1240483Y572833D01*
X1241067Y572750D01*
X1241567Y572417D01*
X1241817Y571833D01*
Y569500D01*
G01X1244583Y572833D02*
Y570500D01*
X1244917Y569917D01*
X1245417Y569583D01*
X1246000Y569500D01*
X1246583Y569583D01*
X1247083Y569917D01*
X1247417Y570500D01*
G01Y569500D02*
Y572833D01*
G01X1253100Y569500D02*
Y572833D01*
G01Y572250D02*
X1252767Y572583D01*
X1252267Y572750D01*
X1251683Y572833D01*
X1251100Y572667D01*
X1250600Y572333D01*
X1250267Y571833D01*
X1250100Y571167D01*
X1250267Y570500D01*
X1250600Y570000D01*
X1251100Y569667D01*
X1251683Y569500D01*
X1252267Y569583D01*
X1252767Y569833D01*
X1253100Y570167D01*
G01X1257200Y569500D02*
Y574500D01*
G01X1267233Y569500D02*
Y572833D01*
G01Y572167D02*
X1267650Y572500D01*
X1268067Y572750D01*
X1268650Y572833D01*
X1269067Y572750D01*
X1269567Y572500D01*
G01X1274000Y572833D02*
Y569500D01*
G01Y574167D02*
X1273833Y574250D01*
Y574417D01*
X1274000Y574500D01*
X1274167Y574417D01*
Y574250D01*
X1274000Y574167D01*
G01X1278183Y569500D02*
Y572833D01*
G01Y572000D02*
X1278517Y572417D01*
X1279017Y572750D01*
X1279683Y572833D01*
X1280267Y572750D01*
X1280767Y572417D01*
X1281017Y571833D01*
Y569500D01*
G01X1284033Y568250D02*
X1284617Y567917D01*
X1285283Y567833D01*
X1285867Y567917D01*
X1286367Y568333D01*
X1286700Y568917D01*
Y572833D01*
G01Y572167D02*
X1286367Y572500D01*
X1285867Y572750D01*
X1285283Y572833D01*
X1284617Y572667D01*
X1284200Y572333D01*
X1283867Y571750D01*
X1283700Y571167D01*
X1283783Y570667D01*
X1284117Y570083D01*
X1284617Y569667D01*
X1285283Y569500D01*
X1285783Y569583D01*
X1286367Y569917D01*
X1286700Y570250D01*
G01X1294983Y569500D02*
Y572833D01*
G01Y572000D02*
X1295317Y572417D01*
X1295817Y572750D01*
X1296483Y572833D01*
X1297067Y572750D01*
X1297567Y572417D01*
X1297817Y571833D01*
Y569500D01*
G01X1300750Y571750D02*
X1303417D01*
X1303167Y572333D01*
X1302750Y572667D01*
X1302167Y572833D01*
X1301583Y572750D01*
X1301083Y572500D01*
X1300750Y571917D01*
X1300583Y571417D01*
Y570917D01*
X1300750Y570417D01*
X1301167Y569917D01*
X1301667Y569583D01*
X1302250Y569500D01*
X1302833Y569667D01*
X1303417Y570167D01*
G01X1306350Y571750D02*
X1309017D01*
X1308767Y572333D01*
X1308350Y572667D01*
X1307767Y572833D01*
X1307183Y572750D01*
X1306683Y572500D01*
X1306350Y571917D01*
X1306183Y571417D01*
Y570917D01*
X1306350Y570417D01*
X1306767Y569917D01*
X1307267Y569583D01*
X1307850Y569500D01*
X1308433Y569667D01*
X1309017Y570167D01*
G01X1314700Y574500D02*
Y569500D01*
G01Y570250D02*
X1314367Y569833D01*
X1313867Y569583D01*
X1313283Y569500D01*
X1312617Y569667D01*
X1312117Y570083D01*
X1311783Y570583D01*
X1311700Y571167D01*
X1311783Y571750D01*
X1312117Y572250D01*
X1312617Y572667D01*
X1313283Y572833D01*
X1313867Y572750D01*
X1314283Y572583D01*
X1314700Y572250D01*
G01X1038500Y510500D02*
Y513833D01*
G01Y513250D02*
X1038167Y513583D01*
X1037667Y513750D01*
X1037083Y513833D01*
X1036500Y513667D01*
X1036000Y513333D01*
X1035667Y512833D01*
X1035500Y512167D01*
X1035667Y511500D01*
X1036000Y511000D01*
X1036500Y510667D01*
X1037083Y510500D01*
X1037667Y510583D01*
X1038167Y510833D01*
X1038500Y511167D01*
G01X1042600Y510333D02*
X1042433Y510417D01*
Y510583D01*
X1042600Y510667D01*
X1042767Y510583D01*
Y510417D01*
X1042600Y510333D01*
G01X1048867Y513167D02*
X1049200Y513417D01*
X1049450Y513833D01*
X1049617Y514417D01*
X1049450Y514917D01*
X1049117Y515250D01*
X1048533Y515500D01*
X1046283D01*
Y510500D01*
X1049033D01*
X1049617Y510833D01*
X1049950Y511333D01*
X1050117Y511917D01*
X1049950Y512500D01*
X1049450Y513000D01*
X1048867Y513167D01*
X1046283D01*
G01X1053800Y510500D02*
X1053300Y510583D01*
X1052800Y510917D01*
X1052467Y511500D01*
X1052300Y512167D01*
X1052467Y512833D01*
X1052800Y513417D01*
X1053300Y513750D01*
X1053800Y513833D01*
X1054300Y513750D01*
X1054800Y513417D01*
X1055133Y512833D01*
X1055217Y512167D01*
X1055133Y511500D01*
X1054800Y510917D01*
X1054300Y510583D01*
X1053800Y510500D01*
G01X1060900D02*
Y513833D01*
G01Y513250D02*
X1060567Y513583D01*
X1060067Y513750D01*
X1059483Y513833D01*
X1058900Y513667D01*
X1058400Y513333D01*
X1058067Y512833D01*
X1057900Y512167D01*
X1058067Y511500D01*
X1058400Y511000D01*
X1058900Y510667D01*
X1059483Y510500D01*
X1060067Y510583D01*
X1060567Y510833D01*
X1060900Y511167D01*
G01X1063833Y510500D02*
Y513833D01*
G01Y513167D02*
X1064250Y513500D01*
X1064667Y513750D01*
X1065250Y513833D01*
X1065667Y513750D01*
X1066167Y513500D01*
G01X1072100Y515500D02*
Y510500D01*
G01Y511250D02*
X1071767Y510833D01*
X1071267Y510583D01*
X1070683Y510500D01*
X1070017Y510667D01*
X1069517Y511083D01*
X1069183Y511583D01*
X1069100Y512167D01*
X1069183Y512750D01*
X1069517Y513250D01*
X1070017Y513667D01*
X1070683Y513833D01*
X1071267Y513750D01*
X1071683Y513583D01*
X1072100Y513250D01*
G01X1081800Y515500D02*
Y510500D01*
G01X1080633Y513833D02*
X1082967D01*
G01X1085983Y510500D02*
Y515500D01*
G01Y513083D02*
X1086400Y513500D01*
X1086817Y513750D01*
X1087483Y513833D01*
X1087983Y513750D01*
X1088567Y513417D01*
X1088817Y512917D01*
Y510500D01*
G01X1093000Y513833D02*
Y510500D01*
G01Y515167D02*
X1092833Y515250D01*
Y515417D01*
X1093000Y515500D01*
X1093167Y515417D01*
Y515250D01*
X1093000Y515167D01*
G01X1099933Y513417D02*
X1099350Y513750D01*
X1098850Y513833D01*
X1098183Y513667D01*
X1097683Y513333D01*
X1097350Y512750D01*
X1097267Y512167D01*
X1097350Y511583D01*
X1097683Y511083D01*
X1098183Y510667D01*
X1098850Y510500D01*
X1099433Y510667D01*
X1099933Y511000D01*
G01X1102783Y510500D02*
Y515500D01*
G01X1105450Y513833D02*
X1102783Y511917D01*
G01X1103867Y512667D02*
X1105617Y510500D01*
G01X1108383D02*
Y513833D01*
G01Y513000D02*
X1108717Y513417D01*
X1109217Y513750D01*
X1109883Y513833D01*
X1110467Y513750D01*
X1110967Y513417D01*
X1111217Y512833D01*
Y510500D01*
G01X1114150Y512750D02*
X1116817D01*
X1116567Y513333D01*
X1116150Y513667D01*
X1115567Y513833D01*
X1114983Y513750D01*
X1114483Y513500D01*
X1114150Y512917D01*
X1113983Y512417D01*
Y511917D01*
X1114150Y511417D01*
X1114567Y510917D01*
X1115067Y510583D01*
X1115650Y510500D01*
X1116233Y510667D01*
X1116817Y511167D01*
G01X1119750Y511083D02*
X1120167Y510750D01*
X1120750Y510500D01*
X1121250D01*
X1121750Y510667D01*
X1122083Y510917D01*
X1122250Y511250D01*
X1122167Y511750D01*
X1121833Y512000D01*
X1120333Y512500D01*
X1120000Y513083D01*
X1120167Y513500D01*
X1120500Y513750D01*
X1121000Y513833D01*
X1121500Y513750D01*
X1122000Y513500D01*
G01X1125350Y511083D02*
X1125767Y510750D01*
X1126350Y510500D01*
X1126850D01*
X1127350Y510667D01*
X1127683Y510917D01*
X1127850Y511250D01*
X1127767Y511750D01*
X1127433Y512000D01*
X1125933Y512500D01*
X1125600Y513083D01*
X1125767Y513500D01*
X1126100Y513750D01*
X1126600Y513833D01*
X1127100Y513750D01*
X1127600Y513500D01*
G01X1130533Y510500D02*
X1133867Y512167D01*
X1130533Y513833D01*
G01X1136717Y511417D02*
X1138883D01*
G01Y512917D02*
X1136717D01*
G01X1149000Y515500D02*
X1148333Y515333D01*
X1147833Y514917D01*
X1147500Y514417D01*
X1147250Y513750D01*
X1147167Y513000D01*
X1147250Y512250D01*
X1147500Y511583D01*
X1147833Y511083D01*
X1148333Y510667D01*
X1149000Y510500D01*
X1149667Y510667D01*
X1150167Y511083D01*
X1150500Y511583D01*
X1150750Y512250D01*
X1150833Y513000D01*
X1150750Y513750D01*
X1150500Y514417D01*
X1150167Y514917D01*
X1149667Y515333D01*
X1149000Y515500D01*
G01X1154600Y510333D02*
X1154433Y510417D01*
Y510583D01*
X1154600Y510667D01*
X1154767Y510583D01*
Y510417D01*
X1154600Y510333D01*
G01X1158783Y511083D02*
X1159367Y510667D01*
X1160033Y510500D01*
X1160700Y510667D01*
X1161283Y511167D01*
X1161700Y511917D01*
X1161867Y512667D01*
Y513583D01*
X1161700Y514333D01*
X1161283Y515000D01*
X1160783Y515333D01*
X1160200Y515500D01*
X1159533Y515333D01*
X1159033Y515000D01*
X1158700Y514500D01*
X1158533Y513833D01*
X1158700Y513250D01*
X1159117Y512667D01*
X1159617Y512333D01*
X1160200Y512250D01*
X1160867Y512417D01*
X1161367Y512833D01*
X1161867Y513583D01*
G01X1163300Y510500D02*
Y513833D01*
G01Y512917D02*
X1163550Y513333D01*
X1163967Y513667D01*
X1164550Y513833D01*
X1165133Y513667D01*
X1165550Y513333D01*
X1165800Y512917D01*
Y510500D01*
G01Y512917D02*
X1166050Y513333D01*
X1166467Y513667D01*
X1167050Y513833D01*
X1167633Y513667D01*
X1168050Y513333D01*
X1168300Y512833D01*
Y510500D01*
G01X1171400Y510333D02*
X1171233Y510417D01*
Y510583D01*
X1171400Y510667D01*
X1171567Y510583D01*
Y510417D01*
X1171400Y510333D01*
G01Y512583D02*
X1171233Y512667D01*
Y512833D01*
X1171400Y512917D01*
X1171567Y512833D01*
Y512667D01*
X1171400Y512583D01*
G01X1034250Y520500D02*
Y525500D01*
G01X1037750D02*
Y520500D01*
G01Y523000D02*
X1034250D01*
G01X1043100Y520500D02*
Y523833D01*
G01Y523250D02*
X1042767Y523583D01*
X1042267Y523750D01*
X1041683Y523833D01*
X1041100Y523667D01*
X1040600Y523333D01*
X1040267Y522833D01*
X1040100Y522167D01*
X1040267Y521500D01*
X1040600Y521000D01*
X1041100Y520667D01*
X1041683Y520500D01*
X1042267Y520583D01*
X1042767Y520833D01*
X1043100Y521167D01*
G01X1047200Y520500D02*
Y525500D01*
G01X1052300Y520500D02*
Y524750D01*
X1052467Y525167D01*
X1052800Y525417D01*
X1053300Y525500D01*
X1053800Y525333D01*
X1054050Y524917D01*
G01X1053050Y523500D02*
X1051383D01*
G01X1057317Y522167D02*
X1059483D01*
G01X1062500Y518833D02*
Y523833D01*
G01Y523083D02*
X1062917Y523500D01*
X1063333Y523750D01*
X1064000Y523833D01*
X1064583Y523750D01*
X1065167Y523333D01*
X1065417Y522750D01*
X1065500Y522167D01*
X1065417Y521583D01*
X1065167Y521000D01*
X1064667Y520667D01*
X1064000Y520500D01*
X1063417Y520583D01*
X1062833Y520833D01*
X1062500Y521167D01*
G01X1069600Y520500D02*
Y525500D01*
G01X1073783Y523833D02*
Y521500D01*
X1074117Y520917D01*
X1074617Y520583D01*
X1075200Y520500D01*
X1075783Y520583D01*
X1076283Y520917D01*
X1076617Y521500D01*
G01Y520500D02*
Y523833D01*
G01X1079633Y519250D02*
X1080217Y518917D01*
X1080883Y518833D01*
X1081467Y518917D01*
X1081967Y519333D01*
X1082300Y519917D01*
Y523833D01*
G01Y523167D02*
X1081967Y523500D01*
X1081467Y523750D01*
X1080883Y523833D01*
X1080217Y523667D01*
X1079800Y523333D01*
X1079467Y522750D01*
X1079300Y522167D01*
X1079383Y521667D01*
X1079717Y521083D01*
X1080217Y520667D01*
X1080883Y520500D01*
X1081383Y520583D01*
X1081967Y520917D01*
X1082300Y521250D01*
G01X1085233Y519250D02*
X1085817Y518917D01*
X1086483Y518833D01*
X1087067Y518917D01*
X1087567Y519333D01*
X1087900Y519917D01*
Y523833D01*
G01Y523167D02*
X1087567Y523500D01*
X1087067Y523750D01*
X1086483Y523833D01*
X1085817Y523667D01*
X1085400Y523333D01*
X1085067Y522750D01*
X1084900Y522167D01*
X1084983Y521667D01*
X1085317Y521083D01*
X1085817Y520667D01*
X1086483Y520500D01*
X1086983Y520583D01*
X1087567Y520917D01*
X1087900Y521250D01*
G01X1092000Y523833D02*
Y520500D01*
G01Y525167D02*
X1091833Y525250D01*
Y525417D01*
X1092000Y525500D01*
X1092167Y525417D01*
Y525250D01*
X1092000Y525167D01*
G01X1096183Y520500D02*
Y523833D01*
G01Y523000D02*
X1096517Y523417D01*
X1097017Y523750D01*
X1097683Y523833D01*
X1098267Y523750D01*
X1098767Y523417D01*
X1099017Y522833D01*
Y520500D01*
G01X1102033Y519250D02*
X1102617Y518917D01*
X1103283Y518833D01*
X1103867Y518917D01*
X1104367Y519333D01*
X1104700Y519917D01*
Y523833D01*
G01Y523167D02*
X1104367Y523500D01*
X1103867Y523750D01*
X1103283Y523833D01*
X1102617Y523667D01*
X1102200Y523333D01*
X1101867Y522750D01*
X1101700Y522167D01*
X1101783Y521667D01*
X1102117Y521083D01*
X1102617Y520667D01*
X1103283Y520500D01*
X1103783Y520583D01*
X1104367Y520917D01*
X1104700Y521250D01*
G01X1114400Y520333D02*
X1114233Y520417D01*
Y520583D01*
X1114400Y520667D01*
X1114567Y520583D01*
Y520417D01*
X1114400Y520333D01*
G01Y522583D02*
X1114233Y522667D01*
Y522833D01*
X1114400Y522917D01*
X1114567Y522833D01*
Y522667D01*
X1114400Y522583D01*
G01X1125600Y525500D02*
Y520500D01*
G01X1124433Y523833D02*
X1126767D01*
G01X1129783Y520500D02*
Y525500D01*
G01Y523083D02*
X1130200Y523500D01*
X1130617Y523750D01*
X1131283Y523833D01*
X1131783Y523750D01*
X1132367Y523417D01*
X1132617Y522917D01*
Y520500D01*
G01X1135550Y522750D02*
X1138217D01*
X1137967Y523333D01*
X1137550Y523667D01*
X1136967Y523833D01*
X1136383Y523750D01*
X1135883Y523500D01*
X1135550Y522917D01*
X1135383Y522417D01*
Y521917D01*
X1135550Y521417D01*
X1135967Y520917D01*
X1136467Y520583D01*
X1137050Y520500D01*
X1137633Y520667D01*
X1138217Y521167D01*
G01X1146500Y518833D02*
Y523833D01*
G01Y523083D02*
X1146917Y523500D01*
X1147333Y523750D01*
X1148000Y523833D01*
X1148583Y523750D01*
X1149167Y523333D01*
X1149417Y522750D01*
X1149500Y522167D01*
X1149417Y521583D01*
X1149167Y521000D01*
X1148667Y520667D01*
X1148000Y520500D01*
X1147417Y520583D01*
X1146833Y520833D01*
X1146500Y521167D01*
G01X1153600Y520500D02*
Y525500D01*
G01X1157783Y523833D02*
Y521500D01*
X1158117Y520917D01*
X1158617Y520583D01*
X1159200Y520500D01*
X1159783Y520583D01*
X1160283Y520917D01*
X1160617Y521500D01*
G01Y520500D02*
Y523833D01*
G01X1163633Y519250D02*
X1164217Y518917D01*
X1164883Y518833D01*
X1165467Y518917D01*
X1165967Y519333D01*
X1166300Y519917D01*
Y523833D01*
G01Y523167D02*
X1165967Y523500D01*
X1165467Y523750D01*
X1164883Y523833D01*
X1164217Y523667D01*
X1163800Y523333D01*
X1163467Y522750D01*
X1163300Y522167D01*
X1163383Y521667D01*
X1163717Y521083D01*
X1164217Y520667D01*
X1164883Y520500D01*
X1165383Y520583D01*
X1165967Y520917D01*
X1166300Y521250D01*
G01X1169233Y519250D02*
X1169817Y518917D01*
X1170483Y518833D01*
X1171067Y518917D01*
X1171567Y519333D01*
X1171900Y519917D01*
Y523833D01*
G01Y523167D02*
X1171567Y523500D01*
X1171067Y523750D01*
X1170483Y523833D01*
X1169817Y523667D01*
X1169400Y523333D01*
X1169067Y522750D01*
X1168900Y522167D01*
X1168983Y521667D01*
X1169317Y521083D01*
X1169817Y520667D01*
X1170483Y520500D01*
X1170983Y520583D01*
X1171567Y520917D01*
X1171900Y521250D01*
G01X1176000Y523833D02*
Y520500D01*
G01Y525167D02*
X1175833Y525250D01*
Y525417D01*
X1176000Y525500D01*
X1176167Y525417D01*
Y525250D01*
X1176000Y525167D01*
G01X1180183Y520500D02*
Y523833D01*
G01Y523000D02*
X1180517Y523417D01*
X1181017Y523750D01*
X1181683Y523833D01*
X1182267Y523750D01*
X1182767Y523417D01*
X1183017Y522833D01*
Y520500D01*
G01X1186033Y519250D02*
X1186617Y518917D01*
X1187283Y518833D01*
X1187867Y518917D01*
X1188367Y519333D01*
X1188700Y519917D01*
Y523833D01*
G01Y523167D02*
X1188367Y523500D01*
X1187867Y523750D01*
X1187283Y523833D01*
X1186617Y523667D01*
X1186200Y523333D01*
X1185867Y522750D01*
X1185700Y522167D01*
X1185783Y521667D01*
X1186117Y521083D01*
X1186617Y520667D01*
X1187283Y520500D01*
X1187783Y520583D01*
X1188367Y520917D01*
X1188700Y521250D01*
G01X1197233Y520500D02*
Y523833D01*
G01Y523167D02*
X1197650Y523500D01*
X1198067Y523750D01*
X1198650Y523833D01*
X1199067Y523750D01*
X1199567Y523500D01*
G01X1205500Y520500D02*
Y523833D01*
G01Y523250D02*
X1205167Y523583D01*
X1204667Y523750D01*
X1204083Y523833D01*
X1203500Y523667D01*
X1203000Y523333D01*
X1202667Y522833D01*
X1202500Y522167D01*
X1202667Y521500D01*
X1203000Y521000D01*
X1203500Y520667D01*
X1204083Y520500D01*
X1204667Y520583D01*
X1205167Y520833D01*
X1205500Y521167D01*
G01X1209600Y525500D02*
Y520500D01*
G01X1208433Y523833D02*
X1210767D01*
G01X1215200D02*
Y520500D01*
G01Y525167D02*
X1215033Y525250D01*
Y525417D01*
X1215200Y525500D01*
X1215367Y525417D01*
Y525250D01*
X1215200Y525167D01*
G01X1220800Y520500D02*
X1220300Y520583D01*
X1219800Y520917D01*
X1219467Y521500D01*
X1219300Y522167D01*
X1219467Y522833D01*
X1219800Y523417D01*
X1220300Y523750D01*
X1220800Y523833D01*
X1221300Y523750D01*
X1221800Y523417D01*
X1222133Y522833D01*
X1222217Y522167D01*
X1222133Y521500D01*
X1221800Y520917D01*
X1221300Y520583D01*
X1220800Y520500D01*
G01X1230500Y518833D02*
Y523833D01*
G01Y523083D02*
X1230917Y523500D01*
X1231333Y523750D01*
X1232000Y523833D01*
X1232583Y523750D01*
X1233167Y523333D01*
X1233417Y522750D01*
X1233500Y522167D01*
X1233417Y521583D01*
X1233167Y521000D01*
X1232667Y520667D01*
X1232000Y520500D01*
X1231417Y520583D01*
X1230833Y520833D01*
X1230500Y521167D01*
G01X1236350Y522750D02*
X1239017D01*
X1238767Y523333D01*
X1238350Y523667D01*
X1237767Y523833D01*
X1237183Y523750D01*
X1236683Y523500D01*
X1236350Y522917D01*
X1236183Y522417D01*
Y521917D01*
X1236350Y521417D01*
X1236767Y520917D01*
X1237267Y520583D01*
X1237850Y520500D01*
X1238433Y520667D01*
X1239017Y521167D01*
G01X1242033Y520500D02*
Y523833D01*
G01Y523167D02*
X1242450Y523500D01*
X1242867Y523750D01*
X1243450Y523833D01*
X1243867Y523750D01*
X1244367Y523500D01*
G01X1253900Y520500D02*
Y524750D01*
X1254067Y525167D01*
X1254400Y525417D01*
X1254900Y525500D01*
X1255400Y525333D01*
X1255650Y524917D01*
G01X1254650Y523500D02*
X1252983D01*
G01X1260000Y520500D02*
X1259500Y520583D01*
X1259000Y520917D01*
X1258667Y521500D01*
X1258500Y522167D01*
X1258667Y522833D01*
X1259000Y523417D01*
X1259500Y523750D01*
X1260000Y523833D01*
X1260500Y523750D01*
X1261000Y523417D01*
X1261333Y522833D01*
X1261417Y522167D01*
X1261333Y521500D01*
X1261000Y520917D01*
X1260500Y520583D01*
X1260000Y520500D01*
G01X1265600D02*
Y525500D01*
G01X1271200Y520500D02*
Y525500D01*
G01X1276800Y520500D02*
X1276300Y520583D01*
X1275800Y520917D01*
X1275467Y521500D01*
X1275300Y522167D01*
X1275467Y522833D01*
X1275800Y523417D01*
X1276300Y523750D01*
X1276800Y523833D01*
X1277300Y523750D01*
X1277800Y523417D01*
X1278133Y522833D01*
X1278217Y522167D01*
X1278133Y521500D01*
X1277800Y520917D01*
X1277300Y520583D01*
X1276800Y520500D01*
G01X1280317Y523833D02*
X1281317Y520500D01*
X1282400Y523833D01*
X1283483Y520500D01*
X1284483Y523833D01*
G01X1288000D02*
Y520500D01*
G01Y525167D02*
X1287833Y525250D01*
Y525417D01*
X1288000Y525500D01*
X1288167Y525417D01*
Y525250D01*
X1288000Y525167D01*
G01X1292183Y520500D02*
Y523833D01*
G01Y523000D02*
X1292517Y523417D01*
X1293017Y523750D01*
X1293683Y523833D01*
X1294267Y523750D01*
X1294767Y523417D01*
X1295017Y522833D01*
Y520500D01*
G01X1298033Y519250D02*
X1298617Y518917D01*
X1299283Y518833D01*
X1299867Y518917D01*
X1300367Y519333D01*
X1300700Y519917D01*
Y523833D01*
G01Y523167D02*
X1300367Y523500D01*
X1299867Y523750D01*
X1299283Y523833D01*
X1298617Y523667D01*
X1298200Y523333D01*
X1297867Y522750D01*
X1297700Y522167D01*
X1297783Y521667D01*
X1298117Y521083D01*
X1298617Y520667D01*
X1299283Y520500D01*
X1299783Y520583D01*
X1300367Y520917D01*
X1300700Y521250D01*
G01X1304800Y520333D02*
X1304633Y520417D01*
Y520583D01*
X1304800Y520667D01*
X1304967Y520583D01*
Y520417D01*
X1304800Y520333D01*
G01Y522583D02*
X1304633Y522667D01*
Y522833D01*
X1304800Y522917D01*
X1304967Y522833D01*
Y522667D01*
X1304800Y522583D01*
G01X1033500Y529500D02*
Y534500D01*
G01Y532000D02*
X1033917Y532500D01*
X1034417Y532750D01*
X1034917Y532833D01*
X1035667Y532667D01*
X1036167Y532333D01*
X1036500Y531750D01*
Y531083D01*
X1036333Y530417D01*
X1036000Y529917D01*
X1035417Y529583D01*
X1034917Y529500D01*
X1034417Y529583D01*
X1033917Y529833D01*
X1033500Y530250D01*
G01X1039350Y531750D02*
X1042017D01*
X1041767Y532333D01*
X1041350Y532667D01*
X1040767Y532833D01*
X1040183Y532750D01*
X1039683Y532500D01*
X1039350Y531917D01*
X1039183Y531417D01*
Y530917D01*
X1039350Y530417D01*
X1039767Y529917D01*
X1040267Y529583D01*
X1040850Y529500D01*
X1041433Y529667D01*
X1042017Y530167D01*
G01X1051300Y529500D02*
Y533750D01*
X1051467Y534167D01*
X1051800Y534417D01*
X1052300Y534500D01*
X1052800Y534333D01*
X1053050Y533917D01*
G01X1052050Y532500D02*
X1050383D01*
G01X1056233Y529500D02*
Y532833D01*
G01Y532167D02*
X1056650Y532500D01*
X1057067Y532750D01*
X1057650Y532833D01*
X1058067Y532750D01*
X1058567Y532500D01*
G01X1061750Y531750D02*
X1064417D01*
X1064167Y532333D01*
X1063750Y532667D01*
X1063167Y532833D01*
X1062583Y532750D01*
X1062083Y532500D01*
X1061750Y531917D01*
X1061583Y531417D01*
Y530917D01*
X1061750Y530417D01*
X1062167Y529917D01*
X1062667Y529583D01*
X1063250Y529500D01*
X1063833Y529667D01*
X1064417Y530167D01*
G01X1067350Y531750D02*
X1070017D01*
X1069767Y532333D01*
X1069350Y532667D01*
X1068767Y532833D01*
X1068183Y532750D01*
X1067683Y532500D01*
X1067350Y531917D01*
X1067183Y531417D01*
Y530917D01*
X1067350Y530417D01*
X1067767Y529917D01*
X1068267Y529583D01*
X1068850Y529500D01*
X1069433Y529667D01*
X1070017Y530167D01*
G01X1079300Y529500D02*
Y533750D01*
X1079467Y534167D01*
X1079800Y534417D01*
X1080300Y534500D01*
X1080800Y534333D01*
X1081050Y533917D01*
G01X1080050Y532500D02*
X1078383D01*
G01X1084233Y529500D02*
Y532833D01*
G01Y532167D02*
X1084650Y532500D01*
X1085067Y532750D01*
X1085650Y532833D01*
X1086067Y532750D01*
X1086567Y532500D01*
G01X1091000Y529500D02*
X1090500Y529583D01*
X1090000Y529917D01*
X1089667Y530500D01*
X1089500Y531167D01*
X1089667Y531833D01*
X1090000Y532417D01*
X1090500Y532750D01*
X1091000Y532833D01*
X1091500Y532750D01*
X1092000Y532417D01*
X1092333Y531833D01*
X1092417Y531167D01*
X1092333Y530500D01*
X1092000Y529917D01*
X1091500Y529583D01*
X1091000Y529500D01*
G01X1094100D02*
Y532833D01*
G01Y531917D02*
X1094350Y532333D01*
X1094767Y532667D01*
X1095350Y532833D01*
X1095933Y532667D01*
X1096350Y532333D01*
X1096600Y531917D01*
Y529500D01*
G01Y531917D02*
X1096850Y532333D01*
X1097267Y532667D01*
X1097850Y532833D01*
X1098433Y532667D01*
X1098850Y532333D01*
X1099100Y531833D01*
Y529500D01*
G01X1106550Y530083D02*
X1106967Y529750D01*
X1107550Y529500D01*
X1108050D01*
X1108550Y529667D01*
X1108883Y529917D01*
X1109050Y530250D01*
X1108967Y530750D01*
X1108633Y531000D01*
X1107133Y531500D01*
X1106800Y532083D01*
X1106967Y532500D01*
X1107300Y532750D01*
X1107800Y532833D01*
X1108300Y532750D01*
X1108800Y532500D01*
G01X1113400Y529500D02*
X1112900Y529583D01*
X1112400Y529917D01*
X1112067Y530500D01*
X1111900Y531167D01*
X1112067Y531833D01*
X1112400Y532417D01*
X1112900Y532750D01*
X1113400Y532833D01*
X1113900Y532750D01*
X1114400Y532417D01*
X1114733Y531833D01*
X1114817Y531167D01*
X1114733Y530500D01*
X1114400Y529917D01*
X1113900Y529583D01*
X1113400Y529500D01*
G01X1119000D02*
Y534500D01*
G01X1126100D02*
Y529500D01*
G01Y530250D02*
X1125767Y529833D01*
X1125267Y529583D01*
X1124683Y529500D01*
X1124017Y529667D01*
X1123517Y530083D01*
X1123183Y530583D01*
X1123100Y531167D01*
X1123183Y531750D01*
X1123517Y532250D01*
X1124017Y532667D01*
X1124683Y532833D01*
X1125267Y532750D01*
X1125683Y532583D01*
X1126100Y532250D01*
G01X1128950Y531750D02*
X1131617D01*
X1131367Y532333D01*
X1130950Y532667D01*
X1130367Y532833D01*
X1129783Y532750D01*
X1129283Y532500D01*
X1128950Y531917D01*
X1128783Y531417D01*
Y530917D01*
X1128950Y530417D01*
X1129367Y529917D01*
X1129867Y529583D01*
X1130450Y529500D01*
X1131033Y529667D01*
X1131617Y530167D01*
G01X1134633Y529500D02*
Y532833D01*
G01Y532167D02*
X1135050Y532500D01*
X1135467Y532750D01*
X1136050Y532833D01*
X1136467Y532750D01*
X1136967Y532500D01*
G01X1144500Y529500D02*
Y532833D01*
G01Y531917D02*
X1144750Y532333D01*
X1145167Y532667D01*
X1145750Y532833D01*
X1146333Y532667D01*
X1146750Y532333D01*
X1147000Y531917D01*
Y529500D01*
G01Y531917D02*
X1147250Y532333D01*
X1147667Y532667D01*
X1148250Y532833D01*
X1148833Y532667D01*
X1149250Y532333D01*
X1149500Y531833D01*
Y529500D01*
G01X1154100D02*
Y532833D01*
G01Y532250D02*
X1153767Y532583D01*
X1153267Y532750D01*
X1152683Y532833D01*
X1152100Y532667D01*
X1151600Y532333D01*
X1151267Y531833D01*
X1151100Y531167D01*
X1151267Y530500D01*
X1151600Y530000D01*
X1152100Y529667D01*
X1152683Y529500D01*
X1153267Y529583D01*
X1153767Y529833D01*
X1154100Y530167D01*
G01X1156950Y530083D02*
X1157367Y529750D01*
X1157950Y529500D01*
X1158450D01*
X1158950Y529667D01*
X1159283Y529917D01*
X1159450Y530250D01*
X1159367Y530750D01*
X1159033Y531000D01*
X1157533Y531500D01*
X1157200Y532083D01*
X1157367Y532500D01*
X1157700Y532750D01*
X1158200Y532833D01*
X1158700Y532750D01*
X1159200Y532500D01*
G01X1162383Y529500D02*
Y534500D01*
G01X1165050Y532833D02*
X1162383Y530917D01*
G01X1163467Y531667D02*
X1165217Y529500D01*
G01X1169400Y529333D02*
X1169233Y529417D01*
Y529583D01*
X1169400Y529667D01*
X1169567Y529583D01*
Y529417D01*
X1169400Y529333D01*
G01X1020417Y542667D02*
X1020917Y543167D01*
X1021500Y543417D01*
X1022167Y543500D01*
X1023000Y543333D01*
X1023583Y542917D01*
X1023750Y542417D01*
X1023667Y541917D01*
X1023333Y541500D01*
X1021667Y540667D01*
X1020917Y540083D01*
X1020417Y539250D01*
X1020250Y538500D01*
X1023750D01*
G01X1027600Y538333D02*
X1027433Y538417D01*
Y538583D01*
X1027600Y538667D01*
X1027767Y538583D01*
Y538417D01*
X1027600Y538333D01*
G01X1033200Y543500D02*
Y538500D01*
G01X1031283Y543500D02*
X1035117D01*
G01X1037383Y538500D02*
Y543500D01*
G01Y541083D02*
X1037800Y541500D01*
X1038217Y541750D01*
X1038883Y541833D01*
X1039383Y541750D01*
X1039967Y541417D01*
X1040217Y540917D01*
Y538500D01*
G01X1043150Y540750D02*
X1045817D01*
X1045567Y541333D01*
X1045150Y541667D01*
X1044567Y541833D01*
X1043983Y541750D01*
X1043483Y541500D01*
X1043150Y540917D01*
X1042983Y540417D01*
Y539917D01*
X1043150Y539417D01*
X1043567Y538917D01*
X1044067Y538583D01*
X1044650Y538500D01*
X1045233Y538667D01*
X1045817Y539167D01*
G01X1054350Y539083D02*
X1054767Y538750D01*
X1055350Y538500D01*
X1055850D01*
X1056350Y538667D01*
X1056683Y538917D01*
X1056850Y539250D01*
X1056767Y539750D01*
X1056433Y540000D01*
X1054933Y540500D01*
X1054600Y541083D01*
X1054767Y541500D01*
X1055100Y541750D01*
X1055600Y541833D01*
X1056100Y541750D01*
X1056600Y541500D01*
G01X1061200Y541833D02*
Y538500D01*
G01Y543167D02*
X1061033Y543250D01*
Y543417D01*
X1061200Y543500D01*
X1061367Y543417D01*
Y543250D01*
X1061200Y543167D01*
G01X1068300Y543500D02*
Y538500D01*
G01Y539250D02*
X1067967Y538833D01*
X1067467Y538583D01*
X1066883Y538500D01*
X1066217Y538667D01*
X1065717Y539083D01*
X1065383Y539583D01*
X1065300Y540167D01*
X1065383Y540750D01*
X1065717Y541250D01*
X1066217Y541667D01*
X1066883Y541833D01*
X1067467Y541750D01*
X1067883Y541583D01*
X1068300Y541250D01*
G01X1071150Y540750D02*
X1073817D01*
X1073567Y541333D01*
X1073150Y541667D01*
X1072567Y541833D01*
X1071983Y541750D01*
X1071483Y541500D01*
X1071150Y540917D01*
X1070983Y540417D01*
Y539917D01*
X1071150Y539417D01*
X1071567Y538917D01*
X1072067Y538583D01*
X1072650Y538500D01*
X1073233Y538667D01*
X1073817Y539167D01*
G01X1081517Y541833D02*
X1082517Y538500D01*
X1083600Y541833D01*
X1084683Y538500D01*
X1085683Y541833D01*
G01X1089200D02*
Y538500D01*
G01Y543167D02*
X1089033Y543250D01*
Y543417D01*
X1089200Y543500D01*
X1089367Y543417D01*
Y543250D01*
X1089200Y543167D01*
G01X1094800Y543500D02*
Y538500D01*
G01X1093633Y541833D02*
X1095967D01*
G01X1098983Y538500D02*
Y543500D01*
G01Y541083D02*
X1099400Y541500D01*
X1099817Y541750D01*
X1100483Y541833D01*
X1100983Y541750D01*
X1101567Y541417D01*
X1101817Y540917D01*
Y538500D01*
G01X1110350Y539083D02*
X1110767Y538750D01*
X1111350Y538500D01*
X1111850D01*
X1112350Y538667D01*
X1112683Y538917D01*
X1112850Y539250D01*
X1112767Y539750D01*
X1112433Y540000D01*
X1110933Y540500D01*
X1110600Y541083D01*
X1110767Y541500D01*
X1111100Y541750D01*
X1111600Y541833D01*
X1112100Y541750D01*
X1112600Y541500D01*
G01X1117200Y538500D02*
X1116700Y538583D01*
X1116200Y538917D01*
X1115867Y539500D01*
X1115700Y540167D01*
X1115867Y540833D01*
X1116200Y541417D01*
X1116700Y541750D01*
X1117200Y541833D01*
X1117700Y541750D01*
X1118200Y541417D01*
X1118533Y540833D01*
X1118617Y540167D01*
X1118533Y539500D01*
X1118200Y538917D01*
X1117700Y538583D01*
X1117200Y538500D01*
G01X1122800D02*
Y543500D01*
G01X1129900D02*
Y538500D01*
G01Y539250D02*
X1129567Y538833D01*
X1129067Y538583D01*
X1128483Y538500D01*
X1127817Y538667D01*
X1127317Y539083D01*
X1126983Y539583D01*
X1126900Y540167D01*
X1126983Y540750D01*
X1127317Y541250D01*
X1127817Y541667D01*
X1128483Y541833D01*
X1129067Y541750D01*
X1129483Y541583D01*
X1129900Y541250D01*
G01X1132750Y540750D02*
X1135417D01*
X1135167Y541333D01*
X1134750Y541667D01*
X1134167Y541833D01*
X1133583Y541750D01*
X1133083Y541500D01*
X1132750Y540917D01*
X1132583Y540417D01*
Y539917D01*
X1132750Y539417D01*
X1133167Y538917D01*
X1133667Y538583D01*
X1134250Y538500D01*
X1134833Y538667D01*
X1135417Y539167D01*
G01X1138433Y538500D02*
Y541833D01*
G01Y541167D02*
X1138850Y541500D01*
X1139267Y541750D01*
X1139850Y541833D01*
X1140267Y541750D01*
X1140767Y541500D01*
G01X1148300Y538500D02*
Y541833D01*
G01Y540917D02*
X1148550Y541333D01*
X1148967Y541667D01*
X1149550Y541833D01*
X1150133Y541667D01*
X1150550Y541333D01*
X1150800Y540917D01*
Y538500D01*
G01Y540917D02*
X1151050Y541333D01*
X1151467Y541667D01*
X1152050Y541833D01*
X1152633Y541667D01*
X1153050Y541333D01*
X1153300Y540833D01*
Y538500D01*
G01X1157900D02*
Y541833D01*
G01Y541250D02*
X1157567Y541583D01*
X1157067Y541750D01*
X1156483Y541833D01*
X1155900Y541667D01*
X1155400Y541333D01*
X1155067Y540833D01*
X1154900Y540167D01*
X1155067Y539500D01*
X1155400Y539000D01*
X1155900Y538667D01*
X1156483Y538500D01*
X1157067Y538583D01*
X1157567Y538833D01*
X1157900Y539167D01*
G01X1160750Y539083D02*
X1161167Y538750D01*
X1161750Y538500D01*
X1162250D01*
X1162750Y538667D01*
X1163083Y538917D01*
X1163250Y539250D01*
X1163167Y539750D01*
X1162833Y540000D01*
X1161333Y540500D01*
X1161000Y541083D01*
X1161167Y541500D01*
X1161500Y541750D01*
X1162000Y541833D01*
X1162500Y541750D01*
X1163000Y541500D01*
G01X1166183Y538500D02*
Y543500D01*
G01X1168850Y541833D02*
X1166183Y539917D01*
G01X1167267Y540667D02*
X1169017Y538500D01*
G01X1177300Y536833D02*
Y541833D01*
G01Y541083D02*
X1177717Y541500D01*
X1178133Y541750D01*
X1178800Y541833D01*
X1179383Y541750D01*
X1179967Y541333D01*
X1180217Y540750D01*
X1180300Y540167D01*
X1180217Y539583D01*
X1179967Y539000D01*
X1179467Y538667D01*
X1178800Y538500D01*
X1178217Y538583D01*
X1177633Y538833D01*
X1177300Y539167D01*
G01X1185900Y538500D02*
Y541833D01*
G01Y541250D02*
X1185567Y541583D01*
X1185067Y541750D01*
X1184483Y541833D01*
X1183900Y541667D01*
X1183400Y541333D01*
X1183067Y540833D01*
X1182900Y540167D01*
X1183067Y539500D01*
X1183400Y539000D01*
X1183900Y538667D01*
X1184483Y538500D01*
X1185067Y538583D01*
X1185567Y538833D01*
X1185900Y539167D01*
G01X1191500Y543500D02*
Y538500D01*
G01Y539250D02*
X1191167Y538833D01*
X1190667Y538583D01*
X1190083Y538500D01*
X1189417Y538667D01*
X1188917Y539083D01*
X1188583Y539583D01*
X1188500Y540167D01*
X1188583Y540750D01*
X1188917Y541250D01*
X1189417Y541667D01*
X1190083Y541833D01*
X1190667Y541750D01*
X1191083Y541583D01*
X1191500Y541250D01*
G01X1195433Y537583D02*
X1195767Y538667D01*
G01X1206800Y543500D02*
Y538500D01*
G01X1205633Y541833D02*
X1207967D01*
G01X1210983Y538500D02*
Y543500D01*
G01Y541083D02*
X1211400Y541500D01*
X1211817Y541750D01*
X1212483Y541833D01*
X1212983Y541750D01*
X1213567Y541417D01*
X1213817Y540917D01*
Y538500D01*
G01X1216750Y540750D02*
X1219417D01*
X1219167Y541333D01*
X1218750Y541667D01*
X1218167Y541833D01*
X1217583Y541750D01*
X1217083Y541500D01*
X1216750Y540917D01*
X1216583Y540417D01*
Y539917D01*
X1216750Y539417D01*
X1217167Y538917D01*
X1217667Y538583D01*
X1218250Y538500D01*
X1218833Y538667D01*
X1219417Y539167D01*
G01X1230700Y538500D02*
Y541833D01*
G01Y541250D02*
X1230367Y541583D01*
X1229867Y541750D01*
X1229283Y541833D01*
X1228700Y541667D01*
X1228200Y541333D01*
X1227867Y540833D01*
X1227700Y540167D01*
X1227867Y539500D01*
X1228200Y539000D01*
X1228700Y538667D01*
X1229283Y538500D01*
X1229867Y538583D01*
X1230367Y538833D01*
X1230700Y539167D01*
G01X1233383Y538500D02*
Y541833D01*
G01Y541000D02*
X1233717Y541417D01*
X1234217Y541750D01*
X1234883Y541833D01*
X1235467Y541750D01*
X1235967Y541417D01*
X1236217Y540833D01*
Y538500D01*
G01X1238983D02*
Y541833D01*
G01Y541000D02*
X1239317Y541417D01*
X1239817Y541750D01*
X1240483Y541833D01*
X1241067Y541750D01*
X1241567Y541417D01*
X1241817Y540833D01*
Y538500D01*
G01X1244583Y541833D02*
Y539500D01*
X1244917Y538917D01*
X1245417Y538583D01*
X1246000Y538500D01*
X1246583Y538583D01*
X1247083Y538917D01*
X1247417Y539500D01*
G01Y538500D02*
Y541833D01*
G01X1253100Y538500D02*
Y541833D01*
G01Y541250D02*
X1252767Y541583D01*
X1252267Y541750D01*
X1251683Y541833D01*
X1251100Y541667D01*
X1250600Y541333D01*
X1250267Y540833D01*
X1250100Y540167D01*
X1250267Y539500D01*
X1250600Y539000D01*
X1251100Y538667D01*
X1251683Y538500D01*
X1252267Y538583D01*
X1252767Y538833D01*
X1253100Y539167D01*
G01X1257200Y538500D02*
Y543500D01*
G01X1267233Y538500D02*
Y541833D01*
G01Y541167D02*
X1267650Y541500D01*
X1268067Y541750D01*
X1268650Y541833D01*
X1269067Y541750D01*
X1269567Y541500D01*
G01X1274000Y541833D02*
Y538500D01*
G01Y543167D02*
X1273833Y543250D01*
Y543417D01*
X1274000Y543500D01*
X1274167Y543417D01*
Y543250D01*
X1274000Y543167D01*
G01X1278183Y538500D02*
Y541833D01*
G01Y541000D02*
X1278517Y541417D01*
X1279017Y541750D01*
X1279683Y541833D01*
X1280267Y541750D01*
X1280767Y541417D01*
X1281017Y540833D01*
Y538500D01*
G01X1284033Y537250D02*
X1284617Y536917D01*
X1285283Y536833D01*
X1285867Y536917D01*
X1286367Y537333D01*
X1286700Y537917D01*
Y541833D01*
G01Y541167D02*
X1286367Y541500D01*
X1285867Y541750D01*
X1285283Y541833D01*
X1284617Y541667D01*
X1284200Y541333D01*
X1283867Y540750D01*
X1283700Y540167D01*
X1283783Y539667D01*
X1284117Y539083D01*
X1284617Y538667D01*
X1285283Y538500D01*
X1285783Y538583D01*
X1286367Y538917D01*
X1286700Y539250D01*
G01X1295150Y539083D02*
X1295567Y538750D01*
X1296150Y538500D01*
X1296650D01*
X1297150Y538667D01*
X1297483Y538917D01*
X1297650Y539250D01*
X1297567Y539750D01*
X1297233Y540000D01*
X1295733Y540500D01*
X1295400Y541083D01*
X1295567Y541500D01*
X1295900Y541750D01*
X1296400Y541833D01*
X1296900Y541750D01*
X1297400Y541500D01*
G01X1300583Y538500D02*
Y543500D01*
G01Y541083D02*
X1301000Y541500D01*
X1301417Y541750D01*
X1302083Y541833D01*
X1302583Y541750D01*
X1303167Y541417D01*
X1303417Y540917D01*
Y538500D01*
G01X1307600D02*
X1307100Y538583D01*
X1306600Y538917D01*
X1306267Y539500D01*
X1306100Y540167D01*
X1306267Y540833D01*
X1306600Y541417D01*
X1307100Y541750D01*
X1307600Y541833D01*
X1308100Y541750D01*
X1308600Y541417D01*
X1308933Y540833D01*
X1309017Y540167D01*
X1308933Y539500D01*
X1308600Y538917D01*
X1308100Y538583D01*
X1307600Y538500D01*
G01X1311783Y541833D02*
Y539500D01*
X1312117Y538917D01*
X1312617Y538583D01*
X1313200Y538500D01*
X1313783Y538583D01*
X1314283Y538917D01*
X1314617Y539500D01*
G01Y538500D02*
Y541833D01*
G01X1318800Y538500D02*
Y543500D01*
G01X1325900D02*
Y538500D01*
G01Y539250D02*
X1325567Y538833D01*
X1325067Y538583D01*
X1324483Y538500D01*
X1323817Y538667D01*
X1323317Y539083D01*
X1322983Y539583D01*
X1322900Y540167D01*
X1322983Y540750D01*
X1323317Y541250D01*
X1323817Y541667D01*
X1324483Y541833D01*
X1325067Y541750D01*
X1325483Y541583D01*
X1325900Y541250D01*
G01X1032500Y552500D02*
Y557500D01*
G01Y555000D02*
X1032917Y555500D01*
X1033417Y555750D01*
X1033917Y555833D01*
X1034667Y555667D01*
X1035167Y555333D01*
X1035500Y554750D01*
Y554083D01*
X1035333Y553417D01*
X1035000Y552917D01*
X1034417Y552583D01*
X1033917Y552500D01*
X1033417Y552583D01*
X1032917Y552833D01*
X1032500Y553250D01*
G01X1038350Y554750D02*
X1041017D01*
X1040767Y555333D01*
X1040350Y555667D01*
X1039767Y555833D01*
X1039183Y555750D01*
X1038683Y555500D01*
X1038350Y554917D01*
X1038183Y554417D01*
Y553917D01*
X1038350Y553417D01*
X1038767Y552917D01*
X1039267Y552583D01*
X1039850Y552500D01*
X1040433Y552667D01*
X1041017Y553167D01*
G01X1050800Y557500D02*
Y552500D01*
G01X1049633Y555833D02*
X1051967D01*
G01X1055150Y554750D02*
X1057817D01*
X1057567Y555333D01*
X1057150Y555667D01*
X1056567Y555833D01*
X1055983Y555750D01*
X1055483Y555500D01*
X1055150Y554917D01*
X1054983Y554417D01*
Y553917D01*
X1055150Y553417D01*
X1055567Y552917D01*
X1056067Y552583D01*
X1056650Y552500D01*
X1057233Y552667D01*
X1057817Y553167D01*
G01X1060583Y552500D02*
Y555833D01*
G01Y555000D02*
X1060917Y555417D01*
X1061417Y555750D01*
X1062083Y555833D01*
X1062667Y555750D01*
X1063167Y555417D01*
X1063417Y554833D01*
Y552500D01*
G01X1067600Y557500D02*
Y552500D01*
G01X1066433Y555833D02*
X1068767D01*
G01X1071950Y554750D02*
X1074617D01*
X1074367Y555333D01*
X1073950Y555667D01*
X1073367Y555833D01*
X1072783Y555750D01*
X1072283Y555500D01*
X1071950Y554917D01*
X1071783Y554417D01*
Y553917D01*
X1071950Y553417D01*
X1072367Y552917D01*
X1072867Y552583D01*
X1073450Y552500D01*
X1074033Y552667D01*
X1074617Y553167D01*
G01X1080300Y557500D02*
Y552500D01*
G01Y553250D02*
X1079967Y552833D01*
X1079467Y552583D01*
X1078883Y552500D01*
X1078217Y552667D01*
X1077717Y553083D01*
X1077383Y553583D01*
X1077300Y554167D01*
X1077383Y554750D01*
X1077717Y555250D01*
X1078217Y555667D01*
X1078883Y555833D01*
X1079467Y555750D01*
X1079883Y555583D01*
X1080300Y555250D01*
G01X1087917Y555833D02*
X1088917Y552500D01*
X1090000Y555833D01*
X1091083Y552500D01*
X1092083Y555833D01*
G01X1095600D02*
Y552500D01*
G01Y557167D02*
X1095433Y557250D01*
Y557417D01*
X1095600Y557500D01*
X1095767Y557417D01*
Y557250D01*
X1095600Y557167D01*
G01X1101200Y557500D02*
Y552500D01*
G01X1100033Y555833D02*
X1102367D01*
G01X1105383Y552500D02*
Y557500D01*
G01Y555083D02*
X1105800Y555500D01*
X1106217Y555750D01*
X1106883Y555833D01*
X1107383Y555750D01*
X1107967Y555417D01*
X1108217Y554917D01*
Y552500D01*
G01X1116750Y553083D02*
X1117167Y552750D01*
X1117750Y552500D01*
X1118250D01*
X1118750Y552667D01*
X1119083Y552917D01*
X1119250Y553250D01*
X1119167Y553750D01*
X1118833Y554000D01*
X1117333Y554500D01*
X1117000Y555083D01*
X1117167Y555500D01*
X1117500Y555750D01*
X1118000Y555833D01*
X1118500Y555750D01*
X1119000Y555500D01*
G01X1123600Y552500D02*
X1123100Y552583D01*
X1122600Y552917D01*
X1122267Y553500D01*
X1122100Y554167D01*
X1122267Y554833D01*
X1122600Y555417D01*
X1123100Y555750D01*
X1123600Y555833D01*
X1124100Y555750D01*
X1124600Y555417D01*
X1124933Y554833D01*
X1125017Y554167D01*
X1124933Y553500D01*
X1124600Y552917D01*
X1124100Y552583D01*
X1123600Y552500D01*
G01X1129200D02*
Y557500D01*
G01X1136300D02*
Y552500D01*
G01Y553250D02*
X1135967Y552833D01*
X1135467Y552583D01*
X1134883Y552500D01*
X1134217Y552667D01*
X1133717Y553083D01*
X1133383Y553583D01*
X1133300Y554167D01*
X1133383Y554750D01*
X1133717Y555250D01*
X1134217Y555667D01*
X1134883Y555833D01*
X1135467Y555750D01*
X1135883Y555583D01*
X1136300Y555250D01*
G01X1139150Y554750D02*
X1141817D01*
X1141567Y555333D01*
X1141150Y555667D01*
X1140567Y555833D01*
X1139983Y555750D01*
X1139483Y555500D01*
X1139150Y554917D01*
X1138983Y554417D01*
Y553917D01*
X1139150Y553417D01*
X1139567Y552917D01*
X1140067Y552583D01*
X1140650Y552500D01*
X1141233Y552667D01*
X1141817Y553167D01*
G01X1144833Y552500D02*
Y555833D01*
G01Y555167D02*
X1145250Y555500D01*
X1145667Y555750D01*
X1146250Y555833D01*
X1146667Y555750D01*
X1147167Y555500D01*
G01X1154700Y552500D02*
Y555833D01*
G01Y554917D02*
X1154950Y555333D01*
X1155367Y555667D01*
X1155950Y555833D01*
X1156533Y555667D01*
X1156950Y555333D01*
X1157200Y554917D01*
Y552500D01*
G01Y554917D02*
X1157450Y555333D01*
X1157867Y555667D01*
X1158450Y555833D01*
X1159033Y555667D01*
X1159450Y555333D01*
X1159700Y554833D01*
Y552500D01*
G01X1164300D02*
Y555833D01*
G01Y555250D02*
X1163967Y555583D01*
X1163467Y555750D01*
X1162883Y555833D01*
X1162300Y555667D01*
X1161800Y555333D01*
X1161467Y554833D01*
X1161300Y554167D01*
X1161467Y553500D01*
X1161800Y553000D01*
X1162300Y552667D01*
X1162883Y552500D01*
X1163467Y552583D01*
X1163967Y552833D01*
X1164300Y553167D01*
G01X1167150Y553083D02*
X1167567Y552750D01*
X1168150Y552500D01*
X1168650D01*
X1169150Y552667D01*
X1169483Y552917D01*
X1169650Y553250D01*
X1169567Y553750D01*
X1169233Y554000D01*
X1167733Y554500D01*
X1167400Y555083D01*
X1167567Y555500D01*
X1167900Y555750D01*
X1168400Y555833D01*
X1168900Y555750D01*
X1169400Y555500D01*
G01X1172583Y552500D02*
Y557500D01*
G01X1175250Y555833D02*
X1172583Y553917D01*
G01X1173667Y554667D02*
X1175417Y552500D01*
G01X1179600Y552333D02*
X1179433Y552417D01*
Y552583D01*
X1179600Y552667D01*
X1179767Y552583D01*
Y552417D01*
X1179600Y552333D01*
G01X1034000Y566500D02*
Y561500D01*
G01X1032833Y564833D02*
X1035167D01*
G01X1039600Y561500D02*
X1039100Y561583D01*
X1038600Y561917D01*
X1038267Y562500D01*
X1038100Y563167D01*
X1038267Y563833D01*
X1038600Y564417D01*
X1039100Y564750D01*
X1039600Y564833D01*
X1040100Y564750D01*
X1040600Y564417D01*
X1040933Y563833D01*
X1041017Y563167D01*
X1040933Y562500D01*
X1040600Y561917D01*
X1040100Y561583D01*
X1039600Y561500D01*
G01X1049300D02*
Y566500D01*
G01Y564000D02*
X1049717Y564500D01*
X1050217Y564750D01*
X1050717Y564833D01*
X1051467Y564667D01*
X1051967Y564333D01*
X1052300Y563750D01*
Y563083D01*
X1052133Y562417D01*
X1051800Y561917D01*
X1051217Y561583D01*
X1050717Y561500D01*
X1050217Y561583D01*
X1049717Y561833D01*
X1049300Y562250D01*
G01X1055150Y563750D02*
X1057817D01*
X1057567Y564333D01*
X1057150Y564667D01*
X1056567Y564833D01*
X1055983Y564750D01*
X1055483Y564500D01*
X1055150Y563917D01*
X1054983Y563417D01*
Y562917D01*
X1055150Y562417D01*
X1055567Y561917D01*
X1056067Y561583D01*
X1056650Y561500D01*
X1057233Y561667D01*
X1057817Y562167D01*
G01X1068933Y564417D02*
X1068350Y564750D01*
X1067850Y564833D01*
X1067183Y564667D01*
X1066683Y564333D01*
X1066350Y563750D01*
X1066267Y563167D01*
X1066350Y562583D01*
X1066683Y562083D01*
X1067183Y561667D01*
X1067850Y561500D01*
X1068433Y561667D01*
X1068933Y562000D01*
G01X1073200Y561500D02*
X1072700Y561583D01*
X1072200Y561917D01*
X1071867Y562500D01*
X1071700Y563167D01*
X1071867Y563833D01*
X1072200Y564417D01*
X1072700Y564750D01*
X1073200Y564833D01*
X1073700Y564750D01*
X1074200Y564417D01*
X1074533Y563833D01*
X1074617Y563167D01*
X1074533Y562500D01*
X1074200Y561917D01*
X1073700Y561583D01*
X1073200Y561500D01*
G01X1077300Y564833D02*
X1078800Y561500D01*
X1080300Y564833D01*
G01X1083150Y563750D02*
X1085817D01*
X1085567Y564333D01*
X1085150Y564667D01*
X1084567Y564833D01*
X1083983Y564750D01*
X1083483Y564500D01*
X1083150Y563917D01*
X1082983Y563417D01*
Y562917D01*
X1083150Y562417D01*
X1083567Y561917D01*
X1084067Y561583D01*
X1084650Y561500D01*
X1085233Y561667D01*
X1085817Y562167D01*
G01X1088833Y561500D02*
Y564833D01*
G01Y564167D02*
X1089250Y564500D01*
X1089667Y564750D01*
X1090250Y564833D01*
X1090667Y564750D01*
X1091167Y564500D01*
G01X1094350Y563750D02*
X1097017D01*
X1096767Y564333D01*
X1096350Y564667D01*
X1095767Y564833D01*
X1095183Y564750D01*
X1094683Y564500D01*
X1094350Y563917D01*
X1094183Y563417D01*
Y562917D01*
X1094350Y562417D01*
X1094767Y561917D01*
X1095267Y561583D01*
X1095850Y561500D01*
X1096433Y561667D01*
X1097017Y562167D01*
G01X1102700Y566500D02*
Y561500D01*
G01Y562250D02*
X1102367Y561833D01*
X1101867Y561583D01*
X1101283Y561500D01*
X1100617Y561667D01*
X1100117Y562083D01*
X1099783Y562583D01*
X1099700Y563167D01*
X1099783Y563750D01*
X1100117Y564250D01*
X1100617Y564667D01*
X1101283Y564833D01*
X1101867Y564750D01*
X1102283Y564583D01*
X1102700Y564250D01*
G01X1110900Y561500D02*
Y566500D01*
G01Y564000D02*
X1111317Y564500D01*
X1111817Y564750D01*
X1112317Y564833D01*
X1113067Y564667D01*
X1113567Y564333D01*
X1113900Y563750D01*
Y563083D01*
X1113733Y562417D01*
X1113400Y561917D01*
X1112817Y561583D01*
X1112317Y561500D01*
X1111817Y561583D01*
X1111317Y561833D01*
X1110900Y562250D01*
G01X1116250Y560000D02*
X1116750Y559833D01*
X1117417Y560000D01*
X1117833Y560333D01*
X1118167Y560750D01*
X1118667Y562083D01*
X1119750Y564833D01*
G01X1117083D02*
X1118667Y562083D01*
G01X1127950D02*
X1128367Y561750D01*
X1128950Y561500D01*
X1129450D01*
X1129950Y561667D01*
X1130283Y561917D01*
X1130450Y562250D01*
X1130367Y562750D01*
X1130033Y563000D01*
X1128533Y563500D01*
X1128200Y564083D01*
X1128367Y564500D01*
X1128700Y564750D01*
X1129200Y564833D01*
X1129700Y564750D01*
X1130200Y564500D01*
G01X1134800Y561500D02*
X1134300Y561583D01*
X1133800Y561917D01*
X1133467Y562500D01*
X1133300Y563167D01*
X1133467Y563833D01*
X1133800Y564417D01*
X1134300Y564750D01*
X1134800Y564833D01*
X1135300Y564750D01*
X1135800Y564417D01*
X1136133Y563833D01*
X1136217Y563167D01*
X1136133Y562500D01*
X1135800Y561917D01*
X1135300Y561583D01*
X1134800Y561500D01*
G01X1140400D02*
Y566500D01*
G01X1147500D02*
Y561500D01*
G01Y562250D02*
X1147167Y561833D01*
X1146667Y561583D01*
X1146083Y561500D01*
X1145417Y561667D01*
X1144917Y562083D01*
X1144583Y562583D01*
X1144500Y563167D01*
X1144583Y563750D01*
X1144917Y564250D01*
X1145417Y564667D01*
X1146083Y564833D01*
X1146667Y564750D01*
X1147083Y564583D01*
X1147500Y564250D01*
G01X1150350Y563750D02*
X1153017D01*
X1152767Y564333D01*
X1152350Y564667D01*
X1151767Y564833D01*
X1151183Y564750D01*
X1150683Y564500D01*
X1150350Y563917D01*
X1150183Y563417D01*
Y562917D01*
X1150350Y562417D01*
X1150767Y561917D01*
X1151267Y561583D01*
X1151850Y561500D01*
X1152433Y561667D01*
X1153017Y562167D01*
G01X1156033Y561500D02*
Y564833D01*
G01Y564167D02*
X1156450Y564500D01*
X1156867Y564750D01*
X1157450Y564833D01*
X1157867Y564750D01*
X1158367Y564500D01*
G01X1165900Y561500D02*
Y564833D01*
G01Y563917D02*
X1166150Y564333D01*
X1166567Y564667D01*
X1167150Y564833D01*
X1167733Y564667D01*
X1168150Y564333D01*
X1168400Y563917D01*
Y561500D01*
G01Y563917D02*
X1168650Y564333D01*
X1169067Y564667D01*
X1169650Y564833D01*
X1170233Y564667D01*
X1170650Y564333D01*
X1170900Y563833D01*
Y561500D01*
G01X1175500D02*
Y564833D01*
G01Y564250D02*
X1175167Y564583D01*
X1174667Y564750D01*
X1174083Y564833D01*
X1173500Y564667D01*
X1173000Y564333D01*
X1172667Y563833D01*
X1172500Y563167D01*
X1172667Y562500D01*
X1173000Y562000D01*
X1173500Y561667D01*
X1174083Y561500D01*
X1174667Y561583D01*
X1175167Y561833D01*
X1175500Y562167D01*
G01X1178350Y562083D02*
X1178767Y561750D01*
X1179350Y561500D01*
X1179850D01*
X1180350Y561667D01*
X1180683Y561917D01*
X1180850Y562250D01*
X1180767Y562750D01*
X1180433Y563000D01*
X1178933Y563500D01*
X1178600Y564083D01*
X1178767Y564500D01*
X1179100Y564750D01*
X1179600Y564833D01*
X1180100Y564750D01*
X1180600Y564500D01*
G01X1183783Y561500D02*
Y566500D01*
G01X1186450Y564833D02*
X1183783Y562917D01*
G01X1184867Y563667D02*
X1186617Y561500D01*
G01X1197900D02*
Y564833D01*
G01Y564250D02*
X1197567Y564583D01*
X1197067Y564750D01*
X1196483Y564833D01*
X1195900Y564667D01*
X1195400Y564333D01*
X1195067Y563833D01*
X1194900Y563167D01*
X1195067Y562500D01*
X1195400Y562000D01*
X1195900Y561667D01*
X1196483Y561500D01*
X1197067Y561583D01*
X1197567Y561833D01*
X1197900Y562167D01*
G01X1200583Y561500D02*
Y564833D01*
G01Y564000D02*
X1200917Y564417D01*
X1201417Y564750D01*
X1202083Y564833D01*
X1202667Y564750D01*
X1203167Y564417D01*
X1203417Y563833D01*
Y561500D01*
G01X1209100Y566500D02*
Y561500D01*
G01Y562250D02*
X1208767Y561833D01*
X1208267Y561583D01*
X1207683Y561500D01*
X1207017Y561667D01*
X1206517Y562083D01*
X1206183Y562583D01*
X1206100Y563167D01*
X1206183Y563750D01*
X1206517Y564250D01*
X1207017Y564667D01*
X1207683Y564833D01*
X1208267Y564750D01*
X1208683Y564583D01*
X1209100Y564250D01*
G01X1217383Y561500D02*
Y566500D01*
G01Y564083D02*
X1217800Y564500D01*
X1218217Y564750D01*
X1218883Y564833D01*
X1219383Y564750D01*
X1219967Y564417D01*
X1220217Y563917D01*
Y561500D01*
G01X1224400D02*
X1223900Y561583D01*
X1223400Y561917D01*
X1223067Y562500D01*
X1222900Y563167D01*
X1223067Y563833D01*
X1223400Y564417D01*
X1223900Y564750D01*
X1224400Y564833D01*
X1224900Y564750D01*
X1225400Y564417D01*
X1225733Y563833D01*
X1225817Y563167D01*
X1225733Y562500D01*
X1225400Y561917D01*
X1224900Y561583D01*
X1224400Y561500D01*
G01X1230000D02*
Y566500D01*
G01X1234350Y563750D02*
X1237017D01*
X1236767Y564333D01*
X1236350Y564667D01*
X1235767Y564833D01*
X1235183Y564750D01*
X1234683Y564500D01*
X1234350Y563917D01*
X1234183Y563417D01*
Y562917D01*
X1234350Y562417D01*
X1234767Y561917D01*
X1235267Y561583D01*
X1235850Y561500D01*
X1236433Y561667D01*
X1237017Y562167D01*
G01X1248300Y561500D02*
Y564833D01*
G01Y564250D02*
X1247967Y564583D01*
X1247467Y564750D01*
X1246883Y564833D01*
X1246300Y564667D01*
X1245800Y564333D01*
X1245467Y563833D01*
X1245300Y563167D01*
X1245467Y562500D01*
X1245800Y562000D01*
X1246300Y561667D01*
X1246883Y561500D01*
X1247467Y561583D01*
X1247967Y561833D01*
X1248300Y562167D01*
G01X1252400Y561500D02*
Y566500D01*
G01X1256750Y562083D02*
X1257167Y561750D01*
X1257750Y561500D01*
X1258250D01*
X1258750Y561667D01*
X1259083Y561917D01*
X1259250Y562250D01*
X1259167Y562750D01*
X1258833Y563000D01*
X1257333Y563500D01*
X1257000Y564083D01*
X1257167Y564500D01*
X1257500Y564750D01*
X1258000Y564833D01*
X1258500Y564750D01*
X1259000Y564500D01*
G01X1263600Y561500D02*
X1263100Y561583D01*
X1262600Y561917D01*
X1262267Y562500D01*
X1262100Y563167D01*
X1262267Y563833D01*
X1262600Y564417D01*
X1263100Y564750D01*
X1263600Y564833D01*
X1264100Y564750D01*
X1264600Y564417D01*
X1264933Y563833D01*
X1265017Y563167D01*
X1264933Y562500D01*
X1264600Y561917D01*
X1264100Y561583D01*
X1263600Y561500D01*
G01X1273383D02*
Y564833D01*
G01Y564000D02*
X1273717Y564417D01*
X1274217Y564750D01*
X1274883Y564833D01*
X1275467Y564750D01*
X1275967Y564417D01*
X1276217Y563833D01*
Y561500D01*
G01X1279150Y563750D02*
X1281817D01*
X1281567Y564333D01*
X1281150Y564667D01*
X1280567Y564833D01*
X1279983Y564750D01*
X1279483Y564500D01*
X1279150Y563917D01*
X1278983Y563417D01*
Y562917D01*
X1279150Y562417D01*
X1279567Y561917D01*
X1280067Y561583D01*
X1280650Y561500D01*
X1281233Y561667D01*
X1281817Y562167D01*
G01X1284750Y563750D02*
X1287417D01*
X1287167Y564333D01*
X1286750Y564667D01*
X1286167Y564833D01*
X1285583Y564750D01*
X1285083Y564500D01*
X1284750Y563917D01*
X1284583Y563417D01*
Y562917D01*
X1284750Y562417D01*
X1285167Y561917D01*
X1285667Y561583D01*
X1286250Y561500D01*
X1286833Y561667D01*
X1287417Y562167D01*
G01X1293100Y566500D02*
Y561500D01*
G01Y562250D02*
X1292767Y561833D01*
X1292267Y561583D01*
X1291683Y561500D01*
X1291017Y561667D01*
X1290517Y562083D01*
X1290183Y562583D01*
X1290100Y563167D01*
X1290183Y563750D01*
X1290517Y564250D01*
X1291017Y564667D01*
X1291683Y564833D01*
X1292267Y564750D01*
X1292683Y564583D01*
X1293100Y564250D01*
G01X1302800Y566500D02*
Y561500D01*
G01X1301633Y564833D02*
X1303967D01*
G01X1308400Y561500D02*
X1307900Y561583D01*
X1307400Y561917D01*
X1307067Y562500D01*
X1306900Y563167D01*
X1307067Y563833D01*
X1307400Y564417D01*
X1307900Y564750D01*
X1308400Y564833D01*
X1308900Y564750D01*
X1309400Y564417D01*
X1309733Y563833D01*
X1309817Y563167D01*
X1309733Y562500D01*
X1309400Y561917D01*
X1308900Y561583D01*
X1308400Y561500D01*
G01X1022000Y569500D02*
Y574500D01*
X1021000Y573500D01*
G01Y569500D02*
X1023000D01*
G01X1027600Y569333D02*
X1027433Y569417D01*
Y569583D01*
X1027600Y569667D01*
X1027767Y569583D01*
Y569417D01*
X1027600Y569333D01*
G01X1033200Y574500D02*
Y569500D01*
G01X1031283Y574500D02*
X1035117D01*
G01X1037383Y569500D02*
Y574500D01*
G01Y572083D02*
X1037800Y572500D01*
X1038217Y572750D01*
X1038883Y572833D01*
X1039383Y572750D01*
X1039967Y572417D01*
X1040217Y571917D01*
Y569500D01*
G01X1043150Y571750D02*
X1045817D01*
X1045567Y572333D01*
X1045150Y572667D01*
X1044567Y572833D01*
X1043983Y572750D01*
X1043483Y572500D01*
X1043150Y571917D01*
X1042983Y571417D01*
Y570917D01*
X1043150Y570417D01*
X1043567Y569917D01*
X1044067Y569583D01*
X1044650Y569500D01*
X1045233Y569667D01*
X1045817Y570167D01*
G01X1054350Y570083D02*
X1054767Y569750D01*
X1055350Y569500D01*
X1055850D01*
X1056350Y569667D01*
X1056683Y569917D01*
X1056850Y570250D01*
X1056767Y570750D01*
X1056433Y571000D01*
X1054933Y571500D01*
X1054600Y572083D01*
X1054767Y572500D01*
X1055100Y572750D01*
X1055600Y572833D01*
X1056100Y572750D01*
X1056600Y572500D01*
G01X1061200Y572833D02*
Y569500D01*
G01Y574167D02*
X1061033Y574250D01*
Y574417D01*
X1061200Y574500D01*
X1061367Y574417D01*
Y574250D01*
X1061200Y574167D01*
G01X1068300Y574500D02*
Y569500D01*
G01Y570250D02*
X1067967Y569833D01*
X1067467Y569583D01*
X1066883Y569500D01*
X1066217Y569667D01*
X1065717Y570083D01*
X1065383Y570583D01*
X1065300Y571167D01*
X1065383Y571750D01*
X1065717Y572250D01*
X1066217Y572667D01*
X1066883Y572833D01*
X1067467Y572750D01*
X1067883Y572583D01*
X1068300Y572250D01*
G01X1071150Y571750D02*
X1073817D01*
X1073567Y572333D01*
X1073150Y572667D01*
X1072567Y572833D01*
X1071983Y572750D01*
X1071483Y572500D01*
X1071150Y571917D01*
X1070983Y571417D01*
Y570917D01*
X1071150Y570417D01*
X1071567Y569917D01*
X1072067Y569583D01*
X1072650Y569500D01*
X1073233Y569667D01*
X1073817Y570167D01*
G01X1081517Y572833D02*
X1082517Y569500D01*
X1083600Y572833D01*
X1084683Y569500D01*
X1085683Y572833D01*
G01X1089200D02*
Y569500D01*
G01Y574167D02*
X1089033Y574250D01*
Y574417D01*
X1089200Y574500D01*
X1089367Y574417D01*
Y574250D01*
X1089200Y574167D01*
G01X1094800Y574500D02*
Y569500D01*
G01X1093633Y572833D02*
X1095967D01*
G01X1098983Y569500D02*
Y574500D01*
G01Y572083D02*
X1099400Y572500D01*
X1099817Y572750D01*
X1100483Y572833D01*
X1100983Y572750D01*
X1101567Y572417D01*
X1101817Y571917D01*
Y569500D01*
G01X1106000D02*
X1105500Y569583D01*
X1105000Y569917D01*
X1104667Y570500D01*
X1104500Y571167D01*
X1104667Y571833D01*
X1105000Y572417D01*
X1105500Y572750D01*
X1106000Y572833D01*
X1106500Y572750D01*
X1107000Y572417D01*
X1107333Y571833D01*
X1107417Y571167D01*
X1107333Y570500D01*
X1107000Y569917D01*
X1106500Y569583D01*
X1106000Y569500D01*
G01X1110183Y572833D02*
Y570500D01*
X1110517Y569917D01*
X1111017Y569583D01*
X1111600Y569500D01*
X1112183Y569583D01*
X1112683Y569917D01*
X1113017Y570500D01*
G01Y569500D02*
Y572833D01*
G01X1117200Y574500D02*
Y569500D01*
G01X1116033Y572833D02*
X1118367D01*
G01X1127150Y570083D02*
X1127567Y569750D01*
X1128150Y569500D01*
X1128650D01*
X1129150Y569667D01*
X1129483Y569917D01*
X1129650Y570250D01*
X1129567Y570750D01*
X1129233Y571000D01*
X1127733Y571500D01*
X1127400Y572083D01*
X1127567Y572500D01*
X1127900Y572750D01*
X1128400Y572833D01*
X1128900Y572750D01*
X1129400Y572500D01*
G01X1134000Y569500D02*
X1133500Y569583D01*
X1133000Y569917D01*
X1132667Y570500D01*
X1132500Y571167D01*
X1132667Y571833D01*
X1133000Y572417D01*
X1133500Y572750D01*
X1134000Y572833D01*
X1134500Y572750D01*
X1135000Y572417D01*
X1135333Y571833D01*
X1135417Y571167D01*
X1135333Y570500D01*
X1135000Y569917D01*
X1134500Y569583D01*
X1134000Y569500D01*
G01X1139600D02*
Y574500D01*
G01X1146700D02*
Y569500D01*
G01Y570250D02*
X1146367Y569833D01*
X1145867Y569583D01*
X1145283Y569500D01*
X1144617Y569667D01*
X1144117Y570083D01*
X1143783Y570583D01*
X1143700Y571167D01*
X1143783Y571750D01*
X1144117Y572250D01*
X1144617Y572667D01*
X1145283Y572833D01*
X1145867Y572750D01*
X1146283Y572583D01*
X1146700Y572250D01*
G01X1149550Y571750D02*
X1152217D01*
X1151967Y572333D01*
X1151550Y572667D01*
X1150967Y572833D01*
X1150383Y572750D01*
X1149883Y572500D01*
X1149550Y571917D01*
X1149383Y571417D01*
Y570917D01*
X1149550Y570417D01*
X1149967Y569917D01*
X1150467Y569583D01*
X1151050Y569500D01*
X1151633Y569667D01*
X1152217Y570167D01*
G01X1155233Y569500D02*
Y572833D01*
G01Y572167D02*
X1155650Y572500D01*
X1156067Y572750D01*
X1156650Y572833D01*
X1157067Y572750D01*
X1157567Y572500D01*
G01X1165100Y569500D02*
Y572833D01*
G01Y571917D02*
X1165350Y572333D01*
X1165767Y572667D01*
X1166350Y572833D01*
X1166933Y572667D01*
X1167350Y572333D01*
X1167600Y571917D01*
Y569500D01*
G01Y571917D02*
X1167850Y572333D01*
X1168267Y572667D01*
X1168850Y572833D01*
X1169433Y572667D01*
X1169850Y572333D01*
X1170100Y571833D01*
Y569500D01*
G01X1174700D02*
Y572833D01*
G01Y572250D02*
X1174367Y572583D01*
X1173867Y572750D01*
X1173283Y572833D01*
X1172700Y572667D01*
X1172200Y572333D01*
X1171867Y571833D01*
X1171700Y571167D01*
X1171867Y570500D01*
X1172200Y570000D01*
X1172700Y569667D01*
X1173283Y569500D01*
X1173867Y569583D01*
X1174367Y569833D01*
X1174700Y570167D01*
G01X1177550Y570083D02*
X1177967Y569750D01*
X1178550Y569500D01*
X1179050D01*
X1179550Y569667D01*
X1179883Y569917D01*
X1180050Y570250D01*
X1179967Y570750D01*
X1179633Y571000D01*
X1178133Y571500D01*
X1177800Y572083D01*
X1177967Y572500D01*
X1178300Y572750D01*
X1178800Y572833D01*
X1179300Y572750D01*
X1179800Y572500D01*
G01X1182983Y569500D02*
Y574500D01*
G01X1185650Y572833D02*
X1182983Y570917D01*
G01X1184067Y571667D02*
X1185817Y569500D01*
G01X1194100Y567833D02*
Y572833D01*
G01Y572083D02*
X1194517Y572500D01*
X1194933Y572750D01*
X1195600Y572833D01*
X1196183Y572750D01*
X1196767Y572333D01*
X1197017Y571750D01*
X1197100Y571167D01*
X1197017Y570583D01*
X1196767Y570000D01*
X1196267Y569667D01*
X1195600Y569500D01*
X1195017Y569583D01*
X1194433Y569833D01*
X1194100Y570167D01*
G01X1202700Y569500D02*
Y572833D01*
G01Y572250D02*
X1202367Y572583D01*
X1201867Y572750D01*
X1201283Y572833D01*
X1200700Y572667D01*
X1200200Y572333D01*
X1199867Y571833D01*
X1199700Y571167D01*
X1199867Y570500D01*
X1200200Y570000D01*
X1200700Y569667D01*
X1201283Y569500D01*
X1201867Y569583D01*
X1202367Y569833D01*
X1202700Y570167D01*
G01X1208300Y574500D02*
Y569500D01*
G01Y570250D02*
X1207967Y569833D01*
X1207467Y569583D01*
X1206883Y569500D01*
X1206217Y569667D01*
X1205717Y570083D01*
X1205383Y570583D01*
X1205300Y571167D01*
X1205383Y571750D01*
X1205717Y572250D01*
X1206217Y572667D01*
X1206883Y572833D01*
X1207467Y572750D01*
X1207883Y572583D01*
X1208300Y572250D01*
G01X1217833Y568583D02*
X1218167Y569667D01*
G01X1230700Y569500D02*
Y572833D01*
G01Y572250D02*
X1230367Y572583D01*
X1229867Y572750D01*
X1229283Y572833D01*
X1228700Y572667D01*
X1228200Y572333D01*
X1227867Y571833D01*
X1227700Y571167D01*
X1227867Y570500D01*
X1228200Y570000D01*
X1228700Y569667D01*
X1229283Y569500D01*
X1229867Y569583D01*
X1230367Y569833D01*
X1230700Y570167D01*
G01X1233383Y569500D02*
Y572833D01*
G01Y572000D02*
X1233717Y572417D01*
X1234217Y572750D01*
X1234883Y572833D01*
X1235467Y572750D01*
X1235967Y572417D01*
X1236217Y571833D01*
Y569500D01*
G01X1238983D02*
Y572833D01*
G01Y572000D02*
X1239317Y572417D01*
X1239817Y572750D01*
X1240483Y572833D01*
X1241067Y572750D01*
X1241567Y572417D01*
X1241817Y571833D01*
Y569500D01*
G01X1244583Y572833D02*
Y570500D01*
X1244917Y569917D01*
X1245417Y569583D01*
X1246000Y569500D01*
X1246583Y569583D01*
X1247083Y569917D01*
X1247417Y570500D01*
G01Y569500D02*
Y572833D01*
G01X1253100Y569500D02*
Y572833D01*
G01Y572250D02*
X1252767Y572583D01*
X1252267Y572750D01*
X1251683Y572833D01*
X1251100Y572667D01*
X1250600Y572333D01*
X1250267Y571833D01*
X1250100Y571167D01*
X1250267Y570500D01*
X1250600Y570000D01*
X1251100Y569667D01*
X1251683Y569500D01*
X1252267Y569583D01*
X1252767Y569833D01*
X1253100Y570167D01*
G01X1257200Y569500D02*
Y574500D01*
G01X1267233Y569500D02*
Y572833D01*
G01Y572167D02*
X1267650Y572500D01*
X1268067Y572750D01*
X1268650Y572833D01*
X1269067Y572750D01*
X1269567Y572500D01*
G01X1274000Y572833D02*
Y569500D01*
G01Y574167D02*
X1273833Y574250D01*
Y574417D01*
X1274000Y574500D01*
X1274167Y574417D01*
Y574250D01*
X1274000Y574167D01*
G01X1278183Y569500D02*
Y572833D01*
G01Y572000D02*
X1278517Y572417D01*
X1279017Y572750D01*
X1279683Y572833D01*
X1280267Y572750D01*
X1280767Y572417D01*
X1281017Y571833D01*
Y569500D01*
G01X1284033Y568250D02*
X1284617Y567917D01*
X1285283Y567833D01*
X1285867Y567917D01*
X1286367Y568333D01*
X1286700Y568917D01*
Y572833D01*
G01Y572167D02*
X1286367Y572500D01*
X1285867Y572750D01*
X1285283Y572833D01*
X1284617Y572667D01*
X1284200Y572333D01*
X1283867Y571750D01*
X1283700Y571167D01*
X1283783Y570667D01*
X1284117Y570083D01*
X1284617Y569667D01*
X1285283Y569500D01*
X1285783Y569583D01*
X1286367Y569917D01*
X1286700Y570250D01*
G01X1294983Y569500D02*
Y572833D01*
G01Y572000D02*
X1295317Y572417D01*
X1295817Y572750D01*
X1296483Y572833D01*
X1297067Y572750D01*
X1297567Y572417D01*
X1297817Y571833D01*
Y569500D01*
G01X1300750Y571750D02*
X1303417D01*
X1303167Y572333D01*
X1302750Y572667D01*
X1302167Y572833D01*
X1301583Y572750D01*
X1301083Y572500D01*
X1300750Y571917D01*
X1300583Y571417D01*
Y570917D01*
X1300750Y570417D01*
X1301167Y569917D01*
X1301667Y569583D01*
X1302250Y569500D01*
X1302833Y569667D01*
X1303417Y570167D01*
G01X1306350Y571750D02*
X1309017D01*
X1308767Y572333D01*
X1308350Y572667D01*
X1307767Y572833D01*
X1307183Y572750D01*
X1306683Y572500D01*
X1306350Y571917D01*
X1306183Y571417D01*
Y570917D01*
X1306350Y570417D01*
X1306767Y569917D01*
X1307267Y569583D01*
X1307850Y569500D01*
X1308433Y569667D01*
X1309017Y570167D01*
G01X1314700Y574500D02*
Y569500D01*
G01Y570250D02*
X1314367Y569833D01*
X1313867Y569583D01*
X1313283Y569500D01*
X1312617Y569667D01*
X1312117Y570083D01*
X1311783Y570583D01*
X1311700Y571167D01*
X1311783Y571750D01*
X1312117Y572250D01*
X1312617Y572667D01*
X1313283Y572833D01*
X1313867Y572750D01*
X1314283Y572583D01*
X1314700Y572250D01*
G01X1012083Y730500D02*
Y733833D01*
G01Y733000D02*
X1012417Y733417D01*
X1012917Y733750D01*
X1013583Y733833D01*
X1014167Y733750D01*
X1014667Y733417D01*
X1014917Y732833D01*
Y730500D01*
G01X1019100D02*
X1018600Y730583D01*
X1018100Y730917D01*
X1017767Y731500D01*
X1017600Y732167D01*
X1017767Y732833D01*
X1018100Y733417D01*
X1018600Y733750D01*
X1019100Y733833D01*
X1019600Y733750D01*
X1020100Y733417D01*
X1020433Y732833D01*
X1020517Y732167D01*
X1020433Y731500D01*
X1020100Y730917D01*
X1019600Y730583D01*
X1019100Y730500D01*
G01X1028800Y728833D02*
Y733833D01*
G01Y733083D02*
X1029217Y733500D01*
X1029633Y733750D01*
X1030300Y733833D01*
X1030883Y733750D01*
X1031467Y733333D01*
X1031717Y732750D01*
X1031800Y732167D01*
X1031717Y731583D01*
X1031467Y731000D01*
X1030967Y730667D01*
X1030300Y730500D01*
X1029717Y730583D01*
X1029133Y730833D01*
X1028800Y731167D01*
G01X1035900Y730500D02*
Y735500D01*
G01X1040083Y733833D02*
Y731500D01*
X1040417Y730917D01*
X1040917Y730583D01*
X1041500Y730500D01*
X1042083Y730583D01*
X1042583Y730917D01*
X1042917Y731500D01*
G01Y730500D02*
Y733833D01*
G01X1045933Y729250D02*
X1046517Y728917D01*
X1047183Y728833D01*
X1047767Y728917D01*
X1048267Y729333D01*
X1048600Y729917D01*
Y733833D01*
G01Y733167D02*
X1048267Y733500D01*
X1047767Y733750D01*
X1047183Y733833D01*
X1046517Y733667D01*
X1046100Y733333D01*
X1045767Y732750D01*
X1045600Y732167D01*
X1045683Y731667D01*
X1046017Y731083D01*
X1046517Y730667D01*
X1047183Y730500D01*
X1047683Y730583D01*
X1048267Y730917D01*
X1048600Y731250D01*
G01X1051533Y729250D02*
X1052117Y728917D01*
X1052783Y728833D01*
X1053367Y728917D01*
X1053867Y729333D01*
X1054200Y729917D01*
Y733833D01*
G01Y733167D02*
X1053867Y733500D01*
X1053367Y733750D01*
X1052783Y733833D01*
X1052117Y733667D01*
X1051700Y733333D01*
X1051367Y732750D01*
X1051200Y732167D01*
X1051283Y731667D01*
X1051617Y731083D01*
X1052117Y730667D01*
X1052783Y730500D01*
X1053283Y730583D01*
X1053867Y730917D01*
X1054200Y731250D01*
G01X1058300Y733833D02*
Y730500D01*
G01Y735167D02*
X1058133Y735250D01*
Y735417D01*
X1058300Y735500D01*
X1058467Y735417D01*
Y735250D01*
X1058300Y735167D01*
G01X1062483Y730500D02*
Y733833D01*
G01Y733000D02*
X1062817Y733417D01*
X1063317Y733750D01*
X1063983Y733833D01*
X1064567Y733750D01*
X1065067Y733417D01*
X1065317Y732833D01*
Y730500D01*
G01X1068333Y729250D02*
X1068917Y728917D01*
X1069583Y728833D01*
X1070167Y728917D01*
X1070667Y729333D01*
X1071000Y729917D01*
Y733833D01*
G01Y733167D02*
X1070667Y733500D01*
X1070167Y733750D01*
X1069583Y733833D01*
X1068917Y733667D01*
X1068500Y733333D01*
X1068167Y732750D01*
X1068000Y732167D01*
X1068083Y731667D01*
X1068417Y731083D01*
X1068917Y730667D01*
X1069583Y730500D01*
X1070083Y730583D01*
X1070667Y730917D01*
X1071000Y731250D01*
G01X1012083Y730500D02*
Y733833D01*
G01Y733000D02*
X1012417Y733417D01*
X1012917Y733750D01*
X1013583Y733833D01*
X1014167Y733750D01*
X1014667Y733417D01*
X1014917Y732833D01*
Y730500D01*
G01X1019100D02*
X1018600Y730583D01*
X1018100Y730917D01*
X1017767Y731500D01*
X1017600Y732167D01*
X1017767Y732833D01*
X1018100Y733417D01*
X1018600Y733750D01*
X1019100Y733833D01*
X1019600Y733750D01*
X1020100Y733417D01*
X1020433Y732833D01*
X1020517Y732167D01*
X1020433Y731500D01*
X1020100Y730917D01*
X1019600Y730583D01*
X1019100Y730500D01*
G01X1028800Y728833D02*
Y733833D01*
G01Y733083D02*
X1029217Y733500D01*
X1029633Y733750D01*
X1030300Y733833D01*
X1030883Y733750D01*
X1031467Y733333D01*
X1031717Y732750D01*
X1031800Y732167D01*
X1031717Y731583D01*
X1031467Y731000D01*
X1030967Y730667D01*
X1030300Y730500D01*
X1029717Y730583D01*
X1029133Y730833D01*
X1028800Y731167D01*
G01X1035900Y730500D02*
Y735500D01*
G01X1040083Y733833D02*
Y731500D01*
X1040417Y730917D01*
X1040917Y730583D01*
X1041500Y730500D01*
X1042083Y730583D01*
X1042583Y730917D01*
X1042917Y731500D01*
G01Y730500D02*
Y733833D01*
G01X1045933Y729250D02*
X1046517Y728917D01*
X1047183Y728833D01*
X1047767Y728917D01*
X1048267Y729333D01*
X1048600Y729917D01*
Y733833D01*
G01Y733167D02*
X1048267Y733500D01*
X1047767Y733750D01*
X1047183Y733833D01*
X1046517Y733667D01*
X1046100Y733333D01*
X1045767Y732750D01*
X1045600Y732167D01*
X1045683Y731667D01*
X1046017Y731083D01*
X1046517Y730667D01*
X1047183Y730500D01*
X1047683Y730583D01*
X1048267Y730917D01*
X1048600Y731250D01*
G01X1051533Y729250D02*
X1052117Y728917D01*
X1052783Y728833D01*
X1053367Y728917D01*
X1053867Y729333D01*
X1054200Y729917D01*
Y733833D01*
G01Y733167D02*
X1053867Y733500D01*
X1053367Y733750D01*
X1052783Y733833D01*
X1052117Y733667D01*
X1051700Y733333D01*
X1051367Y732750D01*
X1051200Y732167D01*
X1051283Y731667D01*
X1051617Y731083D01*
X1052117Y730667D01*
X1052783Y730500D01*
X1053283Y730583D01*
X1053867Y730917D01*
X1054200Y731250D01*
G01X1058300Y733833D02*
Y730500D01*
G01Y735167D02*
X1058133Y735250D01*
Y735417D01*
X1058300Y735500D01*
X1058467Y735417D01*
Y735250D01*
X1058300Y735167D01*
G01X1062483Y730500D02*
Y733833D01*
G01Y733000D02*
X1062817Y733417D01*
X1063317Y733750D01*
X1063983Y733833D01*
X1064567Y733750D01*
X1065067Y733417D01*
X1065317Y732833D01*
Y730500D01*
G01X1068333Y729250D02*
X1068917Y728917D01*
X1069583Y728833D01*
X1070167Y728917D01*
X1070667Y729333D01*
X1071000Y729917D01*
Y733833D01*
G01Y733167D02*
X1070667Y733500D01*
X1070167Y733750D01*
X1069583Y733833D01*
X1068917Y733667D01*
X1068500Y733333D01*
X1068167Y732750D01*
X1068000Y732167D01*
X1068083Y731667D01*
X1068417Y731083D01*
X1068917Y730667D01*
X1069583Y730500D01*
X1070083Y730583D01*
X1070667Y730917D01*
X1071000Y731250D01*
G01X1089493Y104700D02*
Y99700D01*
X1092827D01*
G01X1095510Y103033D02*
X1098010Y99700D01*
G01Y103033D02*
X1095510Y99700D01*
G01X1102360Y99533D02*
X1102193Y99617D01*
Y99783D01*
X1102360Y99867D01*
X1102527Y99783D01*
Y99617D01*
X1102360Y99533D01*
G01Y101783D02*
X1102193Y101867D01*
Y102033D01*
X1102360Y102117D01*
X1102527Y102033D01*
Y101867D01*
X1102360Y101783D01*
G01X1111060Y99700D02*
Y103033D01*
G01Y102117D02*
X1111310Y102533D01*
X1111727Y102867D01*
X1112310Y103033D01*
X1112893Y102867D01*
X1113310Y102533D01*
X1113560Y102117D01*
Y99700D01*
G01Y102117D02*
X1113810Y102533D01*
X1114227Y102867D01*
X1114810Y103033D01*
X1115393Y102867D01*
X1115810Y102533D01*
X1116060Y102033D01*
Y99700D01*
G01X1117743Y103033D02*
Y100700D01*
X1118077Y100117D01*
X1118577Y99783D01*
X1119160Y99700D01*
X1119743Y99783D01*
X1120243Y100117D01*
X1120577Y100700D01*
G01Y99700D02*
Y103033D01*
G01X1123510Y100283D02*
X1123927Y99950D01*
X1124510Y99700D01*
X1125010D01*
X1125510Y99867D01*
X1125843Y100117D01*
X1126010Y100450D01*
X1125927Y100950D01*
X1125593Y101200D01*
X1124093Y101700D01*
X1123760Y102283D01*
X1123927Y102700D01*
X1124260Y102950D01*
X1124760Y103033D01*
X1125260Y102950D01*
X1125760Y102700D01*
G01X1130360Y104700D02*
Y99700D01*
G01X1129193Y103033D02*
X1131527D01*
G01X1140060Y99700D02*
Y104700D01*
G01Y102200D02*
X1140477Y102700D01*
X1140977Y102950D01*
X1141477Y103033D01*
X1142227Y102867D01*
X1142727Y102533D01*
X1143060Y101950D01*
Y101283D01*
X1142893Y100617D01*
X1142560Y100117D01*
X1141977Y99783D01*
X1141477Y99700D01*
X1140977Y99783D01*
X1140477Y100033D01*
X1140060Y100450D01*
G01X1145910Y101950D02*
X1148577D01*
X1148327Y102533D01*
X1147910Y102867D01*
X1147327Y103033D01*
X1146743Y102950D01*
X1146243Y102700D01*
X1145910Y102117D01*
X1145743Y101617D01*
Y101117D01*
X1145910Y100617D01*
X1146327Y100117D01*
X1146827Y99783D01*
X1147410Y99700D01*
X1147993Y99867D01*
X1148577Y100367D01*
G01X1156860Y99700D02*
Y104700D01*
G01Y102200D02*
X1157277Y102700D01*
X1157777Y102950D01*
X1158277Y103033D01*
X1159027Y102867D01*
X1159527Y102533D01*
X1159860Y101950D01*
Y101283D01*
X1159693Y100617D01*
X1159360Y100117D01*
X1158777Y99783D01*
X1158277Y99700D01*
X1157777Y99783D01*
X1157277Y100033D01*
X1156860Y100450D01*
G01X1162793Y99700D02*
Y103033D01*
G01Y102367D02*
X1163210Y102700D01*
X1163627Y102950D01*
X1164210Y103033D01*
X1164627Y102950D01*
X1165127Y102700D01*
G01X1169560Y99700D02*
X1169060Y99783D01*
X1168560Y100117D01*
X1168227Y100700D01*
X1168060Y101367D01*
X1168227Y102033D01*
X1168560Y102617D01*
X1169060Y102950D01*
X1169560Y103033D01*
X1170060Y102950D01*
X1170560Y102617D01*
X1170893Y102033D01*
X1170977Y101367D01*
X1170893Y100700D01*
X1170560Y100117D01*
X1170060Y99783D01*
X1169560Y99700D01*
G01X1173743D02*
Y104700D01*
G01X1176410Y103033D02*
X1173743Y101117D01*
G01X1174827Y101867D02*
X1176577Y99700D01*
G01X1179510Y101950D02*
X1182177D01*
X1181927Y102533D01*
X1181510Y102867D01*
X1180927Y103033D01*
X1180343Y102950D01*
X1179843Y102700D01*
X1179510Y102117D01*
X1179343Y101617D01*
Y101117D01*
X1179510Y100617D01*
X1179927Y100117D01*
X1180427Y99783D01*
X1181010Y99700D01*
X1181593Y99867D01*
X1182177Y100367D01*
G01X1184943Y99700D02*
Y103033D01*
G01Y102200D02*
X1185277Y102617D01*
X1185777Y102950D01*
X1186443Y103033D01*
X1187027Y102950D01*
X1187527Y102617D01*
X1187777Y102033D01*
Y99700D01*
G01X1197560D02*
Y104700D01*
G01X1204660Y99700D02*
Y103033D01*
G01Y102450D02*
X1204327Y102783D01*
X1203827Y102950D01*
X1203243Y103033D01*
X1202660Y102867D01*
X1202160Y102533D01*
X1201827Y102033D01*
X1201660Y101367D01*
X1201827Y100700D01*
X1202160Y100200D01*
X1202660Y99867D01*
X1203243Y99700D01*
X1203827Y99783D01*
X1204327Y100033D01*
X1204660Y100367D01*
G01X1207010Y98200D02*
X1207510Y98033D01*
X1208177Y98200D01*
X1208593Y98533D01*
X1208927Y98950D01*
X1209427Y100283D01*
X1210510Y103033D01*
G01X1207843D02*
X1209427Y100283D01*
G01X1213110Y101950D02*
X1215777D01*
X1215527Y102533D01*
X1215110Y102867D01*
X1214527Y103033D01*
X1213943Y102950D01*
X1213443Y102700D01*
X1213110Y102117D01*
X1212943Y101617D01*
Y101117D01*
X1213110Y100617D01*
X1213527Y100117D01*
X1214027Y99783D01*
X1214610Y99700D01*
X1215193Y99867D01*
X1215777Y100367D01*
G01X1218793Y99700D02*
Y103033D01*
G01Y102367D02*
X1219210Y102700D01*
X1219627Y102950D01*
X1220210Y103033D01*
X1220627Y102950D01*
X1221127Y102700D01*
G01X1089493Y104700D02*
Y99700D01*
X1092827D01*
G01X1095510Y103033D02*
X1098010Y99700D01*
G01Y103033D02*
X1095510Y99700D01*
G01X1102360Y99533D02*
X1102193Y99617D01*
Y99783D01*
X1102360Y99867D01*
X1102527Y99783D01*
Y99617D01*
X1102360Y99533D01*
G01Y101783D02*
X1102193Y101867D01*
Y102033D01*
X1102360Y102117D01*
X1102527Y102033D01*
Y101867D01*
X1102360Y101783D01*
G01X1111060Y99700D02*
Y103033D01*
G01Y102117D02*
X1111310Y102533D01*
X1111727Y102867D01*
X1112310Y103033D01*
X1112893Y102867D01*
X1113310Y102533D01*
X1113560Y102117D01*
Y99700D01*
G01Y102117D02*
X1113810Y102533D01*
X1114227Y102867D01*
X1114810Y103033D01*
X1115393Y102867D01*
X1115810Y102533D01*
X1116060Y102033D01*
Y99700D01*
G01X1117743Y103033D02*
Y100700D01*
X1118077Y100117D01*
X1118577Y99783D01*
X1119160Y99700D01*
X1119743Y99783D01*
X1120243Y100117D01*
X1120577Y100700D01*
G01Y99700D02*
Y103033D01*
G01X1123510Y100283D02*
X1123927Y99950D01*
X1124510Y99700D01*
X1125010D01*
X1125510Y99867D01*
X1125843Y100117D01*
X1126010Y100450D01*
X1125927Y100950D01*
X1125593Y101200D01*
X1124093Y101700D01*
X1123760Y102283D01*
X1123927Y102700D01*
X1124260Y102950D01*
X1124760Y103033D01*
X1125260Y102950D01*
X1125760Y102700D01*
G01X1130360Y104700D02*
Y99700D01*
G01X1129193Y103033D02*
X1131527D01*
G01X1140060Y99700D02*
Y104700D01*
G01Y102200D02*
X1140477Y102700D01*
X1140977Y102950D01*
X1141477Y103033D01*
X1142227Y102867D01*
X1142727Y102533D01*
X1143060Y101950D01*
Y101283D01*
X1142893Y100617D01*
X1142560Y100117D01*
X1141977Y99783D01*
X1141477Y99700D01*
X1140977Y99783D01*
X1140477Y100033D01*
X1140060Y100450D01*
G01X1145910Y101950D02*
X1148577D01*
X1148327Y102533D01*
X1147910Y102867D01*
X1147327Y103033D01*
X1146743Y102950D01*
X1146243Y102700D01*
X1145910Y102117D01*
X1145743Y101617D01*
Y101117D01*
X1145910Y100617D01*
X1146327Y100117D01*
X1146827Y99783D01*
X1147410Y99700D01*
X1147993Y99867D01*
X1148577Y100367D01*
G01X1156860Y99700D02*
Y104700D01*
G01Y102200D02*
X1157277Y102700D01*
X1157777Y102950D01*
X1158277Y103033D01*
X1159027Y102867D01*
X1159527Y102533D01*
X1159860Y101950D01*
Y101283D01*
X1159693Y100617D01*
X1159360Y100117D01*
X1158777Y99783D01*
X1158277Y99700D01*
X1157777Y99783D01*
X1157277Y100033D01*
X1156860Y100450D01*
G01X1162793Y99700D02*
Y103033D01*
G01Y102367D02*
X1163210Y102700D01*
X1163627Y102950D01*
X1164210Y103033D01*
X1164627Y102950D01*
X1165127Y102700D01*
G01X1169560Y99700D02*
X1169060Y99783D01*
X1168560Y100117D01*
X1168227Y100700D01*
X1168060Y101367D01*
X1168227Y102033D01*
X1168560Y102617D01*
X1169060Y102950D01*
X1169560Y103033D01*
X1170060Y102950D01*
X1170560Y102617D01*
X1170893Y102033D01*
X1170977Y101367D01*
X1170893Y100700D01*
X1170560Y100117D01*
X1170060Y99783D01*
X1169560Y99700D01*
G01X1173743D02*
Y104700D01*
G01X1176410Y103033D02*
X1173743Y101117D01*
G01X1174827Y101867D02*
X1176577Y99700D01*
G01X1179510Y101950D02*
X1182177D01*
X1181927Y102533D01*
X1181510Y102867D01*
X1180927Y103033D01*
X1180343Y102950D01*
X1179843Y102700D01*
X1179510Y102117D01*
X1179343Y101617D01*
Y101117D01*
X1179510Y100617D01*
X1179927Y100117D01*
X1180427Y99783D01*
X1181010Y99700D01*
X1181593Y99867D01*
X1182177Y100367D01*
G01X1184943Y99700D02*
Y103033D01*
G01Y102200D02*
X1185277Y102617D01*
X1185777Y102950D01*
X1186443Y103033D01*
X1187027Y102950D01*
X1187527Y102617D01*
X1187777Y102033D01*
Y99700D01*
G01X1197560D02*
Y104700D01*
G01X1204660Y99700D02*
Y103033D01*
G01Y102450D02*
X1204327Y102783D01*
X1203827Y102950D01*
X1203243Y103033D01*
X1202660Y102867D01*
X1202160Y102533D01*
X1201827Y102033D01*
X1201660Y101367D01*
X1201827Y100700D01*
X1202160Y100200D01*
X1202660Y99867D01*
X1203243Y99700D01*
X1203827Y99783D01*
X1204327Y100033D01*
X1204660Y100367D01*
G01X1207010Y98200D02*
X1207510Y98033D01*
X1208177Y98200D01*
X1208593Y98533D01*
X1208927Y98950D01*
X1209427Y100283D01*
X1210510Y103033D01*
G01X1207843D02*
X1209427Y100283D01*
G01X1213110Y101950D02*
X1215777D01*
X1215527Y102533D01*
X1215110Y102867D01*
X1214527Y103033D01*
X1213943Y102950D01*
X1213443Y102700D01*
X1213110Y102117D01*
X1212943Y101617D01*
Y101117D01*
X1213110Y100617D01*
X1213527Y100117D01*
X1214027Y99783D01*
X1214610Y99700D01*
X1215193Y99867D01*
X1215777Y100367D01*
G01X1218793Y99700D02*
Y103033D01*
G01Y102367D02*
X1219210Y102700D01*
X1219627Y102950D01*
X1220210Y103033D01*
X1220627Y102950D01*
X1221127Y102700D01*
G01X1087667Y124000D02*
Y129000D01*
X1089333D01*
X1090000Y128750D01*
X1090500Y128417D01*
X1090917Y127917D01*
X1091250Y127333D01*
X1091333Y126500D01*
X1091250Y125667D01*
X1090917Y125083D01*
X1090500Y124583D01*
X1090000Y124250D01*
X1089333Y124000D01*
X1087667D01*
G01X1093933D02*
Y127333D01*
G01Y126667D02*
X1094350Y127000D01*
X1094767Y127250D01*
X1095350Y127333D01*
X1095767Y127250D01*
X1096267Y127000D01*
G01X1100700Y127333D02*
Y124000D01*
G01Y128667D02*
X1100533Y128750D01*
Y128917D01*
X1100700Y129000D01*
X1100867Y128917D01*
Y128750D01*
X1100700Y128667D01*
G01X1106300Y124000D02*
Y129000D01*
G01X1111900Y124000D02*
Y129000D01*
G01X1121517Y124000D02*
Y129000D01*
X1124683D01*
G01X1123517Y126583D02*
X1121517D01*
G01X1127533Y124000D02*
Y127333D01*
G01Y126667D02*
X1127950Y127000D01*
X1128367Y127250D01*
X1128950Y127333D01*
X1129367Y127250D01*
X1129867Y127000D01*
G01X1134300Y124000D02*
X1133800Y124083D01*
X1133300Y124417D01*
X1132967Y125000D01*
X1132800Y125667D01*
X1132967Y126333D01*
X1133300Y126917D01*
X1133800Y127250D01*
X1134300Y127333D01*
X1134800Y127250D01*
X1135300Y126917D01*
X1135633Y126333D01*
X1135717Y125667D01*
X1135633Y125000D01*
X1135300Y124417D01*
X1134800Y124083D01*
X1134300Y124000D01*
G01X1137400D02*
Y127333D01*
G01Y126417D02*
X1137650Y126833D01*
X1138067Y127167D01*
X1138650Y127333D01*
X1139233Y127167D01*
X1139650Y126833D01*
X1139900Y126417D01*
Y124000D01*
G01Y126417D02*
X1140150Y126833D01*
X1140567Y127167D01*
X1141150Y127333D01*
X1141733Y127167D01*
X1142150Y126833D01*
X1142400Y126333D01*
Y124000D01*
G01X1167483Y122333D02*
X1166650Y123167D01*
X1166233Y124000D01*
Y127333D01*
X1166650Y128167D01*
X1167483Y129000D01*
G01X1174167Y126667D02*
X1174500Y126917D01*
X1174750Y127333D01*
X1174917Y127917D01*
X1174750Y128417D01*
X1174417Y128750D01*
X1173833Y129000D01*
X1171583D01*
Y124000D01*
X1174333D01*
X1174917Y124333D01*
X1175250Y124833D01*
X1175417Y125417D01*
X1175250Y126000D01*
X1174750Y126500D01*
X1174167Y126667D01*
X1171583D01*
G01X1179100Y124000D02*
X1178433Y124083D01*
X1177850Y124417D01*
X1177350Y124917D01*
X1177017Y125500D01*
X1176850Y126167D01*
Y126833D01*
X1177017Y127500D01*
X1177350Y128083D01*
X1177850Y128583D01*
X1178433Y128917D01*
X1179100Y129000D01*
X1179767Y128917D01*
X1180350Y128583D01*
X1180850Y128083D01*
X1181183Y127500D01*
X1181350Y126833D01*
Y126167D01*
X1181183Y125500D01*
X1180850Y124917D01*
X1180350Y124417D01*
X1179767Y124083D01*
X1179100Y124000D01*
G01X1184700Y129000D02*
Y124000D01*
G01X1182783Y129000D02*
X1186617D01*
G01X1190300D02*
Y124000D01*
G01X1188383Y129000D02*
X1192217D01*
G01X1195900Y124000D02*
X1195233Y124083D01*
X1194650Y124417D01*
X1194150Y124917D01*
X1193817Y125500D01*
X1193650Y126167D01*
Y126833D01*
X1193817Y127500D01*
X1194150Y128083D01*
X1194650Y128583D01*
X1195233Y128917D01*
X1195900Y129000D01*
X1196567Y128917D01*
X1197150Y128583D01*
X1197650Y128083D01*
X1197983Y127500D01*
X1198150Y126833D01*
Y126167D01*
X1197983Y125500D01*
X1197650Y124917D01*
X1197150Y124417D01*
X1196567Y124083D01*
X1195900Y124000D01*
G01X1199333D02*
Y129000D01*
X1201500Y124833D01*
X1203667Y129000D01*
Y124000D01*
G01X1207517Y122333D02*
X1208350Y123167D01*
X1208767Y124000D01*
Y127333D01*
X1208350Y128167D01*
X1207517Y129000D01*
G01X1218300D02*
Y124000D01*
G01X1217133Y127333D02*
X1219467D01*
G01X1223900Y124000D02*
X1223400Y124083D01*
X1222900Y124417D01*
X1222567Y125000D01*
X1222400Y125667D01*
X1222567Y126333D01*
X1222900Y126917D01*
X1223400Y127250D01*
X1223900Y127333D01*
X1224400Y127250D01*
X1224900Y126917D01*
X1225233Y126333D01*
X1225317Y125667D01*
X1225233Y125000D01*
X1224900Y124417D01*
X1224400Y124083D01*
X1223900Y124000D01*
G01X1233433Y129000D02*
Y124000D01*
X1236767D01*
G01X1239450Y127333D02*
X1241950Y124000D01*
G01Y127333D02*
X1239450Y124000D01*
G01X1136167Y157700D02*
Y162700D01*
X1137833D01*
X1138500Y162450D01*
X1139000Y162117D01*
X1139417Y161617D01*
X1139750Y161033D01*
X1139833Y160200D01*
X1139750Y159367D01*
X1139417Y158783D01*
X1139000Y158283D01*
X1138500Y157950D01*
X1137833Y157700D01*
X1136167D01*
G01X1142017Y161867D02*
X1142517Y162367D01*
X1143100Y162617D01*
X1143767Y162700D01*
X1144600Y162533D01*
X1145183Y162117D01*
X1145350Y161617D01*
X1145267Y161117D01*
X1144933Y160700D01*
X1143267Y159867D01*
X1142517Y159283D01*
X1142017Y158450D01*
X1141850Y157700D01*
X1145350D01*
G01X1088893Y117200D02*
Y112200D01*
X1092227D01*
G01X1094743D02*
Y115533D01*
G01Y114700D02*
X1095077Y115117D01*
X1095577Y115450D01*
X1096243Y115533D01*
X1096827Y115450D01*
X1097327Y115117D01*
X1097577Y114533D01*
Y112200D01*
G01X1101760Y112033D02*
X1101593Y112117D01*
Y112283D01*
X1101760Y112367D01*
X1101927Y112283D01*
Y112117D01*
X1101760Y112033D01*
G01Y114283D02*
X1101593Y114367D01*
Y114533D01*
X1101760Y114617D01*
X1101927Y114533D01*
Y114367D01*
X1101760Y114283D01*
G01X1114293Y115117D02*
X1113710Y115450D01*
X1113210Y115533D01*
X1112543Y115367D01*
X1112043Y115033D01*
X1111710Y114450D01*
X1111627Y113867D01*
X1111710Y113283D01*
X1112043Y112783D01*
X1112543Y112367D01*
X1113210Y112200D01*
X1113793Y112367D01*
X1114293Y112700D01*
G01X1120060Y112200D02*
Y115533D01*
G01Y114950D02*
X1119727Y115283D01*
X1119227Y115450D01*
X1118643Y115533D01*
X1118060Y115367D01*
X1117560Y115033D01*
X1117227Y114533D01*
X1117060Y113867D01*
X1117227Y113200D01*
X1117560Y112700D01*
X1118060Y112367D01*
X1118643Y112200D01*
X1119227Y112283D01*
X1119727Y112533D01*
X1120060Y112867D01*
G01X1122743Y112200D02*
Y115533D01*
G01Y114700D02*
X1123077Y115117D01*
X1123577Y115450D01*
X1124243Y115533D01*
X1124827Y115450D01*
X1125327Y115117D01*
X1125577Y114533D01*
Y112200D01*
G01X1129760Y115533D02*
X1130593Y116575D01*
Y117200D01*
X1129968D01*
Y116575D01*
X1130593D01*
G01X1135360Y117200D02*
Y112200D01*
G01X1134193Y115533D02*
X1136527D01*
G01X1145060Y112200D02*
Y117200D01*
G01Y114700D02*
X1145477Y115200D01*
X1145977Y115450D01*
X1146477Y115533D01*
X1147227Y115367D01*
X1147727Y115033D01*
X1148060Y114450D01*
Y113783D01*
X1147893Y113117D01*
X1147560Y112617D01*
X1146977Y112283D01*
X1146477Y112200D01*
X1145977Y112283D01*
X1145477Y112533D01*
X1145060Y112950D01*
G01X1150910Y114450D02*
X1153577D01*
X1153327Y115033D01*
X1152910Y115367D01*
X1152327Y115533D01*
X1151743Y115450D01*
X1151243Y115200D01*
X1150910Y114617D01*
X1150743Y114117D01*
Y113617D01*
X1150910Y113117D01*
X1151327Y112617D01*
X1151827Y112283D01*
X1152410Y112200D01*
X1152993Y112367D01*
X1153577Y112867D01*
G01X1161860Y112200D02*
Y117200D01*
G01Y114700D02*
X1162277Y115200D01*
X1162777Y115450D01*
X1163277Y115533D01*
X1164027Y115367D01*
X1164527Y115033D01*
X1164860Y114450D01*
Y113783D01*
X1164693Y113117D01*
X1164360Y112617D01*
X1163777Y112283D01*
X1163277Y112200D01*
X1162777Y112283D01*
X1162277Y112533D01*
X1161860Y112950D01*
G01X1167793Y112200D02*
Y115533D01*
G01Y114867D02*
X1168210Y115200D01*
X1168627Y115450D01*
X1169210Y115533D01*
X1169627Y115450D01*
X1170127Y115200D01*
G01X1174560Y112200D02*
X1174060Y112283D01*
X1173560Y112617D01*
X1173227Y113200D01*
X1173060Y113867D01*
X1173227Y114533D01*
X1173560Y115117D01*
X1174060Y115450D01*
X1174560Y115533D01*
X1175060Y115450D01*
X1175560Y115117D01*
X1175893Y114533D01*
X1175977Y113867D01*
X1175893Y113200D01*
X1175560Y112617D01*
X1175060Y112283D01*
X1174560Y112200D01*
G01X1178743D02*
Y117200D01*
G01X1181410Y115533D02*
X1178743Y113617D01*
G01X1179827Y114367D02*
X1181577Y112200D01*
G01X1184510Y114450D02*
X1187177D01*
X1186927Y115033D01*
X1186510Y115367D01*
X1185927Y115533D01*
X1185343Y115450D01*
X1184843Y115200D01*
X1184510Y114617D01*
X1184343Y114117D01*
Y113617D01*
X1184510Y113117D01*
X1184927Y112617D01*
X1185427Y112283D01*
X1186010Y112200D01*
X1186593Y112367D01*
X1187177Y112867D01*
G01X1189943Y112200D02*
Y115533D01*
G01Y114700D02*
X1190277Y115117D01*
X1190777Y115450D01*
X1191443Y115533D01*
X1192027Y115450D01*
X1192527Y115117D01*
X1192777Y114533D01*
Y112200D01*
G01X1202560D02*
Y117200D01*
G01X1209660Y112200D02*
Y115533D01*
G01Y114950D02*
X1209327Y115283D01*
X1208827Y115450D01*
X1208243Y115533D01*
X1207660Y115367D01*
X1207160Y115033D01*
X1206827Y114533D01*
X1206660Y113867D01*
X1206827Y113200D01*
X1207160Y112700D01*
X1207660Y112367D01*
X1208243Y112200D01*
X1208827Y112283D01*
X1209327Y112533D01*
X1209660Y112867D01*
G01X1212010Y110700D02*
X1212510Y110533D01*
X1213177Y110700D01*
X1213593Y111033D01*
X1213927Y111450D01*
X1214427Y112783D01*
X1215510Y115533D01*
G01X1212843D02*
X1214427Y112783D01*
G01X1218110Y114450D02*
X1220777D01*
X1220527Y115033D01*
X1220110Y115367D01*
X1219527Y115533D01*
X1218943Y115450D01*
X1218443Y115200D01*
X1218110Y114617D01*
X1217943Y114117D01*
Y113617D01*
X1218110Y113117D01*
X1218527Y112617D01*
X1219027Y112283D01*
X1219610Y112200D01*
X1220193Y112367D01*
X1220777Y112867D01*
G01X1223793Y112200D02*
Y115533D01*
G01Y114867D02*
X1224210Y115200D01*
X1224627Y115450D01*
X1225210Y115533D01*
X1225627Y115450D01*
X1226127Y115200D01*
G01X1087667Y124000D02*
Y129000D01*
X1089333D01*
X1090000Y128750D01*
X1090500Y128417D01*
X1090917Y127917D01*
X1091250Y127333D01*
X1091333Y126500D01*
X1091250Y125667D01*
X1090917Y125083D01*
X1090500Y124583D01*
X1090000Y124250D01*
X1089333Y124000D01*
X1087667D01*
G01X1093933D02*
Y127333D01*
G01Y126667D02*
X1094350Y127000D01*
X1094767Y127250D01*
X1095350Y127333D01*
X1095767Y127250D01*
X1096267Y127000D01*
G01X1100700Y127333D02*
Y124000D01*
G01Y128667D02*
X1100533Y128750D01*
Y128917D01*
X1100700Y129000D01*
X1100867Y128917D01*
Y128750D01*
X1100700Y128667D01*
G01X1106300Y124000D02*
Y129000D01*
G01X1111900Y124000D02*
Y129000D01*
G01X1121517Y124000D02*
Y129000D01*
X1124683D01*
G01X1123517Y126583D02*
X1121517D01*
G01X1127533Y124000D02*
Y127333D01*
G01Y126667D02*
X1127950Y127000D01*
X1128367Y127250D01*
X1128950Y127333D01*
X1129367Y127250D01*
X1129867Y127000D01*
G01X1134300Y124000D02*
X1133800Y124083D01*
X1133300Y124417D01*
X1132967Y125000D01*
X1132800Y125667D01*
X1132967Y126333D01*
X1133300Y126917D01*
X1133800Y127250D01*
X1134300Y127333D01*
X1134800Y127250D01*
X1135300Y126917D01*
X1135633Y126333D01*
X1135717Y125667D01*
X1135633Y125000D01*
X1135300Y124417D01*
X1134800Y124083D01*
X1134300Y124000D01*
G01X1137400D02*
Y127333D01*
G01Y126417D02*
X1137650Y126833D01*
X1138067Y127167D01*
X1138650Y127333D01*
X1139233Y127167D01*
X1139650Y126833D01*
X1139900Y126417D01*
Y124000D01*
G01Y126417D02*
X1140150Y126833D01*
X1140567Y127167D01*
X1141150Y127333D01*
X1141733Y127167D01*
X1142150Y126833D01*
X1142400Y126333D01*
Y124000D01*
G01X1167483Y122333D02*
X1166650Y123167D01*
X1166233Y124000D01*
Y127333D01*
X1166650Y128167D01*
X1167483Y129000D01*
G01X1174167Y126667D02*
X1174500Y126917D01*
X1174750Y127333D01*
X1174917Y127917D01*
X1174750Y128417D01*
X1174417Y128750D01*
X1173833Y129000D01*
X1171583D01*
Y124000D01*
X1174333D01*
X1174917Y124333D01*
X1175250Y124833D01*
X1175417Y125417D01*
X1175250Y126000D01*
X1174750Y126500D01*
X1174167Y126667D01*
X1171583D01*
G01X1179100Y124000D02*
X1178433Y124083D01*
X1177850Y124417D01*
X1177350Y124917D01*
X1177017Y125500D01*
X1176850Y126167D01*
Y126833D01*
X1177017Y127500D01*
X1177350Y128083D01*
X1177850Y128583D01*
X1178433Y128917D01*
X1179100Y129000D01*
X1179767Y128917D01*
X1180350Y128583D01*
X1180850Y128083D01*
X1181183Y127500D01*
X1181350Y126833D01*
Y126167D01*
X1181183Y125500D01*
X1180850Y124917D01*
X1180350Y124417D01*
X1179767Y124083D01*
X1179100Y124000D01*
G01X1184700Y129000D02*
Y124000D01*
G01X1182783Y129000D02*
X1186617D01*
G01X1190300D02*
Y124000D01*
G01X1188383Y129000D02*
X1192217D01*
G01X1195900Y124000D02*
X1195233Y124083D01*
X1194650Y124417D01*
X1194150Y124917D01*
X1193817Y125500D01*
X1193650Y126167D01*
Y126833D01*
X1193817Y127500D01*
X1194150Y128083D01*
X1194650Y128583D01*
X1195233Y128917D01*
X1195900Y129000D01*
X1196567Y128917D01*
X1197150Y128583D01*
X1197650Y128083D01*
X1197983Y127500D01*
X1198150Y126833D01*
Y126167D01*
X1197983Y125500D01*
X1197650Y124917D01*
X1197150Y124417D01*
X1196567Y124083D01*
X1195900Y124000D01*
G01X1199333D02*
Y129000D01*
X1201500Y124833D01*
X1203667Y129000D01*
Y124000D01*
G01X1207517Y122333D02*
X1208350Y123167D01*
X1208767Y124000D01*
Y127333D01*
X1208350Y128167D01*
X1207517Y129000D01*
G01X1218300D02*
Y124000D01*
G01X1217133Y127333D02*
X1219467D01*
G01X1223900Y124000D02*
X1223400Y124083D01*
X1222900Y124417D01*
X1222567Y125000D01*
X1222400Y125667D01*
X1222567Y126333D01*
X1222900Y126917D01*
X1223400Y127250D01*
X1223900Y127333D01*
X1224400Y127250D01*
X1224900Y126917D01*
X1225233Y126333D01*
X1225317Y125667D01*
X1225233Y125000D01*
X1224900Y124417D01*
X1224400Y124083D01*
X1223900Y124000D01*
G01X1233433Y129000D02*
Y124000D01*
X1236767D01*
G01X1239450Y127333D02*
X1241950Y124000D01*
G01Y127333D02*
X1239450Y124000D01*
G01X1136167Y157700D02*
Y162700D01*
X1137833D01*
X1138500Y162450D01*
X1139000Y162117D01*
X1139417Y161617D01*
X1139750Y161033D01*
X1139833Y160200D01*
X1139750Y159367D01*
X1139417Y158783D01*
X1139000Y158283D01*
X1138500Y157950D01*
X1137833Y157700D01*
X1136167D01*
G01X1142017Y161867D02*
X1142517Y162367D01*
X1143100Y162617D01*
X1143767Y162700D01*
X1144600Y162533D01*
X1145183Y162117D01*
X1145350Y161617D01*
X1145267Y161117D01*
X1144933Y160700D01*
X1143267Y159867D01*
X1142517Y159283D01*
X1142017Y158450D01*
X1141850Y157700D01*
X1145350D01*
G01X1088893Y117200D02*
Y112200D01*
X1092227D01*
G01X1094743D02*
Y115533D01*
G01Y114700D02*
X1095077Y115117D01*
X1095577Y115450D01*
X1096243Y115533D01*
X1096827Y115450D01*
X1097327Y115117D01*
X1097577Y114533D01*
Y112200D01*
G01X1101760Y112033D02*
X1101593Y112117D01*
Y112283D01*
X1101760Y112367D01*
X1101927Y112283D01*
Y112117D01*
X1101760Y112033D01*
G01Y114283D02*
X1101593Y114367D01*
Y114533D01*
X1101760Y114617D01*
X1101927Y114533D01*
Y114367D01*
X1101760Y114283D01*
G01X1114293Y115117D02*
X1113710Y115450D01*
X1113210Y115533D01*
X1112543Y115367D01*
X1112043Y115033D01*
X1111710Y114450D01*
X1111627Y113867D01*
X1111710Y113283D01*
X1112043Y112783D01*
X1112543Y112367D01*
X1113210Y112200D01*
X1113793Y112367D01*
X1114293Y112700D01*
G01X1120060Y112200D02*
Y115533D01*
G01Y114950D02*
X1119727Y115283D01*
X1119227Y115450D01*
X1118643Y115533D01*
X1118060Y115367D01*
X1117560Y115033D01*
X1117227Y114533D01*
X1117060Y113867D01*
X1117227Y113200D01*
X1117560Y112700D01*
X1118060Y112367D01*
X1118643Y112200D01*
X1119227Y112283D01*
X1119727Y112533D01*
X1120060Y112867D01*
G01X1122743Y112200D02*
Y115533D01*
G01Y114700D02*
X1123077Y115117D01*
X1123577Y115450D01*
X1124243Y115533D01*
X1124827Y115450D01*
X1125327Y115117D01*
X1125577Y114533D01*
Y112200D01*
G01X1129760Y115533D02*
X1130593Y116575D01*
Y117200D01*
X1129968D01*
Y116575D01*
X1130593D01*
G01X1135360Y117200D02*
Y112200D01*
G01X1134193Y115533D02*
X1136527D01*
G01X1145060Y112200D02*
Y117200D01*
G01Y114700D02*
X1145477Y115200D01*
X1145977Y115450D01*
X1146477Y115533D01*
X1147227Y115367D01*
X1147727Y115033D01*
X1148060Y114450D01*
Y113783D01*
X1147893Y113117D01*
X1147560Y112617D01*
X1146977Y112283D01*
X1146477Y112200D01*
X1145977Y112283D01*
X1145477Y112533D01*
X1145060Y112950D01*
G01X1150910Y114450D02*
X1153577D01*
X1153327Y115033D01*
X1152910Y115367D01*
X1152327Y115533D01*
X1151743Y115450D01*
X1151243Y115200D01*
X1150910Y114617D01*
X1150743Y114117D01*
Y113617D01*
X1150910Y113117D01*
X1151327Y112617D01*
X1151827Y112283D01*
X1152410Y112200D01*
X1152993Y112367D01*
X1153577Y112867D01*
G01X1161860Y112200D02*
Y117200D01*
G01Y114700D02*
X1162277Y115200D01*
X1162777Y115450D01*
X1163277Y115533D01*
X1164027Y115367D01*
X1164527Y115033D01*
X1164860Y114450D01*
Y113783D01*
X1164693Y113117D01*
X1164360Y112617D01*
X1163777Y112283D01*
X1163277Y112200D01*
X1162777Y112283D01*
X1162277Y112533D01*
X1161860Y112950D01*
G01X1167793Y112200D02*
Y115533D01*
G01Y114867D02*
X1168210Y115200D01*
X1168627Y115450D01*
X1169210Y115533D01*
X1169627Y115450D01*
X1170127Y115200D01*
G01X1174560Y112200D02*
X1174060Y112283D01*
X1173560Y112617D01*
X1173227Y113200D01*
X1173060Y113867D01*
X1173227Y114533D01*
X1173560Y115117D01*
X1174060Y115450D01*
X1174560Y115533D01*
X1175060Y115450D01*
X1175560Y115117D01*
X1175893Y114533D01*
X1175977Y113867D01*
X1175893Y113200D01*
X1175560Y112617D01*
X1175060Y112283D01*
X1174560Y112200D01*
G01X1178743D02*
Y117200D01*
G01X1181410Y115533D02*
X1178743Y113617D01*
G01X1179827Y114367D02*
X1181577Y112200D01*
G01X1184510Y114450D02*
X1187177D01*
X1186927Y115033D01*
X1186510Y115367D01*
X1185927Y115533D01*
X1185343Y115450D01*
X1184843Y115200D01*
X1184510Y114617D01*
X1184343Y114117D01*
Y113617D01*
X1184510Y113117D01*
X1184927Y112617D01*
X1185427Y112283D01*
X1186010Y112200D01*
X1186593Y112367D01*
X1187177Y112867D01*
G01X1189943Y112200D02*
Y115533D01*
G01Y114700D02*
X1190277Y115117D01*
X1190777Y115450D01*
X1191443Y115533D01*
X1192027Y115450D01*
X1192527Y115117D01*
X1192777Y114533D01*
Y112200D01*
G01X1202560D02*
Y117200D01*
G01X1209660Y112200D02*
Y115533D01*
G01Y114950D02*
X1209327Y115283D01*
X1208827Y115450D01*
X1208243Y115533D01*
X1207660Y115367D01*
X1207160Y115033D01*
X1206827Y114533D01*
X1206660Y113867D01*
X1206827Y113200D01*
X1207160Y112700D01*
X1207660Y112367D01*
X1208243Y112200D01*
X1208827Y112283D01*
X1209327Y112533D01*
X1209660Y112867D01*
G01X1212010Y110700D02*
X1212510Y110533D01*
X1213177Y110700D01*
X1213593Y111033D01*
X1213927Y111450D01*
X1214427Y112783D01*
X1215510Y115533D01*
G01X1212843D02*
X1214427Y112783D01*
G01X1218110Y114450D02*
X1220777D01*
X1220527Y115033D01*
X1220110Y115367D01*
X1219527Y115533D01*
X1218943Y115450D01*
X1218443Y115200D01*
X1218110Y114617D01*
X1217943Y114117D01*
Y113617D01*
X1218110Y113117D01*
X1218527Y112617D01*
X1219027Y112283D01*
X1219610Y112200D01*
X1220193Y112367D01*
X1220777Y112867D01*
G01X1223793Y112200D02*
Y115533D01*
G01Y114867D02*
X1224210Y115200D01*
X1224627Y115450D01*
X1225210Y115533D01*
X1225627Y115450D01*
X1226127Y115200D01*
G01X1135167Y315700D02*
Y320700D01*
X1136833D01*
X1137500Y320450D01*
X1138000Y320117D01*
X1138417Y319617D01*
X1138750Y319033D01*
X1138833Y318200D01*
X1138750Y317367D01*
X1138417Y316783D01*
X1138000Y316283D01*
X1137500Y315950D01*
X1136833Y315700D01*
X1135167D01*
G01X1142600D02*
Y320700D01*
X1141600Y319700D01*
G01Y315700D02*
X1143600D01*
G01X1135167D02*
Y320700D01*
X1136833D01*
X1137500Y320450D01*
X1138000Y320117D01*
X1138417Y319617D01*
X1138750Y319033D01*
X1138833Y318200D01*
X1138750Y317367D01*
X1138417Y316783D01*
X1138000Y316283D01*
X1137500Y315950D01*
X1136833Y315700D01*
X1135167D01*
G01X1142600D02*
Y320700D01*
X1141600Y319700D01*
G01Y315700D02*
X1143600D01*
G01X1136833Y619917D02*
X1136250Y620250D01*
X1135750Y620333D01*
X1135083Y620167D01*
X1134583Y619833D01*
X1134250Y619250D01*
X1134167Y618667D01*
X1134250Y618083D01*
X1134583Y617583D01*
X1135083Y617167D01*
X1135750Y617000D01*
X1136333Y617167D01*
X1136833Y617500D01*
G01X1141100Y617000D02*
X1140600Y617083D01*
X1140100Y617417D01*
X1139767Y618000D01*
X1139600Y618667D01*
X1139767Y619333D01*
X1140100Y619917D01*
X1140600Y620250D01*
X1141100Y620333D01*
X1141600Y620250D01*
X1142100Y619917D01*
X1142433Y619333D01*
X1142517Y618667D01*
X1142433Y618000D01*
X1142100Y617417D01*
X1141600Y617083D01*
X1141100Y617000D01*
G01X1145200Y615333D02*
Y620333D01*
G01Y619583D02*
X1145617Y620000D01*
X1146033Y620250D01*
X1146700Y620333D01*
X1147283Y620250D01*
X1147867Y619833D01*
X1148117Y619250D01*
X1148200Y618667D01*
X1148117Y618083D01*
X1147867Y617500D01*
X1147367Y617167D01*
X1146700Y617000D01*
X1146117Y617083D01*
X1145533Y617333D01*
X1145200Y617667D01*
G01X1150800Y615333D02*
Y620333D01*
G01Y619583D02*
X1151217Y620000D01*
X1151633Y620250D01*
X1152300Y620333D01*
X1152883Y620250D01*
X1153467Y619833D01*
X1153717Y619250D01*
X1153800Y618667D01*
X1153717Y618083D01*
X1153467Y617500D01*
X1152967Y617167D01*
X1152300Y617000D01*
X1151717Y617083D01*
X1151133Y617333D01*
X1150800Y617667D01*
G01X1156650Y619250D02*
X1159317D01*
X1159067Y619833D01*
X1158650Y620167D01*
X1158067Y620333D01*
X1157483Y620250D01*
X1156983Y620000D01*
X1156650Y619417D01*
X1156483Y618917D01*
Y618417D01*
X1156650Y617917D01*
X1157067Y617417D01*
X1157567Y617083D01*
X1158150Y617000D01*
X1158733Y617167D01*
X1159317Y617667D01*
G01X1162333Y617000D02*
Y620333D01*
G01Y619667D02*
X1162750Y620000D01*
X1163167Y620250D01*
X1163750Y620333D01*
X1164167Y620250D01*
X1164667Y620000D01*
G01X1109833Y590500D02*
Y595500D01*
X1111833D01*
X1112500Y595250D01*
X1113000Y594667D01*
X1113167Y594000D01*
X1113000Y593333D01*
X1112583Y592833D01*
X1111833Y592583D01*
X1109833D01*
G01X1117100Y590500D02*
Y595500D01*
G01X1121283Y593833D02*
Y591500D01*
X1121617Y590917D01*
X1122117Y590583D01*
X1122700Y590500D01*
X1123283Y590583D01*
X1123783Y590917D01*
X1124117Y591500D01*
G01Y590500D02*
Y593833D01*
G01X1127133Y589250D02*
X1127717Y588917D01*
X1128383Y588833D01*
X1128967Y588917D01*
X1129467Y589333D01*
X1129800Y589917D01*
Y593833D01*
G01Y593167D02*
X1129467Y593500D01*
X1128967Y593750D01*
X1128383Y593833D01*
X1127717Y593667D01*
X1127300Y593333D01*
X1126967Y592750D01*
X1126800Y592167D01*
X1126883Y591667D01*
X1127217Y591083D01*
X1127717Y590667D01*
X1128383Y590500D01*
X1128883Y590583D01*
X1129467Y590917D01*
X1129800Y591250D01*
G01X1132733Y589250D02*
X1133317Y588917D01*
X1133983Y588833D01*
X1134567Y588917D01*
X1135067Y589333D01*
X1135400Y589917D01*
Y593833D01*
G01Y593167D02*
X1135067Y593500D01*
X1134567Y593750D01*
X1133983Y593833D01*
X1133317Y593667D01*
X1132900Y593333D01*
X1132567Y592750D01*
X1132400Y592167D01*
X1132483Y591667D01*
X1132817Y591083D01*
X1133317Y590667D01*
X1133983Y590500D01*
X1134483Y590583D01*
X1135067Y590917D01*
X1135400Y591250D01*
G01X1139500Y593833D02*
Y590500D01*
G01Y595167D02*
X1139333Y595250D01*
Y595417D01*
X1139500Y595500D01*
X1139667Y595417D01*
Y595250D01*
X1139500Y595167D01*
G01X1143683Y590500D02*
Y593833D01*
G01Y593000D02*
X1144017Y593417D01*
X1144517Y593750D01*
X1145183Y593833D01*
X1145767Y593750D01*
X1146267Y593417D01*
X1146517Y592833D01*
Y590500D01*
G01X1149533Y589250D02*
X1150117Y588917D01*
X1150783Y588833D01*
X1151367Y588917D01*
X1151867Y589333D01*
X1152200Y589917D01*
Y593833D01*
G01Y593167D02*
X1151867Y593500D01*
X1151367Y593750D01*
X1150783Y593833D01*
X1150117Y593667D01*
X1149700Y593333D01*
X1149367Y592750D01*
X1149200Y592167D01*
X1149283Y591667D01*
X1149617Y591083D01*
X1150117Y590667D01*
X1150783Y590500D01*
X1151283Y590583D01*
X1151867Y590917D01*
X1152200Y591250D01*
G01X1163233Y593417D02*
X1162650Y593750D01*
X1162150Y593833D01*
X1161483Y593667D01*
X1160983Y593333D01*
X1160650Y592750D01*
X1160567Y592167D01*
X1160650Y591583D01*
X1160983Y591083D01*
X1161483Y590667D01*
X1162150Y590500D01*
X1162733Y590667D01*
X1163233Y591000D01*
G01X1166333Y590500D02*
Y593833D01*
G01Y593167D02*
X1166750Y593500D01*
X1167167Y593750D01*
X1167750Y593833D01*
X1168167Y593750D01*
X1168667Y593500D01*
G01X1173100Y593833D02*
Y590500D01*
G01Y595167D02*
X1172933Y595250D01*
Y595417D01*
X1173100Y595500D01*
X1173267Y595417D01*
Y595250D01*
X1173100Y595167D01*
G01X1178700Y595500D02*
Y590500D01*
G01X1177533Y593833D02*
X1179867D01*
G01X1183050Y592750D02*
X1185717D01*
X1185467Y593333D01*
X1185050Y593667D01*
X1184467Y593833D01*
X1183883Y593750D01*
X1183383Y593500D01*
X1183050Y592917D01*
X1182883Y592417D01*
Y591917D01*
X1183050Y591417D01*
X1183467Y590917D01*
X1183967Y590583D01*
X1184550Y590500D01*
X1185133Y590667D01*
X1185717Y591167D01*
G01X1188733Y590500D02*
Y593833D01*
G01Y593167D02*
X1189150Y593500D01*
X1189567Y593750D01*
X1190150Y593833D01*
X1190567Y593750D01*
X1191067Y593500D01*
G01X1195500Y593833D02*
Y590500D01*
G01Y595167D02*
X1195333Y595250D01*
Y595417D01*
X1195500Y595500D01*
X1195667Y595417D01*
Y595250D01*
X1195500Y595167D01*
G01X1202600Y590500D02*
Y593833D01*
G01Y593250D02*
X1202267Y593583D01*
X1201767Y593750D01*
X1201183Y593833D01*
X1200600Y593667D01*
X1200100Y593333D01*
X1199767Y592833D01*
X1199600Y592167D01*
X1199767Y591500D01*
X1200100Y591000D01*
X1200600Y590667D01*
X1201183Y590500D01*
X1201767Y590583D01*
X1202267Y590833D01*
X1202600Y591167D01*
G01X1136833Y619917D02*
X1136250Y620250D01*
X1135750Y620333D01*
X1135083Y620167D01*
X1134583Y619833D01*
X1134250Y619250D01*
X1134167Y618667D01*
X1134250Y618083D01*
X1134583Y617583D01*
X1135083Y617167D01*
X1135750Y617000D01*
X1136333Y617167D01*
X1136833Y617500D01*
G01X1141100Y617000D02*
X1140600Y617083D01*
X1140100Y617417D01*
X1139767Y618000D01*
X1139600Y618667D01*
X1139767Y619333D01*
X1140100Y619917D01*
X1140600Y620250D01*
X1141100Y620333D01*
X1141600Y620250D01*
X1142100Y619917D01*
X1142433Y619333D01*
X1142517Y618667D01*
X1142433Y618000D01*
X1142100Y617417D01*
X1141600Y617083D01*
X1141100Y617000D01*
G01X1145200Y615333D02*
Y620333D01*
G01Y619583D02*
X1145617Y620000D01*
X1146033Y620250D01*
X1146700Y620333D01*
X1147283Y620250D01*
X1147867Y619833D01*
X1148117Y619250D01*
X1148200Y618667D01*
X1148117Y618083D01*
X1147867Y617500D01*
X1147367Y617167D01*
X1146700Y617000D01*
X1146117Y617083D01*
X1145533Y617333D01*
X1145200Y617667D01*
G01X1150800Y615333D02*
Y620333D01*
G01Y619583D02*
X1151217Y620000D01*
X1151633Y620250D01*
X1152300Y620333D01*
X1152883Y620250D01*
X1153467Y619833D01*
X1153717Y619250D01*
X1153800Y618667D01*
X1153717Y618083D01*
X1153467Y617500D01*
X1152967Y617167D01*
X1152300Y617000D01*
X1151717Y617083D01*
X1151133Y617333D01*
X1150800Y617667D01*
G01X1156650Y619250D02*
X1159317D01*
X1159067Y619833D01*
X1158650Y620167D01*
X1158067Y620333D01*
X1157483Y620250D01*
X1156983Y620000D01*
X1156650Y619417D01*
X1156483Y618917D01*
Y618417D01*
X1156650Y617917D01*
X1157067Y617417D01*
X1157567Y617083D01*
X1158150Y617000D01*
X1158733Y617167D01*
X1159317Y617667D01*
G01X1162333Y617000D02*
Y620333D01*
G01Y619667D02*
X1162750Y620000D01*
X1163167Y620250D01*
X1163750Y620333D01*
X1164167Y620250D01*
X1164667Y620000D01*
G01X1109833Y590500D02*
Y595500D01*
X1111833D01*
X1112500Y595250D01*
X1113000Y594667D01*
X1113167Y594000D01*
X1113000Y593333D01*
X1112583Y592833D01*
X1111833Y592583D01*
X1109833D01*
G01X1117100Y590500D02*
Y595500D01*
G01X1121283Y593833D02*
Y591500D01*
X1121617Y590917D01*
X1122117Y590583D01*
X1122700Y590500D01*
X1123283Y590583D01*
X1123783Y590917D01*
X1124117Y591500D01*
G01Y590500D02*
Y593833D01*
G01X1127133Y589250D02*
X1127717Y588917D01*
X1128383Y588833D01*
X1128967Y588917D01*
X1129467Y589333D01*
X1129800Y589917D01*
Y593833D01*
G01Y593167D02*
X1129467Y593500D01*
X1128967Y593750D01*
X1128383Y593833D01*
X1127717Y593667D01*
X1127300Y593333D01*
X1126967Y592750D01*
X1126800Y592167D01*
X1126883Y591667D01*
X1127217Y591083D01*
X1127717Y590667D01*
X1128383Y590500D01*
X1128883Y590583D01*
X1129467Y590917D01*
X1129800Y591250D01*
G01X1132733Y589250D02*
X1133317Y588917D01*
X1133983Y588833D01*
X1134567Y588917D01*
X1135067Y589333D01*
X1135400Y589917D01*
Y593833D01*
G01Y593167D02*
X1135067Y593500D01*
X1134567Y593750D01*
X1133983Y593833D01*
X1133317Y593667D01*
X1132900Y593333D01*
X1132567Y592750D01*
X1132400Y592167D01*
X1132483Y591667D01*
X1132817Y591083D01*
X1133317Y590667D01*
X1133983Y590500D01*
X1134483Y590583D01*
X1135067Y590917D01*
X1135400Y591250D01*
G01X1139500Y593833D02*
Y590500D01*
G01Y595167D02*
X1139333Y595250D01*
Y595417D01*
X1139500Y595500D01*
X1139667Y595417D01*
Y595250D01*
X1139500Y595167D01*
G01X1143683Y590500D02*
Y593833D01*
G01Y593000D02*
X1144017Y593417D01*
X1144517Y593750D01*
X1145183Y593833D01*
X1145767Y593750D01*
X1146267Y593417D01*
X1146517Y592833D01*
Y590500D01*
G01X1149533Y589250D02*
X1150117Y588917D01*
X1150783Y588833D01*
X1151367Y588917D01*
X1151867Y589333D01*
X1152200Y589917D01*
Y593833D01*
G01Y593167D02*
X1151867Y593500D01*
X1151367Y593750D01*
X1150783Y593833D01*
X1150117Y593667D01*
X1149700Y593333D01*
X1149367Y592750D01*
X1149200Y592167D01*
X1149283Y591667D01*
X1149617Y591083D01*
X1150117Y590667D01*
X1150783Y590500D01*
X1151283Y590583D01*
X1151867Y590917D01*
X1152200Y591250D01*
G01X1163233Y593417D02*
X1162650Y593750D01*
X1162150Y593833D01*
X1161483Y593667D01*
X1160983Y593333D01*
X1160650Y592750D01*
X1160567Y592167D01*
X1160650Y591583D01*
X1160983Y591083D01*
X1161483Y590667D01*
X1162150Y590500D01*
X1162733Y590667D01*
X1163233Y591000D01*
G01X1166333Y590500D02*
Y593833D01*
G01Y593167D02*
X1166750Y593500D01*
X1167167Y593750D01*
X1167750Y593833D01*
X1168167Y593750D01*
X1168667Y593500D01*
G01X1173100Y593833D02*
Y590500D01*
G01Y595167D02*
X1172933Y595250D01*
Y595417D01*
X1173100Y595500D01*
X1173267Y595417D01*
Y595250D01*
X1173100Y595167D01*
G01X1178700Y595500D02*
Y590500D01*
G01X1177533Y593833D02*
X1179867D01*
G01X1183050Y592750D02*
X1185717D01*
X1185467Y593333D01*
X1185050Y593667D01*
X1184467Y593833D01*
X1183883Y593750D01*
X1183383Y593500D01*
X1183050Y592917D01*
X1182883Y592417D01*
Y591917D01*
X1183050Y591417D01*
X1183467Y590917D01*
X1183967Y590583D01*
X1184550Y590500D01*
X1185133Y590667D01*
X1185717Y591167D01*
G01X1188733Y590500D02*
Y593833D01*
G01Y593167D02*
X1189150Y593500D01*
X1189567Y593750D01*
X1190150Y593833D01*
X1190567Y593750D01*
X1191067Y593500D01*
G01X1195500Y593833D02*
Y590500D01*
G01Y595167D02*
X1195333Y595250D01*
Y595417D01*
X1195500Y595500D01*
X1195667Y595417D01*
Y595250D01*
X1195500Y595167D01*
G01X1202600Y590500D02*
Y593833D01*
G01Y593250D02*
X1202267Y593583D01*
X1201767Y593750D01*
X1201183Y593833D01*
X1200600Y593667D01*
X1200100Y593333D01*
X1199767Y592833D01*
X1199600Y592167D01*
X1199767Y591500D01*
X1200100Y591000D01*
X1200600Y590667D01*
X1201183Y590500D01*
X1201767Y590583D01*
X1202267Y590833D01*
X1202600Y591167D01*
G01X1106417Y735500D02*
X1108500Y730500D01*
X1110583Y735500D01*
G01X1113100D02*
X1115100D01*
G01X1114100D02*
Y730500D01*
G01X1113100D02*
X1115100D01*
G01X1118033D02*
Y735500D01*
X1120033D01*
X1120700Y735250D01*
X1121200Y734667D01*
X1121367Y734000D01*
X1121200Y733333D01*
X1120783Y732833D01*
X1120033Y732583D01*
X1118033D01*
G01X1106417Y735500D02*
X1108500Y730500D01*
X1110583Y735500D01*
G01X1113100D02*
X1115100D01*
G01X1114100D02*
Y730500D01*
G01X1113100D02*
X1115100D01*
G01X1118033D02*
Y735500D01*
X1120033D01*
X1120700Y735250D01*
X1121200Y734667D01*
X1121367Y734000D01*
X1121200Y733333D01*
X1120783Y732833D01*
X1120033Y732583D01*
X1118033D01*
G01X1184667Y150367D02*
X1185000Y150617D01*
X1185250Y151033D01*
X1185417Y151617D01*
X1185250Y152117D01*
X1184917Y152450D01*
X1184333Y152700D01*
X1182083D01*
Y147700D01*
X1184833D01*
X1185417Y148033D01*
X1185750Y148533D01*
X1185917Y149117D01*
X1185750Y149700D01*
X1185250Y150200D01*
X1184667Y150367D01*
X1182083D01*
G01X1187517Y147700D02*
X1189600Y152700D01*
X1191683Y147700D01*
G01X1190933Y149450D02*
X1188267D01*
G01X1197033Y152283D02*
X1196533Y152533D01*
X1195950Y152700D01*
X1195283D01*
X1194533Y152450D01*
X1193950Y152033D01*
X1193533Y151533D01*
X1193200Y150700D01*
X1193117Y149950D01*
X1193283Y149200D01*
X1193533Y148700D01*
X1194033Y148200D01*
X1194617Y147867D01*
X1195200Y147700D01*
X1195783D01*
X1196367Y147867D01*
X1196867Y148117D01*
X1197283Y148450D01*
G01X1198967Y147700D02*
Y152700D01*
G01X1202133D02*
X1198967Y149617D01*
G01X1202633Y147700D02*
X1200383Y151033D01*
G01X1210167Y147700D02*
Y152700D01*
X1211833D01*
X1212500Y152450D01*
X1213000Y152117D01*
X1213417Y151617D01*
X1213750Y151033D01*
X1213833Y150200D01*
X1213750Y149367D01*
X1213417Y148783D01*
X1213000Y148283D01*
X1212500Y147950D01*
X1211833Y147700D01*
X1210167D01*
G01X1215933D02*
Y152700D01*
X1218017D01*
X1218683Y152450D01*
X1219100Y152117D01*
X1219267Y151450D01*
X1219100Y150783D01*
X1218600Y150367D01*
X1218017Y150117D01*
X1215933D01*
G01X1218017D02*
X1219267Y147700D01*
G01X1222200Y152700D02*
X1224200D01*
G01X1223200D02*
Y147700D01*
G01X1222200D02*
X1224200D01*
G01X1227133Y152700D02*
Y147700D01*
X1230467D01*
G01X1232733Y152700D02*
Y147700D01*
X1236067D01*
G01X1259900D02*
Y151033D01*
G01Y150117D02*
X1260150Y150533D01*
X1260567Y150867D01*
X1261150Y151033D01*
X1261733Y150867D01*
X1262150Y150533D01*
X1262400Y150117D01*
Y147700D01*
G01Y150117D02*
X1262650Y150533D01*
X1263067Y150867D01*
X1263650Y151033D01*
X1264233Y150867D01*
X1264650Y150533D01*
X1264900Y150033D01*
Y147700D01*
G01X1268000Y151033D02*
Y147700D01*
G01Y152367D02*
X1267833Y152450D01*
Y152617D01*
X1268000Y152700D01*
X1268167Y152617D01*
Y152450D01*
X1268000Y152367D01*
G01X1273600Y147700D02*
Y152700D01*
G01X1277950Y148283D02*
X1278367Y147950D01*
X1278950Y147700D01*
X1279450D01*
X1279950Y147867D01*
X1280283Y148117D01*
X1280450Y148450D01*
X1280367Y148950D01*
X1280033Y149200D01*
X1278533Y149700D01*
X1278200Y150283D01*
X1278367Y150700D01*
X1278700Y150950D01*
X1279200Y151033D01*
X1279700Y150950D01*
X1280200Y150700D01*
G01X1284383Y146033D02*
X1283550Y146867D01*
X1283133Y147700D01*
Y151033D01*
X1283550Y151867D01*
X1284383Y152700D01*
G01X1288483Y147700D02*
Y152700D01*
X1292317Y147700D01*
Y152700D01*
G01X1294333Y147700D02*
Y152700D01*
X1296333D01*
X1297000Y152450D01*
X1297500Y151867D01*
X1297667Y151200D01*
X1297500Y150533D01*
X1297083Y150033D01*
X1296333Y149783D01*
X1294333D01*
G01X1301600Y152700D02*
Y147700D01*
G01X1299683Y152700D02*
X1303517D01*
G01X1305450Y147700D02*
Y152700D01*
G01X1308950D02*
Y147700D01*
G01Y150200D02*
X1305450D01*
G01X1313217Y146033D02*
X1314050Y146867D01*
X1314467Y147700D01*
Y151033D01*
X1314050Y151867D01*
X1313217Y152700D01*
G01X1184667Y150367D02*
X1185000Y150617D01*
X1185250Y151033D01*
X1185417Y151617D01*
X1185250Y152117D01*
X1184917Y152450D01*
X1184333Y152700D01*
X1182083D01*
Y147700D01*
X1184833D01*
X1185417Y148033D01*
X1185750Y148533D01*
X1185917Y149117D01*
X1185750Y149700D01*
X1185250Y150200D01*
X1184667Y150367D01*
X1182083D01*
G01X1187517Y147700D02*
X1189600Y152700D01*
X1191683Y147700D01*
G01X1190933Y149450D02*
X1188267D01*
G01X1197033Y152283D02*
X1196533Y152533D01*
X1195950Y152700D01*
X1195283D01*
X1194533Y152450D01*
X1193950Y152033D01*
X1193533Y151533D01*
X1193200Y150700D01*
X1193117Y149950D01*
X1193283Y149200D01*
X1193533Y148700D01*
X1194033Y148200D01*
X1194617Y147867D01*
X1195200Y147700D01*
X1195783D01*
X1196367Y147867D01*
X1196867Y148117D01*
X1197283Y148450D01*
G01X1198967Y147700D02*
Y152700D01*
G01X1202133D02*
X1198967Y149617D01*
G01X1202633Y147700D02*
X1200383Y151033D01*
G01X1210167Y147700D02*
Y152700D01*
X1211833D01*
X1212500Y152450D01*
X1213000Y152117D01*
X1213417Y151617D01*
X1213750Y151033D01*
X1213833Y150200D01*
X1213750Y149367D01*
X1213417Y148783D01*
X1213000Y148283D01*
X1212500Y147950D01*
X1211833Y147700D01*
X1210167D01*
G01X1215933D02*
Y152700D01*
X1218017D01*
X1218683Y152450D01*
X1219100Y152117D01*
X1219267Y151450D01*
X1219100Y150783D01*
X1218600Y150367D01*
X1218017Y150117D01*
X1215933D01*
G01X1218017D02*
X1219267Y147700D01*
G01X1222200Y152700D02*
X1224200D01*
G01X1223200D02*
Y147700D01*
G01X1222200D02*
X1224200D01*
G01X1227133Y152700D02*
Y147700D01*
X1230467D01*
G01X1232733Y152700D02*
Y147700D01*
X1236067D01*
G01X1259900D02*
Y151033D01*
G01Y150117D02*
X1260150Y150533D01*
X1260567Y150867D01*
X1261150Y151033D01*
X1261733Y150867D01*
X1262150Y150533D01*
X1262400Y150117D01*
Y147700D01*
G01Y150117D02*
X1262650Y150533D01*
X1263067Y150867D01*
X1263650Y151033D01*
X1264233Y150867D01*
X1264650Y150533D01*
X1264900Y150033D01*
Y147700D01*
G01X1268000Y151033D02*
Y147700D01*
G01Y152367D02*
X1267833Y152450D01*
Y152617D01*
X1268000Y152700D01*
X1268167Y152617D01*
Y152450D01*
X1268000Y152367D01*
G01X1273600Y147700D02*
Y152700D01*
G01X1277950Y148283D02*
X1278367Y147950D01*
X1278950Y147700D01*
X1279450D01*
X1279950Y147867D01*
X1280283Y148117D01*
X1280450Y148450D01*
X1280367Y148950D01*
X1280033Y149200D01*
X1278533Y149700D01*
X1278200Y150283D01*
X1278367Y150700D01*
X1278700Y150950D01*
X1279200Y151033D01*
X1279700Y150950D01*
X1280200Y150700D01*
G01X1284383Y146033D02*
X1283550Y146867D01*
X1283133Y147700D01*
Y151033D01*
X1283550Y151867D01*
X1284383Y152700D01*
G01X1288483Y147700D02*
Y152700D01*
X1292317Y147700D01*
Y152700D01*
G01X1294333Y147700D02*
Y152700D01*
X1296333D01*
X1297000Y152450D01*
X1297500Y151867D01*
X1297667Y151200D01*
X1297500Y150533D01*
X1297083Y150033D01*
X1296333Y149783D01*
X1294333D01*
G01X1301600Y152700D02*
Y147700D01*
G01X1299683Y152700D02*
X1303517D01*
G01X1305450Y147700D02*
Y152700D01*
G01X1308950D02*
Y147700D01*
G01Y150200D02*
X1305450D01*
G01X1313217Y146033D02*
X1314050Y146867D01*
X1314467Y147700D01*
Y151033D01*
X1314050Y151867D01*
X1313217Y152700D01*
G01X1210333Y218700D02*
Y213700D01*
X1213667D01*
G01X1216350Y217033D02*
X1218850Y213700D01*
G01Y217033D02*
X1216350Y213700D01*
G01X1207333Y260500D02*
Y255500D01*
X1210667D01*
G01X1213183D02*
Y258833D01*
G01Y258000D02*
X1213517Y258417D01*
X1214017Y258750D01*
X1214683Y258833D01*
X1215267Y258750D01*
X1215767Y258417D01*
X1216017Y257833D01*
Y255500D01*
G01X1210333Y218700D02*
Y213700D01*
X1213667D01*
G01X1216350Y217033D02*
X1218850Y213700D01*
G01Y217033D02*
X1216350Y213700D01*
G01X1207333Y260500D02*
Y255500D01*
X1210667D01*
G01X1213183D02*
Y258833D01*
G01Y258000D02*
X1213517Y258417D01*
X1214017Y258750D01*
X1214683Y258833D01*
X1215267Y258750D01*
X1215767Y258417D01*
X1216017Y257833D01*
Y255500D01*
G01X1218250Y281583D02*
X1218667Y281250D01*
X1219250Y281000D01*
X1219750D01*
X1220250Y281167D01*
X1220583Y281417D01*
X1220750Y281750D01*
X1220667Y282250D01*
X1220333Y282500D01*
X1218833Y283000D01*
X1218500Y283583D01*
X1218667Y284000D01*
X1219000Y284250D01*
X1219500Y284333D01*
X1220000Y284250D01*
X1220500Y284000D01*
G01X1225100Y286000D02*
Y281000D01*
G01X1223933Y284333D02*
X1226267D01*
G01X1229283D02*
Y282000D01*
X1229617Y281417D01*
X1230117Y281083D01*
X1230700Y281000D01*
X1231283Y281083D01*
X1231783Y281417D01*
X1232117Y282000D01*
G01Y281000D02*
Y284333D01*
G01X1234800Y281000D02*
Y286000D01*
G01Y283500D02*
X1235217Y284000D01*
X1235717Y284250D01*
X1236217Y284333D01*
X1236967Y284167D01*
X1237467Y283833D01*
X1237800Y283250D01*
Y282583D01*
X1237633Y281917D01*
X1237300Y281417D01*
X1236717Y281083D01*
X1236217Y281000D01*
X1235717Y281083D01*
X1235217Y281333D01*
X1234800Y281750D01*
G01X1247500Y281000D02*
Y286000D01*
G01X1251850Y283250D02*
X1254517D01*
X1254267Y283833D01*
X1253850Y284167D01*
X1253267Y284333D01*
X1252683Y284250D01*
X1252183Y284000D01*
X1251850Y283417D01*
X1251683Y282917D01*
Y282417D01*
X1251850Y281917D01*
X1252267Y281417D01*
X1252767Y281083D01*
X1253350Y281000D01*
X1253933Y281167D01*
X1254517Y281667D01*
G01X1257283Y281000D02*
Y284333D01*
G01Y283500D02*
X1257617Y283917D01*
X1258117Y284250D01*
X1258783Y284333D01*
X1259367Y284250D01*
X1259867Y283917D01*
X1260117Y283333D01*
Y281000D01*
G01X1263133Y279750D02*
X1263717Y279417D01*
X1264383Y279333D01*
X1264967Y279417D01*
X1265467Y279833D01*
X1265800Y280417D01*
Y284333D01*
G01Y283667D02*
X1265467Y284000D01*
X1264967Y284250D01*
X1264383Y284333D01*
X1263717Y284167D01*
X1263300Y283833D01*
X1262967Y283250D01*
X1262800Y282667D01*
X1262883Y282167D01*
X1263217Y281583D01*
X1263717Y281167D01*
X1264383Y281000D01*
X1264883Y281083D01*
X1265467Y281417D01*
X1265800Y281750D01*
G01X1269900Y286000D02*
Y281000D01*
G01X1268733Y284333D02*
X1271067D01*
G01X1274083Y281000D02*
Y286000D01*
G01Y283583D02*
X1274500Y284000D01*
X1274917Y284250D01*
X1275583Y284333D01*
X1276083Y284250D01*
X1276667Y283917D01*
X1276917Y283417D01*
Y281000D01*
G01X1280017Y281917D02*
X1282183D01*
G01Y283417D02*
X1280017D01*
G01X1285117Y283083D02*
X1285700Y283667D01*
X1286200Y284000D01*
X1286867Y284167D01*
X1287450Y284000D01*
X1287867Y283667D01*
X1288200Y283167D01*
X1288283Y282583D01*
X1288200Y282083D01*
X1287867Y281583D01*
X1287367Y281167D01*
X1286783Y281000D01*
X1286117Y281167D01*
X1285533Y281667D01*
X1285200Y282417D01*
X1285117Y283250D01*
X1285283Y284333D01*
X1285533Y284917D01*
X1285950Y285500D01*
X1286533Y285917D01*
X1287117Y286000D01*
X1287700Y285833D01*
X1288117Y285417D01*
G01X1291383Y282667D02*
X1293383D01*
G01X1292300Y283750D02*
Y281583D01*
G01X1296400Y280833D02*
X1299400Y286000D01*
G01X1302417Y282667D02*
X1304583D01*
G01X1307267Y281750D02*
X1307767Y281333D01*
X1308350Y281083D01*
X1309100Y281000D01*
X1309850Y281167D01*
X1310433Y281500D01*
X1310850Y282083D01*
X1310933Y282750D01*
X1310767Y283417D01*
X1310350Y283833D01*
X1309767Y284167D01*
X1309183Y284250D01*
X1308600Y284167D01*
X1307850Y283833D01*
X1308100Y286000D01*
X1310350D01*
G01X1312200Y281000D02*
Y284333D01*
G01Y283417D02*
X1312450Y283833D01*
X1312867Y284167D01*
X1313450Y284333D01*
X1314033Y284167D01*
X1314450Y283833D01*
X1314700Y283417D01*
Y281000D01*
G01Y283417D02*
X1314950Y283833D01*
X1315367Y284167D01*
X1315950Y284333D01*
X1316533Y284167D01*
X1316950Y283833D01*
X1317200Y283333D01*
Y281000D01*
G01X1320300Y284333D02*
Y281000D01*
G01Y285667D02*
X1320133Y285750D01*
Y285917D01*
X1320300Y286000D01*
X1320467Y285917D01*
Y285750D01*
X1320300Y285667D01*
G01X1325900Y281000D02*
Y286000D01*
G01X1178750Y315500D02*
Y320500D01*
G01X1182250D02*
Y315500D01*
G01Y318000D02*
X1178750D01*
G01X1186100Y315500D02*
X1185433Y315583D01*
X1184850Y315917D01*
X1184350Y316417D01*
X1184017Y317000D01*
X1183850Y317667D01*
Y318333D01*
X1184017Y319000D01*
X1184350Y319583D01*
X1184850Y320083D01*
X1185433Y320417D01*
X1186100Y320500D01*
X1186767Y320417D01*
X1187350Y320083D01*
X1187850Y319583D01*
X1188183Y319000D01*
X1188350Y318333D01*
Y317667D01*
X1188183Y317000D01*
X1187850Y316417D01*
X1187350Y315917D01*
X1186767Y315583D01*
X1186100Y315500D01*
G01X1190033Y320500D02*
Y315500D01*
X1193367D01*
G01X1198967D02*
X1195633D01*
Y320500D01*
X1198967D01*
G01X1197633Y318083D02*
X1195633D01*
G01X1222800Y315500D02*
Y318833D01*
G01Y317917D02*
X1223050Y318333D01*
X1223467Y318667D01*
X1224050Y318833D01*
X1224633Y318667D01*
X1225050Y318333D01*
X1225300Y317917D01*
Y315500D01*
G01Y317917D02*
X1225550Y318333D01*
X1225967Y318667D01*
X1226550Y318833D01*
X1227133Y318667D01*
X1227550Y318333D01*
X1227800Y317833D01*
Y315500D01*
G01X1230900Y318833D02*
Y315500D01*
G01Y320167D02*
X1230733Y320250D01*
Y320417D01*
X1230900Y320500D01*
X1231067Y320417D01*
Y320250D01*
X1230900Y320167D01*
G01X1236500Y315500D02*
Y320500D01*
G01X1240850Y316083D02*
X1241267Y315750D01*
X1241850Y315500D01*
X1242350D01*
X1242850Y315667D01*
X1243183Y315917D01*
X1243350Y316250D01*
X1243267Y316750D01*
X1242933Y317000D01*
X1241433Y317500D01*
X1241100Y318083D01*
X1241267Y318500D01*
X1241600Y318750D01*
X1242100Y318833D01*
X1242600Y318750D01*
X1243100Y318500D01*
G01X1247283Y313833D02*
X1246450Y314667D01*
X1246033Y315500D01*
Y318833D01*
X1246450Y319667D01*
X1247283Y320500D01*
G01X1251633Y315500D02*
Y320500D01*
X1253633D01*
X1254300Y320250D01*
X1254800Y319667D01*
X1254967Y319000D01*
X1254800Y318333D01*
X1254383Y317833D01*
X1253633Y317583D01*
X1251633D01*
G01X1258900Y320500D02*
Y315500D01*
G01X1256983Y320500D02*
X1260817D01*
G01X1262750Y315500D02*
Y320500D01*
G01X1266250D02*
Y315500D01*
G01Y318000D02*
X1262750D01*
G01X1270517Y313833D02*
X1271350Y314667D01*
X1271767Y315500D01*
Y318833D01*
X1271350Y319667D01*
X1270517Y320500D01*
G01X1218250Y281583D02*
X1218667Y281250D01*
X1219250Y281000D01*
X1219750D01*
X1220250Y281167D01*
X1220583Y281417D01*
X1220750Y281750D01*
X1220667Y282250D01*
X1220333Y282500D01*
X1218833Y283000D01*
X1218500Y283583D01*
X1218667Y284000D01*
X1219000Y284250D01*
X1219500Y284333D01*
X1220000Y284250D01*
X1220500Y284000D01*
G01X1225100Y286000D02*
Y281000D01*
G01X1223933Y284333D02*
X1226267D01*
G01X1229283D02*
Y282000D01*
X1229617Y281417D01*
X1230117Y281083D01*
X1230700Y281000D01*
X1231283Y281083D01*
X1231783Y281417D01*
X1232117Y282000D01*
G01Y281000D02*
Y284333D01*
G01X1234800Y281000D02*
Y286000D01*
G01Y283500D02*
X1235217Y284000D01*
X1235717Y284250D01*
X1236217Y284333D01*
X1236967Y284167D01*
X1237467Y283833D01*
X1237800Y283250D01*
Y282583D01*
X1237633Y281917D01*
X1237300Y281417D01*
X1236717Y281083D01*
X1236217Y281000D01*
X1235717Y281083D01*
X1235217Y281333D01*
X1234800Y281750D01*
G01X1247500Y281000D02*
Y286000D01*
G01X1251850Y283250D02*
X1254517D01*
X1254267Y283833D01*
X1253850Y284167D01*
X1253267Y284333D01*
X1252683Y284250D01*
X1252183Y284000D01*
X1251850Y283417D01*
X1251683Y282917D01*
Y282417D01*
X1251850Y281917D01*
X1252267Y281417D01*
X1252767Y281083D01*
X1253350Y281000D01*
X1253933Y281167D01*
X1254517Y281667D01*
G01X1257283Y281000D02*
Y284333D01*
G01Y283500D02*
X1257617Y283917D01*
X1258117Y284250D01*
X1258783Y284333D01*
X1259367Y284250D01*
X1259867Y283917D01*
X1260117Y283333D01*
Y281000D01*
G01X1263133Y279750D02*
X1263717Y279417D01*
X1264383Y279333D01*
X1264967Y279417D01*
X1265467Y279833D01*
X1265800Y280417D01*
Y284333D01*
G01Y283667D02*
X1265467Y284000D01*
X1264967Y284250D01*
X1264383Y284333D01*
X1263717Y284167D01*
X1263300Y283833D01*
X1262967Y283250D01*
X1262800Y282667D01*
X1262883Y282167D01*
X1263217Y281583D01*
X1263717Y281167D01*
X1264383Y281000D01*
X1264883Y281083D01*
X1265467Y281417D01*
X1265800Y281750D01*
G01X1269900Y286000D02*
Y281000D01*
G01X1268733Y284333D02*
X1271067D01*
G01X1274083Y281000D02*
Y286000D01*
G01Y283583D02*
X1274500Y284000D01*
X1274917Y284250D01*
X1275583Y284333D01*
X1276083Y284250D01*
X1276667Y283917D01*
X1276917Y283417D01*
Y281000D01*
G01X1280017Y281917D02*
X1282183D01*
G01Y283417D02*
X1280017D01*
G01X1285117Y283083D02*
X1285700Y283667D01*
X1286200Y284000D01*
X1286867Y284167D01*
X1287450Y284000D01*
X1287867Y283667D01*
X1288200Y283167D01*
X1288283Y282583D01*
X1288200Y282083D01*
X1287867Y281583D01*
X1287367Y281167D01*
X1286783Y281000D01*
X1286117Y281167D01*
X1285533Y281667D01*
X1285200Y282417D01*
X1285117Y283250D01*
X1285283Y284333D01*
X1285533Y284917D01*
X1285950Y285500D01*
X1286533Y285917D01*
X1287117Y286000D01*
X1287700Y285833D01*
X1288117Y285417D01*
G01X1291383Y282667D02*
X1293383D01*
G01X1292300Y283750D02*
Y281583D01*
G01X1296400Y280833D02*
X1299400Y286000D01*
G01X1302417Y282667D02*
X1304583D01*
G01X1307267Y281750D02*
X1307767Y281333D01*
X1308350Y281083D01*
X1309100Y281000D01*
X1309850Y281167D01*
X1310433Y281500D01*
X1310850Y282083D01*
X1310933Y282750D01*
X1310767Y283417D01*
X1310350Y283833D01*
X1309767Y284167D01*
X1309183Y284250D01*
X1308600Y284167D01*
X1307850Y283833D01*
X1308100Y286000D01*
X1310350D01*
G01X1312200Y281000D02*
Y284333D01*
G01Y283417D02*
X1312450Y283833D01*
X1312867Y284167D01*
X1313450Y284333D01*
X1314033Y284167D01*
X1314450Y283833D01*
X1314700Y283417D01*
Y281000D01*
G01Y283417D02*
X1314950Y283833D01*
X1315367Y284167D01*
X1315950Y284333D01*
X1316533Y284167D01*
X1316950Y283833D01*
X1317200Y283333D01*
Y281000D01*
G01X1320300Y284333D02*
Y281000D01*
G01Y285667D02*
X1320133Y285750D01*
Y285917D01*
X1320300Y286000D01*
X1320467Y285917D01*
Y285750D01*
X1320300Y285667D01*
G01X1325900Y281000D02*
Y286000D01*
G01X1178750Y315500D02*
Y320500D01*
G01X1182250D02*
Y315500D01*
G01Y318000D02*
X1178750D01*
G01X1186100Y315500D02*
X1185433Y315583D01*
X1184850Y315917D01*
X1184350Y316417D01*
X1184017Y317000D01*
X1183850Y317667D01*
Y318333D01*
X1184017Y319000D01*
X1184350Y319583D01*
X1184850Y320083D01*
X1185433Y320417D01*
X1186100Y320500D01*
X1186767Y320417D01*
X1187350Y320083D01*
X1187850Y319583D01*
X1188183Y319000D01*
X1188350Y318333D01*
Y317667D01*
X1188183Y317000D01*
X1187850Y316417D01*
X1187350Y315917D01*
X1186767Y315583D01*
X1186100Y315500D01*
G01X1190033Y320500D02*
Y315500D01*
X1193367D01*
G01X1198967D02*
X1195633D01*
Y320500D01*
X1198967D01*
G01X1197633Y318083D02*
X1195633D01*
G01X1222800Y315500D02*
Y318833D01*
G01Y317917D02*
X1223050Y318333D01*
X1223467Y318667D01*
X1224050Y318833D01*
X1224633Y318667D01*
X1225050Y318333D01*
X1225300Y317917D01*
Y315500D01*
G01Y317917D02*
X1225550Y318333D01*
X1225967Y318667D01*
X1226550Y318833D01*
X1227133Y318667D01*
X1227550Y318333D01*
X1227800Y317833D01*
Y315500D01*
G01X1230900Y318833D02*
Y315500D01*
G01Y320167D02*
X1230733Y320250D01*
Y320417D01*
X1230900Y320500D01*
X1231067Y320417D01*
Y320250D01*
X1230900Y320167D01*
G01X1236500Y315500D02*
Y320500D01*
G01X1240850Y316083D02*
X1241267Y315750D01*
X1241850Y315500D01*
X1242350D01*
X1242850Y315667D01*
X1243183Y315917D01*
X1243350Y316250D01*
X1243267Y316750D01*
X1242933Y317000D01*
X1241433Y317500D01*
X1241100Y318083D01*
X1241267Y318500D01*
X1241600Y318750D01*
X1242100Y318833D01*
X1242600Y318750D01*
X1243100Y318500D01*
G01X1247283Y313833D02*
X1246450Y314667D01*
X1246033Y315500D01*
Y318833D01*
X1246450Y319667D01*
X1247283Y320500D01*
G01X1251633Y315500D02*
Y320500D01*
X1253633D01*
X1254300Y320250D01*
X1254800Y319667D01*
X1254967Y319000D01*
X1254800Y318333D01*
X1254383Y317833D01*
X1253633Y317583D01*
X1251633D01*
G01X1258900Y320500D02*
Y315500D01*
G01X1256983Y320500D02*
X1260817D01*
G01X1262750Y315500D02*
Y320500D01*
G01X1266250D02*
Y315500D01*
G01Y318000D02*
X1262750D01*
G01X1270517Y313833D02*
X1271350Y314667D01*
X1271767Y315500D01*
Y318833D01*
X1271350Y319667D01*
X1270517Y320500D01*
G01X1180417Y734500D02*
X1182500Y729500D01*
X1184583Y734500D01*
G01X1188100Y729500D02*
X1187433Y729583D01*
X1186850Y729917D01*
X1186350Y730417D01*
X1186017Y731000D01*
X1185850Y731667D01*
Y732333D01*
X1186017Y733000D01*
X1186350Y733583D01*
X1186850Y734083D01*
X1187433Y734417D01*
X1188100Y734500D01*
X1188767Y734417D01*
X1189350Y734083D01*
X1189850Y733583D01*
X1190183Y733000D01*
X1190350Y732333D01*
Y731667D01*
X1190183Y731000D01*
X1189850Y730417D01*
X1189350Y729917D01*
X1188767Y729583D01*
X1188100Y729500D01*
G01X1192033D02*
Y734500D01*
X1194033D01*
X1194700Y734250D01*
X1195200Y733667D01*
X1195367Y733000D01*
X1195200Y732333D01*
X1194783Y731833D01*
X1194033Y731583D01*
X1192033D01*
G01X1180417Y734500D02*
X1182500Y729500D01*
X1184583Y734500D01*
G01X1188100Y729500D02*
X1187433Y729583D01*
X1186850Y729917D01*
X1186350Y730417D01*
X1186017Y731000D01*
X1185850Y731667D01*
Y732333D01*
X1186017Y733000D01*
X1186350Y733583D01*
X1186850Y734083D01*
X1187433Y734417D01*
X1188100Y734500D01*
X1188767Y734417D01*
X1189350Y734083D01*
X1189850Y733583D01*
X1190183Y733000D01*
X1190350Y732333D01*
Y731667D01*
X1190183Y731000D01*
X1189850Y730417D01*
X1189350Y729917D01*
X1188767Y729583D01*
X1188100Y729500D01*
G01X1192033D02*
Y734500D01*
X1194033D01*
X1194700Y734250D01*
X1195200Y733667D01*
X1195367Y733000D01*
X1195200Y732333D01*
X1194783Y731833D01*
X1194033Y731583D01*
X1192033D01*
G01X1241083Y811667D02*
X1243083D01*
G01X1242000Y812750D02*
Y810583D01*
G01X1246100Y809833D02*
X1249100Y815000D01*
G01X1252117Y811667D02*
X1254283D01*
G01X1257217Y814167D02*
X1257717Y814667D01*
X1258300Y814917D01*
X1258967Y815000D01*
X1259800Y814833D01*
X1260383Y814417D01*
X1260550Y813917D01*
X1260467Y813417D01*
X1260133Y813000D01*
X1258467Y812167D01*
X1257717Y811583D01*
X1257217Y810750D01*
X1257050Y810000D01*
X1260550D01*
G01X1261900D02*
Y813333D01*
G01Y812417D02*
X1262150Y812833D01*
X1262567Y813167D01*
X1263150Y813333D01*
X1263733Y813167D01*
X1264150Y812833D01*
X1264400Y812417D01*
Y810000D01*
G01Y812417D02*
X1264650Y812833D01*
X1265067Y813167D01*
X1265650Y813333D01*
X1266233Y813167D01*
X1266650Y812833D01*
X1266900Y812333D01*
Y810000D01*
G01X1270000Y813333D02*
Y810000D01*
G01Y814667D02*
X1269833Y814750D01*
Y814917D01*
X1270000Y815000D01*
X1270167Y814917D01*
Y814750D01*
X1270000Y814667D01*
G01X1275600Y810000D02*
Y815000D01*
G01X1242793Y785443D02*
X1241960Y786277D01*
X1241543Y787110D01*
Y790443D01*
X1241960Y791277D01*
X1242793Y792110D01*
G01X1248810Y787110D02*
Y792110D01*
X1247810Y791110D01*
G01Y787110D02*
X1249810D01*
G01X1254410Y786943D02*
X1254243Y787027D01*
Y787193D01*
X1254410Y787277D01*
X1254577Y787193D01*
Y787027D01*
X1254410Y786943D01*
G01X1258427Y791277D02*
X1258927Y791777D01*
X1259510Y792027D01*
X1260177Y792110D01*
X1261010Y791943D01*
X1261593Y791527D01*
X1261760Y791027D01*
X1261677Y790527D01*
X1261343Y790110D01*
X1259677Y789277D01*
X1258927Y788693D01*
X1258427Y787860D01*
X1258260Y787110D01*
X1261760D01*
G01X1263110D02*
Y790443D01*
G01Y789527D02*
X1263360Y789943D01*
X1263777Y790277D01*
X1264360Y790443D01*
X1264943Y790277D01*
X1265360Y789943D01*
X1265610Y789527D01*
Y787110D01*
G01Y789527D02*
X1265860Y789943D01*
X1266277Y790277D01*
X1266860Y790443D01*
X1267443Y790277D01*
X1267860Y789943D01*
X1268110Y789443D01*
Y787110D01*
G01X1268710D02*
Y790443D01*
G01Y789527D02*
X1268960Y789943D01*
X1269377Y790277D01*
X1269960Y790443D01*
X1270543Y790277D01*
X1270960Y789943D01*
X1271210Y789527D01*
Y787110D01*
G01Y789527D02*
X1271460Y789943D01*
X1271877Y790277D01*
X1272460Y790443D01*
X1273043Y790277D01*
X1273460Y789943D01*
X1273710Y789443D01*
Y787110D01*
G01X1280243D02*
Y792110D01*
X1282410Y787943D01*
X1284577Y792110D01*
Y787110D01*
G01X1289510D02*
Y790443D01*
G01Y789860D02*
X1289177Y790193D01*
X1288677Y790360D01*
X1288093Y790443D01*
X1287510Y790277D01*
X1287010Y789943D01*
X1286677Y789443D01*
X1286510Y788777D01*
X1286677Y788110D01*
X1287010Y787610D01*
X1287510Y787277D01*
X1288093Y787110D01*
X1288677Y787193D01*
X1289177Y787443D01*
X1289510Y787777D01*
G01X1292360Y790443D02*
X1294860Y787110D01*
G01Y790443D02*
X1292360Y787110D01*
G01X1299627Y785443D02*
X1300460Y786277D01*
X1300877Y787110D01*
Y790443D01*
X1300460Y791277D01*
X1299627Y792110D01*
G01X1244877Y797230D02*
X1241543Y798897D01*
X1244877Y800563D01*
G01X1247727Y798147D02*
X1249893D01*
G01Y799647D02*
X1247727D01*
G01X1254410Y802230D02*
X1253743Y802063D01*
X1253243Y801647D01*
X1252910Y801147D01*
X1252660Y800480D01*
X1252577Y799730D01*
X1252660Y798980D01*
X1252910Y798313D01*
X1253243Y797813D01*
X1253743Y797397D01*
X1254410Y797230D01*
X1255077Y797397D01*
X1255577Y797813D01*
X1255910Y798313D01*
X1256160Y798980D01*
X1256243Y799730D01*
X1256160Y800480D01*
X1255910Y801147D01*
X1255577Y801647D01*
X1255077Y802063D01*
X1254410Y802230D01*
G01X1260010Y797063D02*
X1259843Y797147D01*
Y797313D01*
X1260010Y797397D01*
X1260177Y797313D01*
Y797147D01*
X1260010Y797063D01*
G01X1265443Y797230D02*
X1265610Y798313D01*
X1265860Y799230D01*
X1266193Y800063D01*
X1266610Y800980D01*
X1267277Y802230D01*
X1263943D01*
G01X1269377Y797980D02*
X1269877Y797563D01*
X1270460Y797313D01*
X1271210Y797230D01*
X1271960Y797397D01*
X1272543Y797730D01*
X1272960Y798313D01*
X1273043Y798980D01*
X1272877Y799647D01*
X1272460Y800063D01*
X1271877Y800397D01*
X1271293Y800480D01*
X1270710Y800397D01*
X1269960Y800063D01*
X1270210Y802230D01*
X1272460D01*
G01X1275310Y797063D02*
X1278310Y802230D01*
G01X1275310D02*
X1274810Y802063D01*
X1274560Y801813D01*
X1274393Y801313D01*
X1274560Y800813D01*
X1274810Y800563D01*
X1275310Y800397D01*
X1275810Y800563D01*
X1276060Y800813D01*
X1276227Y801313D01*
X1276060Y801813D01*
X1275810Y802063D01*
X1275310Y802230D01*
G01X1278310Y798897D02*
X1277810Y798730D01*
X1277560Y798480D01*
X1277393Y797980D01*
X1277560Y797480D01*
X1277810Y797230D01*
X1278310Y797063D01*
X1278810Y797230D01*
X1279060Y797480D01*
X1279227Y797980D01*
X1279060Y798480D01*
X1278810Y798730D01*
X1278310Y798897D01*
G01X1234540Y850500D02*
Y782000D01*
G01X1241083Y811667D02*
X1243083D01*
G01X1242000Y812750D02*
Y810583D01*
G01X1246100Y809833D02*
X1249100Y815000D01*
G01X1252117Y811667D02*
X1254283D01*
G01X1257217Y814167D02*
X1257717Y814667D01*
X1258300Y814917D01*
X1258967Y815000D01*
X1259800Y814833D01*
X1260383Y814417D01*
X1260550Y813917D01*
X1260467Y813417D01*
X1260133Y813000D01*
X1258467Y812167D01*
X1257717Y811583D01*
X1257217Y810750D01*
X1257050Y810000D01*
X1260550D01*
G01X1261900D02*
Y813333D01*
G01Y812417D02*
X1262150Y812833D01*
X1262567Y813167D01*
X1263150Y813333D01*
X1263733Y813167D01*
X1264150Y812833D01*
X1264400Y812417D01*
Y810000D01*
G01Y812417D02*
X1264650Y812833D01*
X1265067Y813167D01*
X1265650Y813333D01*
X1266233Y813167D01*
X1266650Y812833D01*
X1266900Y812333D01*
Y810000D01*
G01X1270000Y813333D02*
Y810000D01*
G01Y814667D02*
X1269833Y814750D01*
Y814917D01*
X1270000Y815000D01*
X1270167Y814917D01*
Y814750D01*
X1270000Y814667D01*
G01X1275600Y810000D02*
Y815000D01*
G01X1242793Y785443D02*
X1241960Y786277D01*
X1241543Y787110D01*
Y790443D01*
X1241960Y791277D01*
X1242793Y792110D01*
G01X1248810Y787110D02*
Y792110D01*
X1247810Y791110D01*
G01Y787110D02*
X1249810D01*
G01X1254410Y786943D02*
X1254243Y787027D01*
Y787193D01*
X1254410Y787277D01*
X1254577Y787193D01*
Y787027D01*
X1254410Y786943D01*
G01X1258427Y791277D02*
X1258927Y791777D01*
X1259510Y792027D01*
X1260177Y792110D01*
X1261010Y791943D01*
X1261593Y791527D01*
X1261760Y791027D01*
X1261677Y790527D01*
X1261343Y790110D01*
X1259677Y789277D01*
X1258927Y788693D01*
X1258427Y787860D01*
X1258260Y787110D01*
X1261760D01*
G01X1263110D02*
Y790443D01*
G01Y789527D02*
X1263360Y789943D01*
X1263777Y790277D01*
X1264360Y790443D01*
X1264943Y790277D01*
X1265360Y789943D01*
X1265610Y789527D01*
Y787110D01*
G01Y789527D02*
X1265860Y789943D01*
X1266277Y790277D01*
X1266860Y790443D01*
X1267443Y790277D01*
X1267860Y789943D01*
X1268110Y789443D01*
Y787110D01*
G01X1268710D02*
Y790443D01*
G01Y789527D02*
X1268960Y789943D01*
X1269377Y790277D01*
X1269960Y790443D01*
X1270543Y790277D01*
X1270960Y789943D01*
X1271210Y789527D01*
Y787110D01*
G01Y789527D02*
X1271460Y789943D01*
X1271877Y790277D01*
X1272460Y790443D01*
X1273043Y790277D01*
X1273460Y789943D01*
X1273710Y789443D01*
Y787110D01*
G01X1280243D02*
Y792110D01*
X1282410Y787943D01*
X1284577Y792110D01*
Y787110D01*
G01X1289510D02*
Y790443D01*
G01Y789860D02*
X1289177Y790193D01*
X1288677Y790360D01*
X1288093Y790443D01*
X1287510Y790277D01*
X1287010Y789943D01*
X1286677Y789443D01*
X1286510Y788777D01*
X1286677Y788110D01*
X1287010Y787610D01*
X1287510Y787277D01*
X1288093Y787110D01*
X1288677Y787193D01*
X1289177Y787443D01*
X1289510Y787777D01*
G01X1292360Y790443D02*
X1294860Y787110D01*
G01Y790443D02*
X1292360Y787110D01*
G01X1299627Y785443D02*
X1300460Y786277D01*
X1300877Y787110D01*
Y790443D01*
X1300460Y791277D01*
X1299627Y792110D01*
G01X1244877Y797230D02*
X1241543Y798897D01*
X1244877Y800563D01*
G01X1247727Y798147D02*
X1249893D01*
G01Y799647D02*
X1247727D01*
G01X1254410Y802230D02*
X1253743Y802063D01*
X1253243Y801647D01*
X1252910Y801147D01*
X1252660Y800480D01*
X1252577Y799730D01*
X1252660Y798980D01*
X1252910Y798313D01*
X1253243Y797813D01*
X1253743Y797397D01*
X1254410Y797230D01*
X1255077Y797397D01*
X1255577Y797813D01*
X1255910Y798313D01*
X1256160Y798980D01*
X1256243Y799730D01*
X1256160Y800480D01*
X1255910Y801147D01*
X1255577Y801647D01*
X1255077Y802063D01*
X1254410Y802230D01*
G01X1260010Y797063D02*
X1259843Y797147D01*
Y797313D01*
X1260010Y797397D01*
X1260177Y797313D01*
Y797147D01*
X1260010Y797063D01*
G01X1265443Y797230D02*
X1265610Y798313D01*
X1265860Y799230D01*
X1266193Y800063D01*
X1266610Y800980D01*
X1267277Y802230D01*
X1263943D01*
G01X1269377Y797980D02*
X1269877Y797563D01*
X1270460Y797313D01*
X1271210Y797230D01*
X1271960Y797397D01*
X1272543Y797730D01*
X1272960Y798313D01*
X1273043Y798980D01*
X1272877Y799647D01*
X1272460Y800063D01*
X1271877Y800397D01*
X1271293Y800480D01*
X1270710Y800397D01*
X1269960Y800063D01*
X1270210Y802230D01*
X1272460D01*
G01X1275310Y797063D02*
X1278310Y802230D01*
G01X1275310D02*
X1274810Y802063D01*
X1274560Y801813D01*
X1274393Y801313D01*
X1274560Y800813D01*
X1274810Y800563D01*
X1275310Y800397D01*
X1275810Y800563D01*
X1276060Y800813D01*
X1276227Y801313D01*
X1276060Y801813D01*
X1275810Y802063D01*
X1275310Y802230D01*
G01X1278310Y798897D02*
X1277810Y798730D01*
X1277560Y798480D01*
X1277393Y797980D01*
X1277560Y797480D01*
X1277810Y797230D01*
X1278310Y797063D01*
X1278810Y797230D01*
X1279060Y797480D01*
X1279227Y797980D01*
X1279060Y798480D01*
X1278810Y798730D01*
X1278310Y798897D01*
G01X1234540Y850500D02*
Y782000D01*
G01X1241083Y841667D02*
X1243083D01*
G01X1242000Y842750D02*
Y840583D01*
G01X1246100Y839833D02*
X1249100Y845000D01*
G01X1252117Y841667D02*
X1254283D01*
G01X1256967Y840750D02*
X1257467Y840333D01*
X1258050Y840083D01*
X1258800Y840000D01*
X1259550Y840167D01*
X1260133Y840500D01*
X1260550Y841083D01*
X1260633Y841750D01*
X1260467Y842417D01*
X1260050Y842833D01*
X1259467Y843167D01*
X1258883Y843250D01*
X1258300Y843167D01*
X1257550Y842833D01*
X1257800Y845000D01*
X1260050D01*
G01X1261900Y840000D02*
Y843333D01*
G01Y842417D02*
X1262150Y842833D01*
X1262567Y843167D01*
X1263150Y843333D01*
X1263733Y843167D01*
X1264150Y842833D01*
X1264400Y842417D01*
Y840000D01*
G01Y842417D02*
X1264650Y842833D01*
X1265067Y843167D01*
X1265650Y843333D01*
X1266233Y843167D01*
X1266650Y842833D01*
X1266900Y842333D01*
Y840000D01*
G01X1270000Y843333D02*
Y840000D01*
G01Y844667D02*
X1269833Y844750D01*
Y844917D01*
X1270000Y845000D01*
X1270167Y844917D01*
Y844750D01*
X1270000Y844667D01*
G01X1275600Y840000D02*
Y845000D01*
G01X1241083Y826667D02*
X1243083D01*
G01X1242000Y827750D02*
Y825583D01*
G01X1246100Y824833D02*
X1249100Y830000D01*
G01X1252117Y826667D02*
X1254283D01*
G01X1256967Y825750D02*
X1257467Y825333D01*
X1258050Y825083D01*
X1258800Y825000D01*
X1259550Y825167D01*
X1260133Y825500D01*
X1260550Y826083D01*
X1260633Y826750D01*
X1260467Y827417D01*
X1260050Y827833D01*
X1259467Y828167D01*
X1258883Y828250D01*
X1258300Y828167D01*
X1257550Y827833D01*
X1257800Y830000D01*
X1260050D01*
G01X1261900Y825000D02*
Y828333D01*
G01Y827417D02*
X1262150Y827833D01*
X1262567Y828167D01*
X1263150Y828333D01*
X1263733Y828167D01*
X1264150Y827833D01*
X1264400Y827417D01*
Y825000D01*
G01Y827417D02*
X1264650Y827833D01*
X1265067Y828167D01*
X1265650Y828333D01*
X1266233Y828167D01*
X1266650Y827833D01*
X1266900Y827333D01*
Y825000D01*
G01X1270000Y828333D02*
Y825000D01*
G01Y829667D02*
X1269833Y829750D01*
Y829917D01*
X1270000Y830000D01*
X1270167Y829917D01*
Y829750D01*
X1270000Y829667D01*
G01X1275600Y825000D02*
Y830000D01*
G01X1241083Y841667D02*
X1243083D01*
G01X1242000Y842750D02*
Y840583D01*
G01X1246100Y839833D02*
X1249100Y845000D01*
G01X1252117Y841667D02*
X1254283D01*
G01X1256967Y840750D02*
X1257467Y840333D01*
X1258050Y840083D01*
X1258800Y840000D01*
X1259550Y840167D01*
X1260133Y840500D01*
X1260550Y841083D01*
X1260633Y841750D01*
X1260467Y842417D01*
X1260050Y842833D01*
X1259467Y843167D01*
X1258883Y843250D01*
X1258300Y843167D01*
X1257550Y842833D01*
X1257800Y845000D01*
X1260050D01*
G01X1261900Y840000D02*
Y843333D01*
G01Y842417D02*
X1262150Y842833D01*
X1262567Y843167D01*
X1263150Y843333D01*
X1263733Y843167D01*
X1264150Y842833D01*
X1264400Y842417D01*
Y840000D01*
G01Y842417D02*
X1264650Y842833D01*
X1265067Y843167D01*
X1265650Y843333D01*
X1266233Y843167D01*
X1266650Y842833D01*
X1266900Y842333D01*
Y840000D01*
G01X1270000Y843333D02*
Y840000D01*
G01Y844667D02*
X1269833Y844750D01*
Y844917D01*
X1270000Y845000D01*
X1270167Y844917D01*
Y844750D01*
X1270000Y844667D01*
G01X1275600Y840000D02*
Y845000D01*
G01X1241083Y826667D02*
X1243083D01*
G01X1242000Y827750D02*
Y825583D01*
G01X1246100Y824833D02*
X1249100Y830000D01*
G01X1252117Y826667D02*
X1254283D01*
G01X1256967Y825750D02*
X1257467Y825333D01*
X1258050Y825083D01*
X1258800Y825000D01*
X1259550Y825167D01*
X1260133Y825500D01*
X1260550Y826083D01*
X1260633Y826750D01*
X1260467Y827417D01*
X1260050Y827833D01*
X1259467Y828167D01*
X1258883Y828250D01*
X1258300Y828167D01*
X1257550Y827833D01*
X1257800Y830000D01*
X1260050D01*
G01X1261900Y825000D02*
Y828333D01*
G01Y827417D02*
X1262150Y827833D01*
X1262567Y828167D01*
X1263150Y828333D01*
X1263733Y828167D01*
X1264150Y827833D01*
X1264400Y827417D01*
Y825000D01*
G01Y827417D02*
X1264650Y827833D01*
X1265067Y828167D01*
X1265650Y828333D01*
X1266233Y828167D01*
X1266650Y827833D01*
X1266900Y827333D01*
Y825000D01*
G01X1270000Y828333D02*
Y825000D01*
G01Y829667D02*
X1269833Y829750D01*
Y829917D01*
X1270000Y830000D01*
X1270167Y829917D01*
Y829750D01*
X1270000Y829667D01*
G01X1275600Y825000D02*
Y830000D01*
G01X1343000Y850610D02*
Y782110D01*
G01Y850610D02*
Y782110D01*
G54D12*
G01X898852Y712354D02*
Y635354D01*
G01D02*
X942852D01*
G01X907102Y628479D02*
Y635354D01*
G01X891977Y628479D02*
X907102D01*
G01X891977Y721979D02*
Y628479D01*
G01X865852Y712354D02*
Y635354D01*
G01X872727Y628479D02*
Y721979D01*
G01X857602Y628479D02*
X872727D01*
G01X857602Y635354D02*
Y628479D01*
G01X865852Y635354D02*
X843852D01*
G01D02*
Y712354D01*
G01X898852D02*
Y635354D01*
G01D02*
X942852D01*
G01X907102Y628479D02*
Y635354D01*
G01X891977Y628479D02*
X907102D01*
G01X891977Y721979D02*
Y628479D01*
G01X865852Y712354D02*
Y635354D01*
G01X872727Y628479D02*
Y721979D01*
G01X857602Y628479D02*
X872727D01*
G01X857602Y635354D02*
Y628479D01*
G01X865852Y635354D02*
X843852D01*
G01D02*
Y712354D01*
G01X942852D02*
X898852D01*
G01X907102Y715104D02*
Y721979D01*
G01D02*
X891977D01*
G01X857602D02*
Y715104D01*
G01X872727Y721979D02*
X857602D01*
G01X843852Y712354D02*
X865852D01*
G01X942852D02*
X898852D01*
G01X907102Y715104D02*
Y721979D01*
G01D02*
X891977D01*
G01X857602D02*
Y715104D01*
G01X872727Y721979D02*
X857602D01*
G01X843852Y712354D02*
X865852D01*
G01X984102Y628479D02*
Y635354D01*
G01X975852Y712354D02*
Y635354D01*
G01D02*
X1019852D01*
G01X968977Y628479D02*
X984102D01*
G01X968977Y721979D02*
Y628479D01*
G01X949727D02*
Y721979D01*
G01X934602Y628479D02*
X949727D01*
G01X934602Y635354D02*
Y628479D01*
G01X942852Y635354D02*
Y712354D01*
G01X984102Y628479D02*
Y635354D01*
G01X975852Y712354D02*
Y635354D01*
G01D02*
X1019852D01*
G01X968977Y628479D02*
X984102D01*
G01X968977Y721979D02*
Y628479D01*
G01X949727D02*
Y721979D01*
G01X934602Y628479D02*
X949727D01*
G01X934602Y635354D02*
Y628479D01*
G01X942852Y635354D02*
Y712354D01*
G01X984102Y715104D02*
Y721979D01*
G01X1019852Y712354D02*
X975852D01*
G01X984102Y721979D02*
X968977D01*
G01X934602D02*
Y715104D01*
G01X949727Y721979D02*
X934602D01*
G01X984102Y715104D02*
Y721979D01*
G01X1019852Y712354D02*
X975852D01*
G01X984102Y721979D02*
X968977D01*
G01X934602D02*
Y715104D01*
G01X949727Y721979D02*
X934602D01*
G01X1061102Y628479D02*
Y635354D01*
G01X1045977Y628479D02*
X1061102D01*
G01X1045977Y719229D02*
Y628479D01*
G01X1052852Y712354D02*
Y635354D01*
G01D02*
X1096852D01*
G01X1026727Y628479D02*
Y719229D01*
G01X1019852Y635354D02*
Y712354D01*
G01X1011602Y628479D02*
X1026727D01*
G01X1011602Y635354D02*
Y628479D01*
G01X1061102D02*
Y635354D01*
G01X1045977Y628479D02*
X1061102D01*
G01X1045977Y719229D02*
Y628479D01*
G01X1052852Y712354D02*
Y635354D01*
G01D02*
X1096852D01*
G01X1026727Y628479D02*
Y719229D01*
G01X1019852Y635354D02*
Y712354D01*
G01X1011602Y628479D02*
X1026727D01*
G01X1011602Y635354D02*
Y628479D01*
G01X1061102Y719229D02*
X1045977D01*
G01X1061102Y712354D02*
Y719229D01*
G01X1096852Y712354D02*
X1052852D01*
G01X1011602Y719229D02*
Y712354D01*
G01X1026727Y719229D02*
X1011602D01*
G01X1061102D02*
X1045977D01*
G01X1061102Y712354D02*
Y719229D01*
G01X1096852Y712354D02*
X1052852D01*
G01X1011602Y719229D02*
Y712354D01*
G01X1026727Y719229D02*
X1011602D01*
G01X1129852Y712354D02*
Y635354D01*
G01D02*
X1173852D01*
G01X1138102Y628479D02*
Y635354D01*
G01X1122977Y628479D02*
X1138102D01*
G01X1096852Y635354D02*
Y712354D01*
G01X1088602Y628479D02*
X1122977D01*
G01X1088602Y635354D02*
Y628479D01*
G01X1129852Y712354D02*
Y635354D01*
G01D02*
X1173852D01*
G01X1138102Y628479D02*
Y635354D01*
G01X1122977Y628479D02*
X1138102D01*
G01X1096852Y635354D02*
Y712354D01*
G01X1088602Y628479D02*
X1122977D01*
G01X1088602Y635354D02*
Y628479D01*
G01X1173852Y712354D02*
X1129852D01*
G01X1138102D02*
Y719229D01*
G01D02*
X1103727D01*
G01X1088602D02*
Y712354D01*
G01X1103727Y719229D02*
X1088602D01*
G01X1173852Y712354D02*
X1129852D01*
G01X1138102D02*
Y719229D01*
G01D02*
X1103727D01*
G01X1088602D02*
Y712354D01*
G01X1103727Y719229D02*
X1088602D01*
G01X1215102Y628479D02*
Y635354D01*
G01X1206852Y712354D02*
Y635354D01*
G01D02*
X1250852D01*
G01X1199977Y628479D02*
X1215102D01*
G01X1199977Y719229D02*
Y628479D01*
G01X1180727D02*
Y719229D01*
G01X1165602Y628479D02*
X1180727D01*
G01X1165602Y635354D02*
Y628479D01*
G01X1173852Y635354D02*
Y712354D01*
G01X1215102Y628479D02*
Y635354D01*
G01X1206852Y712354D02*
Y635354D01*
G01D02*
X1250852D01*
G01X1199977Y628479D02*
X1215102D01*
G01X1199977Y719229D02*
Y628479D01*
G01X1180727D02*
Y719229D01*
G01X1165602Y628479D02*
X1180727D01*
G01X1165602Y635354D02*
Y628479D01*
G01X1173852Y635354D02*
Y712354D01*
G01X1215102D02*
Y719229D01*
G01X1250852Y712354D02*
X1206852D01*
G01X1215102Y719229D02*
X1199977D01*
G01X1165602D02*
Y712354D01*
G01X1180727Y719229D02*
X1165602D01*
G01X1215102Y712354D02*
Y719229D01*
G01X1250852Y712354D02*
X1206852D01*
G01X1215102Y719229D02*
X1199977D01*
G01X1165602D02*
Y712354D01*
G01X1180727Y719229D02*
X1165602D01*
G01X1250852Y635354D02*
Y712354D01*
G01Y635354D02*
Y712354D01*
G54D13*
G01X341590Y319830D02*
Y303830D01*
G01X303090Y319830D02*
Y303830D01*
G01X345680Y327680D02*
G02X350362Y319860I-4190J-7820D01*
G01X348190Y321780D01*
X351420Y321950D01*
X350460Y319850D01*
G01X341590Y319830D02*
Y303830D01*
G01X303090Y319830D02*
Y303830D01*
G01X345680Y327680D02*
G02X350362Y319860I-4190J-7820D01*
G01X348190Y321780D01*
X351420Y321950D01*
X350460Y319850D01*
G01X292090Y340830D02*
Y357830D01*
G01Y340830D02*
Y357830D01*
G01X356482Y330153D02*
X352452Y324663D01*
X356652Y324643D01*
G01X356482Y330153D02*
X352452Y324663D01*
X356652Y324643D01*
G01X352590Y340830D02*
Y357830D01*
G01Y340830D02*
Y357830D01*
G01X439562Y301543D02*
X435532Y296053D01*
X439732Y296033D01*
G01X439562Y301543D02*
X435532Y296053D01*
X439732Y296033D01*
G54D14*
G01X891779Y725829D02*
X949925D01*
G01X919754Y712629D02*
X906554Y725829D01*
G01X917420Y712629D02*
X904221Y725829D01*
G01X915087Y712629D02*
X901887Y725829D01*
G01X912754Y712629D02*
X907377Y718006D01*
G01X905840Y719543D02*
X899554Y725829D01*
G01X910421Y712629D02*
X907377Y715673D01*
G01X903507Y719543D02*
X897221Y725829D01*
G01X908086Y712629D02*
X907377Y713339D01*
G01X901173Y719543D02*
X894886Y725829D01*
G01X898840Y719543D02*
X892553Y725829D01*
G01X896507Y719543D02*
X891342Y724707D01*
G01X894172Y719543D02*
X890494Y723221D01*
G01X891927Y719455D02*
X889440Y721942D01*
G01X891702Y717347D02*
X888191Y720857D01*
G01X891702Y715014D02*
X886738Y719977D01*
G01X891702Y712680D02*
X885053Y719328D01*
G01X891702Y710347D02*
X883070Y718978D01*
G01X891702Y708014D02*
X880607Y719107D01*
G01X907377Y713613D02*
X919592Y725828D01*
G01X907377Y715946D02*
X917259Y725829D01*
G01X907377Y718280D02*
X914926Y725829D01*
G01X906307Y719543D02*
X912592Y725828D01*
G01X903972Y719543D02*
X910259Y725829D01*
G01X901639Y719543D02*
X907926Y725829D01*
G01X899306Y719543D02*
X905593Y725829D01*
G01X896972Y719543D02*
X903258Y725829D01*
G01X894639Y719543D02*
X900925Y725829D01*
G01X892306Y719543D02*
X898592Y725829D01*
G01X892015Y719543D02*
X891702Y719229D01*
G01X907157Y719543D02*
X892015D01*
G01X907377Y719504D02*
X907157Y719543D01*
G01X907377Y712629D02*
Y719504D01*
G01X934327Y712629D02*
X907377D01*
G01X891702Y675345D02*
X891096Y675951D01*
G01X890957Y676193D02*
X891702Y676936D01*
G01X889988Y677557D02*
X891702Y679270D01*
G01X888823Y678725D02*
X891702Y681604D01*
G01X887462Y679697D02*
X891702Y683937D01*
G01X885887Y680455D02*
X891702Y686270D01*
G01X884054Y680956D02*
X891702Y688604D01*
G01X881854Y681089D02*
X891702Y690937D01*
G01Y674644D02*
X891701Y674645D01*
G01X891702Y719229D02*
Y674644D01*
G01X856340Y725829D02*
X872925D01*
G01X891702Y705679D02*
X876553Y720829D01*
G01X874327Y723054D02*
X871552Y725829D01*
G01X891702Y703346D02*
X869219Y725829D01*
G01X891702Y701013D02*
X866886Y725829D01*
G01X891702Y698679D02*
X873002Y717379D01*
G01X871152Y719229D02*
X864552Y725829D01*
G01X891702Y696346D02*
X873002Y715046D01*
G01X868819Y719229D02*
X862219Y725829D01*
G01X891702Y694013D02*
X873002Y712712D01*
G01X866485Y719229D02*
X859885Y725829D01*
G01X891702Y691679D02*
X873002Y710379D01*
G01X864151Y719229D02*
X857551Y725829D01*
G01X891702Y689346D02*
X873002Y708046D01*
G01X861818Y719229D02*
X855779Y725267D01*
G01X891702Y687012D02*
X873002Y705711D01*
G01X859485Y719229D02*
X854613Y724101D01*
G01X891702Y684678D02*
X873002Y703378D01*
G01X857327Y719053D02*
X853752Y722628D01*
G01X891702Y682345D02*
X873002Y701045D01*
G01X857327Y716720D02*
X853752Y720295D01*
G01X891702Y680012D02*
X873002Y698711D01*
G01X857327Y714387D02*
X853752Y717961D01*
G01X856750Y712629D02*
X853752Y715628D01*
G01X854417Y712629D02*
X853752Y713295D01*
G01X873002Y690905D02*
X891702Y709604D01*
G01X873002Y693238D02*
X891702Y711938D01*
G01X873002Y695572D02*
X891702Y714272D01*
G01X873002Y697906D02*
X891702Y716605D01*
G01X873002Y700239D02*
X891702Y718939D01*
G01X873002Y702572D02*
X896258Y725829D01*
G01X873002Y704906D02*
X893925Y725829D01*
G01X873002Y707239D02*
X885106Y719344D01*
G01X873002Y709572D02*
X882382Y718952D01*
G01X873002Y711907D02*
X880270Y719174D01*
G01X873002Y714240D02*
X878496Y719734D01*
G01X873002Y716573D02*
X876971Y720542D01*
G01X873002Y718907D02*
X875655Y721560D01*
G01X870991Y719229D02*
X874536Y722775D01*
G01X868658Y719229D02*
X873618Y724189D01*
G01X866324Y719229D02*
X872924Y725829D01*
G01X863991Y719229D02*
X870591Y725829D01*
G01X855058Y712629D02*
X857327Y714899D01*
G01X861658Y719229D02*
X868258Y725829D01*
G01X853752Y713657D02*
X857327Y717232D01*
G01X859323Y719229D02*
X865923Y725829D01*
G01X853752Y715991D02*
X863590Y725829D01*
G01X853752Y718324D02*
X861257Y725829D01*
G01X853752Y720657D02*
X858923Y725829D01*
G01X853752Y722991D02*
X856590Y725829D01*
G01X872925D02*
G03X891779I9427J3024D01*
G01X853752Y723240D02*
X856340Y725829D01*
G01X853752Y712629D02*
Y723240D01*
G01X857327Y712629D02*
X853752D01*
G01X857327Y719504D02*
Y712629D01*
G01X857602Y719229D02*
X857327Y719504D01*
G01X873002Y719229D02*
X857602D01*
G01X891702Y677678D02*
X873002Y696378D01*
G01X887198Y679848D02*
X873002Y694045D01*
G01X883703Y681010D02*
X873002Y691711D01*
G01X881330Y681049D02*
X873002Y689377D01*
G01X879392Y680653D02*
X873002Y687044D01*
G01X877738Y679974D02*
X873002Y684711D01*
G01X876310Y679069D02*
X873002Y682377D01*
G01X875080Y677966D02*
X873002Y680044D01*
G01X874045Y676668D02*
X873002Y677711D01*
G01X873215Y675163D02*
X873002Y675377D01*
G01X878929Y680497D02*
X891702Y693270D01*
G01X873002Y676905D02*
X891702Y695603D01*
G01X873002Y679238D02*
X891702Y697938D01*
G01X873002Y681571D02*
X891702Y700271D01*
G01X873002Y683905D02*
X891702Y702604D01*
G01X873002Y686238D02*
X891702Y704938D01*
G01X873002Y688571D02*
X891702Y707271D01*
G01X873002Y674644D02*
Y719229D01*
G01Y674645D02*
Y674644D01*
G01X891701Y674645D02*
G03X873003I-9349J-3541D01*
G01X891779Y725829D02*
X949925D01*
G01X919754Y712629D02*
X906554Y725829D01*
G01X917420Y712629D02*
X904221Y725829D01*
G01X915087Y712629D02*
X901887Y725829D01*
G01X912754Y712629D02*
X907377Y718006D01*
G01X905840Y719543D02*
X899554Y725829D01*
G01X910421Y712629D02*
X907377Y715673D01*
G01X903507Y719543D02*
X897221Y725829D01*
G01X908086Y712629D02*
X907377Y713339D01*
G01X901173Y719543D02*
X894886Y725829D01*
G01X898840Y719543D02*
X892553Y725829D01*
G01X896507Y719543D02*
X891342Y724707D01*
G01X894172Y719543D02*
X890494Y723221D01*
G01X891927Y719455D02*
X889440Y721942D01*
G01X891702Y717347D02*
X888191Y720857D01*
G01X891702Y715014D02*
X886738Y719977D01*
G01X891702Y712680D02*
X885053Y719328D01*
G01X891702Y710347D02*
X883070Y718978D01*
G01X891702Y708014D02*
X880607Y719107D01*
G01X907377Y713613D02*
X919592Y725828D01*
G01X907377Y715946D02*
X917259Y725829D01*
G01X907377Y718280D02*
X914926Y725829D01*
G01X906307Y719543D02*
X912592Y725828D01*
G01X903972Y719543D02*
X910259Y725829D01*
G01X901639Y719543D02*
X907926Y725829D01*
G01X899306Y719543D02*
X905593Y725829D01*
G01X896972Y719543D02*
X903258Y725829D01*
G01X894639Y719543D02*
X900925Y725829D01*
G01X892306Y719543D02*
X898592Y725829D01*
G01X892015Y719543D02*
X891702Y719229D01*
G01X907157Y719543D02*
X892015D01*
G01X907377Y719504D02*
X907157Y719543D01*
G01X907377Y712629D02*
Y719504D01*
G01X934327Y712629D02*
X907377D01*
G01X891702Y675345D02*
X891096Y675951D01*
G01X890957Y676193D02*
X891702Y676936D01*
G01X889988Y677557D02*
X891702Y679270D01*
G01X888823Y678725D02*
X891702Y681604D01*
G01X887462Y679697D02*
X891702Y683937D01*
G01X885887Y680455D02*
X891702Y686270D01*
G01X884054Y680956D02*
X891702Y688604D01*
G01X881854Y681089D02*
X891702Y690937D01*
G01Y674644D02*
X891701Y674645D01*
G01X891702Y719229D02*
Y674644D01*
G01X856340Y725829D02*
X872925D01*
G01X891702Y705679D02*
X876553Y720829D01*
G01X874327Y723054D02*
X871552Y725829D01*
G01X891702Y703346D02*
X869219Y725829D01*
G01X891702Y701013D02*
X866886Y725829D01*
G01X891702Y698679D02*
X873002Y717379D01*
G01X871152Y719229D02*
X864552Y725829D01*
G01X891702Y696346D02*
X873002Y715046D01*
G01X868819Y719229D02*
X862219Y725829D01*
G01X891702Y694013D02*
X873002Y712712D01*
G01X866485Y719229D02*
X859885Y725829D01*
G01X891702Y691679D02*
X873002Y710379D01*
G01X864151Y719229D02*
X857551Y725829D01*
G01X891702Y689346D02*
X873002Y708046D01*
G01X861818Y719229D02*
X855779Y725267D01*
G01X891702Y687012D02*
X873002Y705711D01*
G01X859485Y719229D02*
X854613Y724101D01*
G01X891702Y684678D02*
X873002Y703378D01*
G01X857327Y719053D02*
X853752Y722628D01*
G01X891702Y682345D02*
X873002Y701045D01*
G01X857327Y716720D02*
X853752Y720295D01*
G01X891702Y680012D02*
X873002Y698711D01*
G01X857327Y714387D02*
X853752Y717961D01*
G01X856750Y712629D02*
X853752Y715628D01*
G01X854417Y712629D02*
X853752Y713295D01*
G01X873002Y690905D02*
X891702Y709604D01*
G01X873002Y693238D02*
X891702Y711938D01*
G01X873002Y695572D02*
X891702Y714272D01*
G01X873002Y697906D02*
X891702Y716605D01*
G01X873002Y700239D02*
X891702Y718939D01*
G01X873002Y702572D02*
X896258Y725829D01*
G01X873002Y704906D02*
X893925Y725829D01*
G01X873002Y707239D02*
X885106Y719344D01*
G01X873002Y709572D02*
X882382Y718952D01*
G01X873002Y711907D02*
X880270Y719174D01*
G01X873002Y714240D02*
X878496Y719734D01*
G01X873002Y716573D02*
X876971Y720542D01*
G01X873002Y718907D02*
X875655Y721560D01*
G01X870991Y719229D02*
X874536Y722775D01*
G01X868658Y719229D02*
X873618Y724189D01*
G01X866324Y719229D02*
X872924Y725829D01*
G01X863991Y719229D02*
X870591Y725829D01*
G01X855058Y712629D02*
X857327Y714899D01*
G01X861658Y719229D02*
X868258Y725829D01*
G01X853752Y713657D02*
X857327Y717232D01*
G01X859323Y719229D02*
X865923Y725829D01*
G01X853752Y715991D02*
X863590Y725829D01*
G01X853752Y718324D02*
X861257Y725829D01*
G01X853752Y720657D02*
X858923Y725829D01*
G01X853752Y722991D02*
X856590Y725829D01*
G01X872925D02*
G03X891779I9427J3024D01*
G01X853752Y723240D02*
X856340Y725829D01*
G01X853752Y712629D02*
Y723240D01*
G01X857327Y712629D02*
X853752D01*
G01X857327Y719504D02*
Y712629D01*
G01X857602Y719229D02*
X857327Y719504D01*
G01X873002Y719229D02*
X857602D01*
G01X891702Y677678D02*
X873002Y696378D01*
G01X887198Y679848D02*
X873002Y694045D01*
G01X883703Y681010D02*
X873002Y691711D01*
G01X881330Y681049D02*
X873002Y689377D01*
G01X879392Y680653D02*
X873002Y687044D01*
G01X877738Y679974D02*
X873002Y684711D01*
G01X876310Y679069D02*
X873002Y682377D01*
G01X875080Y677966D02*
X873002Y680044D01*
G01X874045Y676668D02*
X873002Y677711D01*
G01X873215Y675163D02*
X873002Y675377D01*
G01X878929Y680497D02*
X891702Y693270D01*
G01X873002Y676905D02*
X891702Y695603D01*
G01X873002Y679238D02*
X891702Y697938D01*
G01X873002Y681571D02*
X891702Y700271D01*
G01X873002Y683905D02*
X891702Y702604D01*
G01X873002Y686238D02*
X891702Y704938D01*
G01X873002Y688571D02*
X891702Y707271D01*
G01X873002Y674644D02*
Y719229D01*
G01Y674645D02*
Y674644D01*
G01X891701Y674645D02*
G03X873003I-9349J-3541D01*
G01X987952Y632764D02*
X985637Y635078D01*
G01X987952Y630431D02*
X984377Y634006D01*
G01X987952Y628098D02*
X984377Y631673D01*
G01X987225Y626490D02*
X984377Y629338D01*
G01X986058Y625324D02*
X983178Y628204D01*
G01X984377Y629605D02*
X987952Y633180D01*
G01X984377Y631938D02*
X987517Y635079D01*
G01X984377Y634272D02*
X985184Y635079D01*
G01X984377D02*
X987952D01*
G01X984377Y628204D02*
Y635079D01*
G01X984420Y624629D02*
X980845Y628204D01*
G01X984069Y624629D02*
X987952Y628512D01*
G01X981735Y624629D02*
X987952Y630845D01*
G01X979402Y624629D02*
X982977Y628204D01*
G01X987952Y627218D02*
X985362Y624629D01*
G01X968702Y659014D02*
X950002Y677714D01*
G01Y658233D02*
X968702Y676932D01*
G01Y656681D02*
X950002Y675381D01*
G01X968702Y654348D02*
X950002Y673048D01*
G01X968702Y652014D02*
X950002Y670714D01*
G01X968702Y649681D02*
X950002Y668381D01*
G01X968702Y647348D02*
X950002Y666048D01*
G01X968702Y645013D02*
X950002Y663713D01*
G01X968702Y642680D02*
X950002Y661380D01*
G01X968702Y640347D02*
X950002Y659047D01*
G01X982086Y624629D02*
X978512Y628204D01*
G01X968702Y638014D02*
X950002Y656713D01*
G01X979752Y624629D02*
X976177Y628204D01*
G01X968702Y635680D02*
X950002Y654380D01*
G01X968702Y633347D02*
X950002Y652047D01*
G01X968702Y631014D02*
X950002Y649713D01*
G01X968702Y628679D02*
X950002Y647379D01*
G01Y630232D02*
X968702Y648932D01*
G01X950002Y632565D02*
X968702Y651265D01*
G01X950002Y634898D02*
X968702Y653598D01*
G01X950002Y637232D02*
X968702Y655931D01*
G01X950002Y639565D02*
X968702Y658265D01*
G01X950002Y641898D02*
X968702Y660598D01*
G01X950002Y644232D02*
X968702Y662931D01*
G01X950002Y646565D02*
X968702Y665265D01*
G01X950002Y648899D02*
X968702Y667599D01*
G01X950002Y651233D02*
X968702Y669932D01*
G01X950002Y653566D02*
X968702Y672266D01*
G01X950002Y655899D02*
X968702Y674599D01*
G01Y628204D02*
X984377D01*
G01X968702Y719504D02*
Y628204D01*
G01X950002D02*
Y719504D01*
G01X977419Y624629D02*
X973844Y628204D01*
G01X975085Y624629D02*
X971511Y628204D01*
G01X972752Y624629D02*
X969177Y628204D01*
G01X970419Y624629D02*
X950002Y645046D01*
G01X968086Y624629D02*
X950002Y642712D01*
G01X965752Y624629D02*
X950002Y640379D01*
G01X963419Y624629D02*
X950002Y638046D01*
G01X961085Y624629D02*
X950002Y635712D01*
G01X958751Y624629D02*
X950002Y633379D01*
G01X956418Y624629D02*
X950002Y631046D01*
G01X954085Y624629D02*
X950002Y628711D01*
G01X951751Y624629D02*
X948176Y628204D01*
G01X977068Y624629D02*
X980642Y628204D01*
G01X974734Y624629D02*
X978309Y628204D01*
G01X972401Y624629D02*
X975976Y628204D01*
G01X970068Y624629D02*
X973643Y628204D01*
G01X967734Y624629D02*
X971309Y628204D01*
G01X965401Y624629D02*
X968976Y628204D01*
G01X963068Y624629D02*
X968702Y630263D01*
G01X960733Y624629D02*
X968702Y632597D01*
G01X958400Y624629D02*
X968702Y634931D01*
G01X956067Y624629D02*
X968702Y637264D01*
G01X953733Y624629D02*
X968702Y639597D01*
G01X951400Y624629D02*
X968702Y641931D01*
G01X949067Y624629D02*
X968702Y644264D01*
G01X946733Y624629D02*
X968702Y646597D01*
G01X949418Y624629D02*
X945843Y628204D01*
G01X947085Y624629D02*
X943510Y628204D01*
G01X934327Y635053D02*
X934300Y635079D01*
G01X934327Y632720D02*
X931967Y635079D01*
G01X934327Y630387D02*
X930752Y633961D01*
G01X933037Y624933D02*
X936307Y628204D01*
G01X931869Y626100D02*
X934327Y628556D01*
G01X930752Y627315D02*
X934327Y630890D01*
G01X930752Y629649D02*
X934327Y633224D01*
G01X930752Y631983D02*
X933848Y635079D01*
G01X930752Y634316D02*
X931515Y635079D01*
G01X934327Y628204D02*
X950002D01*
G01X934327Y635079D02*
Y628204D01*
G01X930752Y635079D02*
X934327D01*
G01X930752Y627218D02*
Y635079D01*
G01X944750Y624629D02*
X941175Y628204D01*
G01X942417Y624629D02*
X938842Y628204D01*
G01X940084Y624629D02*
X936509Y628204D01*
G01X937750Y624629D02*
X930752Y631627D01*
G01X935417Y624629D02*
X930752Y629294D01*
G01X944400Y624629D02*
X947975Y628204D01*
G01X942066Y624629D02*
X945640Y628203D01*
G01X939733Y624629D02*
X943307Y628204D01*
G01X937399Y624629D02*
X940974Y628203D01*
G01X935066Y624629D02*
X938640Y628203D01*
G01X985362Y624629D02*
X933340D01*
G01D02*
X930752Y627218D01*
G01X987952Y632764D02*
X985637Y635078D01*
G01X987952Y630431D02*
X984377Y634006D01*
G01X987952Y628098D02*
X984377Y631673D01*
G01X987225Y626490D02*
X984377Y629338D01*
G01X986058Y625324D02*
X983178Y628204D01*
G01X984377Y629605D02*
X987952Y633180D01*
G01X984377Y631938D02*
X987517Y635079D01*
G01X984377Y634272D02*
X985184Y635079D01*
G01X984377D02*
X987952D01*
G01X984377Y628204D02*
Y635079D01*
G01X984420Y624629D02*
X980845Y628204D01*
G01X984069Y624629D02*
X987952Y628512D01*
G01X981735Y624629D02*
X987952Y630845D01*
G01X979402Y624629D02*
X982977Y628204D01*
G01X987952Y627218D02*
X985362Y624629D01*
G01X968702Y659014D02*
X950002Y677714D01*
G01Y658233D02*
X968702Y676932D01*
G01Y656681D02*
X950002Y675381D01*
G01X968702Y654348D02*
X950002Y673048D01*
G01X968702Y652014D02*
X950002Y670714D01*
G01X968702Y649681D02*
X950002Y668381D01*
G01X968702Y647348D02*
X950002Y666048D01*
G01X968702Y645013D02*
X950002Y663713D01*
G01X968702Y642680D02*
X950002Y661380D01*
G01X968702Y640347D02*
X950002Y659047D01*
G01X982086Y624629D02*
X978512Y628204D01*
G01X968702Y638014D02*
X950002Y656713D01*
G01X979752Y624629D02*
X976177Y628204D01*
G01X968702Y635680D02*
X950002Y654380D01*
G01X968702Y633347D02*
X950002Y652047D01*
G01X968702Y631014D02*
X950002Y649713D01*
G01X968702Y628679D02*
X950002Y647379D01*
G01Y630232D02*
X968702Y648932D01*
G01X950002Y632565D02*
X968702Y651265D01*
G01X950002Y634898D02*
X968702Y653598D01*
G01X950002Y637232D02*
X968702Y655931D01*
G01X950002Y639565D02*
X968702Y658265D01*
G01X950002Y641898D02*
X968702Y660598D01*
G01X950002Y644232D02*
X968702Y662931D01*
G01X950002Y646565D02*
X968702Y665265D01*
G01X950002Y648899D02*
X968702Y667599D01*
G01X950002Y651233D02*
X968702Y669932D01*
G01X950002Y653566D02*
X968702Y672266D01*
G01X950002Y655899D02*
X968702Y674599D01*
G01Y628204D02*
X984377D01*
G01X968702Y719504D02*
Y628204D01*
G01X950002D02*
Y719504D01*
G01X977419Y624629D02*
X973844Y628204D01*
G01X975085Y624629D02*
X971511Y628204D01*
G01X972752Y624629D02*
X969177Y628204D01*
G01X970419Y624629D02*
X950002Y645046D01*
G01X968086Y624629D02*
X950002Y642712D01*
G01X965752Y624629D02*
X950002Y640379D01*
G01X963419Y624629D02*
X950002Y638046D01*
G01X961085Y624629D02*
X950002Y635712D01*
G01X958751Y624629D02*
X950002Y633379D01*
G01X956418Y624629D02*
X950002Y631046D01*
G01X954085Y624629D02*
X950002Y628711D01*
G01X951751Y624629D02*
X948176Y628204D01*
G01X977068Y624629D02*
X980642Y628204D01*
G01X974734Y624629D02*
X978309Y628204D01*
G01X972401Y624629D02*
X975976Y628204D01*
G01X970068Y624629D02*
X973643Y628204D01*
G01X967734Y624629D02*
X971309Y628204D01*
G01X965401Y624629D02*
X968976Y628204D01*
G01X963068Y624629D02*
X968702Y630263D01*
G01X960733Y624629D02*
X968702Y632597D01*
G01X958400Y624629D02*
X968702Y634931D01*
G01X956067Y624629D02*
X968702Y637264D01*
G01X953733Y624629D02*
X968702Y639597D01*
G01X951400Y624629D02*
X968702Y641931D01*
G01X949067Y624629D02*
X968702Y644264D01*
G01X946733Y624629D02*
X968702Y646597D01*
G01X949418Y624629D02*
X945843Y628204D01*
G01X947085Y624629D02*
X943510Y628204D01*
G01X934327Y635053D02*
X934300Y635079D01*
G01X934327Y632720D02*
X931967Y635079D01*
G01X934327Y630387D02*
X930752Y633961D01*
G01X933037Y624933D02*
X936307Y628204D01*
G01X931869Y626100D02*
X934327Y628556D01*
G01X930752Y627315D02*
X934327Y630890D01*
G01X930752Y629649D02*
X934327Y633224D01*
G01X930752Y631983D02*
X933848Y635079D01*
G01X930752Y634316D02*
X931515Y635079D01*
G01X934327Y628204D02*
X950002D01*
G01X934327Y635079D02*
Y628204D01*
G01X930752Y635079D02*
X934327D01*
G01X930752Y627218D02*
Y635079D01*
G01X944750Y624629D02*
X941175Y628204D01*
G01X942417Y624629D02*
X938842Y628204D01*
G01X940084Y624629D02*
X936509Y628204D01*
G01X937750Y624629D02*
X930752Y631627D01*
G01X935417Y624629D02*
X930752Y629294D01*
G01X944400Y624629D02*
X947975Y628204D01*
G01X942066Y624629D02*
X945640Y628203D01*
G01X939733Y624629D02*
X943307Y628204D01*
G01X937399Y624629D02*
X940974Y628203D01*
G01X935066Y624629D02*
X938640Y628203D01*
G01X985362Y624629D02*
X933340D01*
G01D02*
X930752Y627218D01*
G01X987952Y721436D02*
X983558Y725829D01*
G01X987952Y719102D02*
X981224Y725829D01*
G01X987952Y714435D02*
X984377Y718009D01*
G01X987424Y712629D02*
X984377Y715676D01*
G01X985091Y712629D02*
X984377Y713343D01*
G01X985731Y712629D02*
X987952Y714850D01*
G01X984377Y713608D02*
X987952Y717183D01*
G01X984377Y715942D02*
X987952Y719517D01*
G01X984377Y718276D02*
X987952Y721851D01*
G01X983271Y719504D02*
X987480Y723712D01*
G01X980938Y719504D02*
X986313Y724879D01*
G01X984377Y712629D02*
Y719504D01*
G01X987952Y712629D02*
X984377D01*
G01X985362Y725829D02*
X987952Y723240D01*
G01Y716769D02*
X978891Y725829D01*
G01X968779D02*
X985362D01*
G01X982883Y719504D02*
X976558Y725829D01*
G01X980549Y719504D02*
X974224Y725829D01*
G01X978216Y719504D02*
X971891Y725829D01*
G01X975883Y719504D02*
X969558Y725829D01*
G01X973548Y719504D02*
X968343Y724709D01*
G01X971215Y719504D02*
X967496Y723223D01*
G01X968882Y719504D02*
X966442Y721943D01*
G01X968702Y717350D02*
X965193Y720859D01*
G01X968702Y715017D02*
X963741Y719978D01*
G01X968702Y712684D02*
X962057Y719329D01*
G01X968702Y710350D02*
X960073Y718978D01*
G01X968702Y708017D02*
X957613Y719106D01*
G01X968702Y705684D02*
X953567Y720819D01*
G01X951317Y723067D02*
X948556Y725829D01*
G01X968702Y698683D02*
X950002Y717383D01*
G01X968702Y696350D02*
X950002Y715049D01*
G01X968702Y694016D02*
X950002Y712716D01*
G01X968702Y691683D02*
X950002Y710383D01*
G01Y690901D02*
X968702Y709601D01*
G01X978605Y719504D02*
X984930Y725829D01*
G01X950002Y693234D02*
X968702Y711934D01*
G01X976271Y719504D02*
X982596Y725829D01*
G01X950002Y695568D02*
X968702Y714267D01*
G01X973938Y719504D02*
X980263Y725829D01*
G01X950002Y697901D02*
X968702Y716601D01*
G01X971605Y719504D02*
X977930Y725829D01*
G01X950002Y700234D02*
X968702Y718934D01*
G01X969271Y719504D02*
X975596Y725829D01*
G01X950002Y702569D02*
X973262Y725828D01*
G01X950002Y704902D02*
X970929Y725829D01*
G01X950002Y707235D02*
X962112Y719345D01*
G01X950002Y709569D02*
X959386Y718952D01*
G01X950002Y711902D02*
X957273Y719173D01*
G01X950002Y714235D02*
X955499Y719733D01*
G01X950002Y716569D02*
X953974Y720540D01*
G01X950002Y718903D02*
X952657Y721558D01*
G01X948269Y719504D02*
X951539Y722772D01*
G01X984377Y719504D02*
X968702D01*
G01X949925Y725829D02*
G03X968779I9427J3024D01*
G01X968702Y689350D02*
X950002Y708049D01*
G01X968702Y687016D02*
X950002Y705716D01*
G01X968702Y684683D02*
X950002Y703383D01*
G01X968702Y682350D02*
X950002Y701048D01*
G01X968702Y680015D02*
X950002Y698715D01*
G01X968702Y677682D02*
X950002Y696382D01*
G01X968702Y675349D02*
X950002Y694048D01*
G01X968702Y673015D02*
X950002Y691715D01*
G01X968702Y670682D02*
X950002Y689382D01*
G01X968702Y668349D02*
X950002Y687048D01*
G01X968702Y666015D02*
X950002Y684715D01*
G01X968702Y663681D02*
X950002Y682381D01*
G01X968702Y661348D02*
X950002Y680047D01*
G01Y660566D02*
X968702Y679266D01*
G01X950002Y662899D02*
X968702Y681599D01*
G01X950002Y665234D02*
X968702Y683932D01*
G01X950002Y667567D02*
X968702Y686267D01*
G01X950002Y669900D02*
X968702Y688600D01*
G01X950002Y672234D02*
X968702Y690933D01*
G01X950002Y674567D02*
X968702Y693267D01*
G01X950002Y676900D02*
X968702Y695600D01*
G01X950002Y679233D02*
X968702Y697933D01*
G01X950002Y681567D02*
X968702Y700267D01*
G01X950002Y683901D02*
X968702Y702601D01*
G01X950002Y686234D02*
X968702Y704934D01*
G01X950002Y688568D02*
X968702Y707268D01*
G01Y703350D02*
X946222Y725829D01*
G01X968702Y701017D02*
X943889Y725829D01*
G01X947881Y719504D02*
X941556Y725829D01*
G01X945548Y719504D02*
X939223Y725829D01*
G01X943214Y719504D02*
X936889Y725829D01*
G01X940881Y719504D02*
X934556Y725829D01*
G01X938546Y719504D02*
X932223Y725829D01*
G01X936213Y719504D02*
X929888Y725829D01*
G01X934327Y719058D02*
X927555Y725829D01*
G01X934327Y716725D02*
X925222Y725829D01*
G01X934327Y714390D02*
X922888Y725829D01*
G01X933755Y712629D02*
X920555Y725829D01*
G01X931422Y712629D02*
X918222Y725829D01*
G01X929088Y712629D02*
X915888Y725829D01*
G01X926754Y712629D02*
X913554Y725829D01*
G01X945936Y719504D02*
X950619Y724187D01*
G01X943603Y719504D02*
X949925Y725826D01*
G01X941270Y719504D02*
X947595Y725829D01*
G01X932061Y712629D02*
X934327Y714894D01*
G01X938936Y719504D02*
X945261Y725829D01*
G01X929728Y712629D02*
X934327Y717228D01*
G01X936603Y719504D02*
X942928Y725829D01*
G01X927395Y712629D02*
X940595Y725829D01*
G01X925062Y712629D02*
X938260Y725829D01*
G01X922727Y712629D02*
X935927Y725829D01*
G01X920394Y712629D02*
X933594Y725829D01*
G01X918061Y712629D02*
X931260Y725829D01*
G01X915727Y712629D02*
X928927Y725829D01*
G01X913394Y712629D02*
X926593Y725828D01*
G01X934327Y719504D02*
Y712629D01*
G01X950002Y719504D02*
X934327D01*
G01X924420Y712629D02*
X911221Y725829D01*
G01X922087Y712629D02*
X908887Y725829D01*
G01X911061Y712629D02*
X924260Y725829D01*
G01X908727Y712629D02*
X921927Y725829D01*
G01X987952Y721436D02*
X983558Y725829D01*
G01X987952Y719102D02*
X981224Y725829D01*
G01X987952Y714435D02*
X984377Y718009D01*
G01X987424Y712629D02*
X984377Y715676D01*
G01X985091Y712629D02*
X984377Y713343D01*
G01X985731Y712629D02*
X987952Y714850D01*
G01X984377Y713608D02*
X987952Y717183D01*
G01X984377Y715942D02*
X987952Y719517D01*
G01X984377Y718276D02*
X987952Y721851D01*
G01X983271Y719504D02*
X987480Y723712D01*
G01X980938Y719504D02*
X986313Y724879D01*
G01X984377Y712629D02*
Y719504D01*
G01X987952Y712629D02*
X984377D01*
G01X985362Y725829D02*
X987952Y723240D01*
G01Y716769D02*
X978891Y725829D01*
G01X968779D02*
X985362D01*
G01X982883Y719504D02*
X976558Y725829D01*
G01X980549Y719504D02*
X974224Y725829D01*
G01X978216Y719504D02*
X971891Y725829D01*
G01X975883Y719504D02*
X969558Y725829D01*
G01X973548Y719504D02*
X968343Y724709D01*
G01X971215Y719504D02*
X967496Y723223D01*
G01X968882Y719504D02*
X966442Y721943D01*
G01X968702Y717350D02*
X965193Y720859D01*
G01X968702Y715017D02*
X963741Y719978D01*
G01X968702Y712684D02*
X962057Y719329D01*
G01X968702Y710350D02*
X960073Y718978D01*
G01X968702Y708017D02*
X957613Y719106D01*
G01X968702Y705684D02*
X953567Y720819D01*
G01X951317Y723067D02*
X948556Y725829D01*
G01X968702Y698683D02*
X950002Y717383D01*
G01X968702Y696350D02*
X950002Y715049D01*
G01X968702Y694016D02*
X950002Y712716D01*
G01X968702Y691683D02*
X950002Y710383D01*
G01Y690901D02*
X968702Y709601D01*
G01X978605Y719504D02*
X984930Y725829D01*
G01X950002Y693234D02*
X968702Y711934D01*
G01X976271Y719504D02*
X982596Y725829D01*
G01X950002Y695568D02*
X968702Y714267D01*
G01X973938Y719504D02*
X980263Y725829D01*
G01X950002Y697901D02*
X968702Y716601D01*
G01X971605Y719504D02*
X977930Y725829D01*
G01X950002Y700234D02*
X968702Y718934D01*
G01X969271Y719504D02*
X975596Y725829D01*
G01X950002Y702569D02*
X973262Y725828D01*
G01X950002Y704902D02*
X970929Y725829D01*
G01X950002Y707235D02*
X962112Y719345D01*
G01X950002Y709569D02*
X959386Y718952D01*
G01X950002Y711902D02*
X957273Y719173D01*
G01X950002Y714235D02*
X955499Y719733D01*
G01X950002Y716569D02*
X953974Y720540D01*
G01X950002Y718903D02*
X952657Y721558D01*
G01X948269Y719504D02*
X951539Y722772D01*
G01X984377Y719504D02*
X968702D01*
G01X949925Y725829D02*
G03X968779I9427J3024D01*
G01X968702Y689350D02*
X950002Y708049D01*
G01X968702Y687016D02*
X950002Y705716D01*
G01X968702Y684683D02*
X950002Y703383D01*
G01X968702Y682350D02*
X950002Y701048D01*
G01X968702Y680015D02*
X950002Y698715D01*
G01X968702Y677682D02*
X950002Y696382D01*
G01X968702Y675349D02*
X950002Y694048D01*
G01X968702Y673015D02*
X950002Y691715D01*
G01X968702Y670682D02*
X950002Y689382D01*
G01X968702Y668349D02*
X950002Y687048D01*
G01X968702Y666015D02*
X950002Y684715D01*
G01X968702Y663681D02*
X950002Y682381D01*
G01X968702Y661348D02*
X950002Y680047D01*
G01Y660566D02*
X968702Y679266D01*
G01X950002Y662899D02*
X968702Y681599D01*
G01X950002Y665234D02*
X968702Y683932D01*
G01X950002Y667567D02*
X968702Y686267D01*
G01X950002Y669900D02*
X968702Y688600D01*
G01X950002Y672234D02*
X968702Y690933D01*
G01X950002Y674567D02*
X968702Y693267D01*
G01X950002Y676900D02*
X968702Y695600D01*
G01X950002Y679233D02*
X968702Y697933D01*
G01X950002Y681567D02*
X968702Y700267D01*
G01X950002Y683901D02*
X968702Y702601D01*
G01X950002Y686234D02*
X968702Y704934D01*
G01X950002Y688568D02*
X968702Y707268D01*
G01Y703350D02*
X946222Y725829D01*
G01X968702Y701017D02*
X943889Y725829D01*
G01X947881Y719504D02*
X941556Y725829D01*
G01X945548Y719504D02*
X939223Y725829D01*
G01X943214Y719504D02*
X936889Y725829D01*
G01X940881Y719504D02*
X934556Y725829D01*
G01X938546Y719504D02*
X932223Y725829D01*
G01X936213Y719504D02*
X929888Y725829D01*
G01X934327Y719058D02*
X927555Y725829D01*
G01X934327Y716725D02*
X925222Y725829D01*
G01X934327Y714390D02*
X922888Y725829D01*
G01X933755Y712629D02*
X920555Y725829D01*
G01X931422Y712629D02*
X918222Y725829D01*
G01X929088Y712629D02*
X915888Y725829D01*
G01X926754Y712629D02*
X913554Y725829D01*
G01X945936Y719504D02*
X950619Y724187D01*
G01X943603Y719504D02*
X949925Y725826D01*
G01X941270Y719504D02*
X947595Y725829D01*
G01X932061Y712629D02*
X934327Y714894D01*
G01X938936Y719504D02*
X945261Y725829D01*
G01X929728Y712629D02*
X934327Y717228D01*
G01X936603Y719504D02*
X942928Y725829D01*
G01X927395Y712629D02*
X940595Y725829D01*
G01X925062Y712629D02*
X938260Y725829D01*
G01X922727Y712629D02*
X935927Y725829D01*
G01X920394Y712629D02*
X933594Y725829D01*
G01X918061Y712629D02*
X931260Y725829D01*
G01X915727Y712629D02*
X928927Y725829D01*
G01X913394Y712629D02*
X926593Y725828D01*
G01X934327Y719504D02*
Y712629D01*
G01X950002Y719504D02*
X934327D01*
G01X924420Y712629D02*
X911221Y725829D01*
G01X922087Y712629D02*
X908887Y725829D01*
G01X911061Y712629D02*
X924260Y725829D01*
G01X908727Y712629D02*
X921927Y725829D01*
G01X987952Y635079D02*
Y627218D01*
G01Y635079D02*
Y627218D01*
G01Y723240D02*
Y712629D01*
G01Y723240D02*
Y712629D01*
G01X1120658Y632879D02*
X1122702Y634922D01*
G01X1118325Y632879D02*
X1122702Y637256D01*
G01X1115991Y632879D02*
X1122702Y639589D01*
G01X1113658Y632879D02*
X1122702Y641922D01*
G01X1111325Y632879D02*
X1122702Y644257D01*
G01Y714829D02*
Y632879D01*
G01X1104002Y658224D02*
X1122702Y676924D01*
G01Y659023D02*
X1104002Y677722D01*
G01X1122702Y656689D02*
X1104002Y675389D01*
G01X1122702Y654356D02*
X1104002Y673056D01*
G01X1122702Y652023D02*
X1104002Y670721D01*
G01X1122702Y649688D02*
X1104002Y668388D01*
G01X1122702Y647355D02*
X1104002Y666055D01*
G01X1108990Y632879D02*
X1122702Y646590D01*
G01X1106657Y632879D02*
X1122702Y648923D01*
G01X1104324Y632879D02*
X1122702Y651257D01*
G01X1104002Y634890D02*
X1122702Y653590D01*
G01X1104002Y637224D02*
X1122702Y655923D01*
G01X1104002Y639557D02*
X1122702Y658257D01*
G01X1104002Y641890D02*
X1122702Y660590D01*
G01X1104002Y644225D02*
X1122702Y662924D01*
G01X1104002Y646558D02*
X1122702Y665258D01*
G01X1104002Y648891D02*
X1122702Y667591D01*
G01X1104002Y651225D02*
X1122702Y669924D01*
G01X1104002Y653558D02*
X1122702Y672258D01*
G01X1104002Y655891D02*
X1122702Y674591D01*
G01Y645022D02*
X1104002Y663721D01*
G01X1122702Y642688D02*
X1104002Y661388D01*
G01X1122702Y640355D02*
X1104002Y659055D01*
G01X1122702Y638022D02*
X1104002Y656721D01*
G01X1122702Y635688D02*
X1104002Y654388D01*
G01X1122702Y633354D02*
X1104002Y652054D01*
G01X1120844Y632879D02*
X1104002Y649720D01*
G01X1118510Y632879D02*
X1104002Y647387D01*
G01X1116177Y632879D02*
X1104002Y645054D01*
G01X1113844Y632879D02*
X1104002Y642720D01*
G01X1111509Y632879D02*
X1104002Y640387D01*
G01X1109176Y632879D02*
X1104002Y638054D01*
G01X1106843Y632879D02*
X1104002Y635721D01*
G01X1104509Y632879D02*
X1104002Y633386D01*
G01X1122702Y632879D02*
X1104002D01*
G01D02*
Y714829D01*
G01X1120658Y632879D02*
X1122702Y634922D01*
G01X1118325Y632879D02*
X1122702Y637256D01*
G01X1115991Y632879D02*
X1122702Y639589D01*
G01X1113658Y632879D02*
X1122702Y641922D01*
G01X1111325Y632879D02*
X1122702Y644257D01*
G01Y714829D02*
Y632879D01*
G01X1104002Y658224D02*
X1122702Y676924D01*
G01Y659023D02*
X1104002Y677722D01*
G01X1122702Y656689D02*
X1104002Y675389D01*
G01X1122702Y654356D02*
X1104002Y673056D01*
G01X1122702Y652023D02*
X1104002Y670721D01*
G01X1122702Y649688D02*
X1104002Y668388D01*
G01X1122702Y647355D02*
X1104002Y666055D01*
G01X1108990Y632879D02*
X1122702Y646590D01*
G01X1106657Y632879D02*
X1122702Y648923D01*
G01X1104324Y632879D02*
X1122702Y651257D01*
G01X1104002Y634890D02*
X1122702Y653590D01*
G01X1104002Y637224D02*
X1122702Y655923D01*
G01X1104002Y639557D02*
X1122702Y658257D01*
G01X1104002Y641890D02*
X1122702Y660590D01*
G01X1104002Y644225D02*
X1122702Y662924D01*
G01X1104002Y646558D02*
X1122702Y665258D01*
G01X1104002Y648891D02*
X1122702Y667591D01*
G01X1104002Y651225D02*
X1122702Y669924D01*
G01X1104002Y653558D02*
X1122702Y672258D01*
G01X1104002Y655891D02*
X1122702Y674591D01*
G01Y645022D02*
X1104002Y663721D01*
G01X1122702Y642688D02*
X1104002Y661388D01*
G01X1122702Y640355D02*
X1104002Y659055D01*
G01X1122702Y638022D02*
X1104002Y656721D01*
G01X1122702Y635688D02*
X1104002Y654388D01*
G01X1122702Y633354D02*
X1104002Y652054D01*
G01X1120844Y632879D02*
X1104002Y649720D01*
G01X1118510Y632879D02*
X1104002Y647387D01*
G01X1116177Y632879D02*
X1104002Y645054D01*
G01X1113844Y632879D02*
X1104002Y642720D01*
G01X1111509Y632879D02*
X1104002Y640387D01*
G01X1109176Y632879D02*
X1104002Y638054D01*
G01X1106843Y632879D02*
X1104002Y635721D01*
G01X1104509Y632879D02*
X1104002Y633386D01*
G01X1122702Y632879D02*
X1104002D01*
G01D02*
Y714829D01*
G01X1122702Y712692D02*
X1120565Y714829D01*
G01X1122702Y710359D02*
X1118231Y714829D01*
G01X1122702Y708025D02*
X1115897Y714829D01*
G01X1122702Y705692D02*
X1113564Y714829D01*
G01X1104002Y690893D02*
X1122702Y709593D01*
G01X1104002Y693226D02*
X1122702Y711926D01*
G01X1104002Y695561D02*
X1122702Y714259D01*
G01X1104002Y697894D02*
X1120937Y714829D01*
G01X1104002Y700227D02*
X1118604Y714829D01*
G01X1104002Y702561D02*
X1116270Y714829D01*
G01X1104002Y704894D02*
X1113937Y714829D01*
G01X1104002Y707227D02*
X1111604Y714829D01*
G01X1104002Y709561D02*
X1109270Y714829D01*
G01X1104002Y711894D02*
X1106937Y714829D01*
G01X1104002Y714228D02*
X1104604Y714829D01*
G01X1122702Y703358D02*
X1111231Y714829D01*
G01X1122702Y701024D02*
X1108897Y714829D01*
G01X1122702Y698691D02*
X1106564Y714829D01*
G01X1122702Y696358D02*
X1104231Y714829D01*
G01X1122702Y694024D02*
X1104002Y712724D01*
G01X1122702Y691691D02*
X1104002Y710391D01*
G01X1122702Y689358D02*
X1104002Y708057D01*
G01X1122702Y687023D02*
X1104002Y705723D01*
G01X1122702Y684690D02*
X1104002Y703390D01*
G01X1122702Y682357D02*
X1104002Y701056D01*
G01X1122702Y680023D02*
X1104002Y698723D01*
G01Y714829D02*
X1122702D01*
G01X1104002Y660559D02*
X1122702Y679259D01*
G01X1104002Y662892D02*
X1122702Y681592D01*
G01X1104002Y665225D02*
X1122702Y683925D01*
G01X1104002Y667559D02*
X1122702Y686258D01*
G01X1104002Y669892D02*
X1122702Y688592D01*
G01X1104002Y672225D02*
X1122702Y690925D01*
G01X1104002Y674559D02*
X1122702Y693258D01*
G01X1104002Y676892D02*
X1122702Y695592D01*
G01X1104002Y679226D02*
X1122702Y697926D01*
G01X1104002Y681560D02*
X1122702Y700259D01*
G01X1104002Y683893D02*
X1122702Y702593D01*
G01X1104002Y686226D02*
X1122702Y704926D01*
G01X1104002Y688560D02*
X1122702Y707259D01*
G01Y677690D02*
X1104002Y696390D01*
G01X1122702Y675357D02*
X1104002Y694057D01*
G01X1122702Y673023D02*
X1104002Y691723D01*
G01X1122702Y670690D02*
X1104002Y689390D01*
G01X1122702Y668356D02*
X1104002Y687056D01*
G01X1122702Y666022D02*
X1104002Y684722D01*
G01X1122702Y663689D02*
X1104002Y682389D01*
G01X1122702Y661356D02*
X1104002Y680056D01*
G01X1122702Y712692D02*
X1120565Y714829D01*
G01X1122702Y710359D02*
X1118231Y714829D01*
G01X1122702Y708025D02*
X1115897Y714829D01*
G01X1122702Y705692D02*
X1113564Y714829D01*
G01X1104002Y690893D02*
X1122702Y709593D01*
G01X1104002Y693226D02*
X1122702Y711926D01*
G01X1104002Y695561D02*
X1122702Y714259D01*
G01X1104002Y697894D02*
X1120937Y714829D01*
G01X1104002Y700227D02*
X1118604Y714829D01*
G01X1104002Y702561D02*
X1116270Y714829D01*
G01X1104002Y704894D02*
X1113937Y714829D01*
G01X1104002Y707227D02*
X1111604Y714829D01*
G01X1104002Y709561D02*
X1109270Y714829D01*
G01X1104002Y711894D02*
X1106937Y714829D01*
G01X1104002Y714228D02*
X1104604Y714829D01*
G01X1122702Y703358D02*
X1111231Y714829D01*
G01X1122702Y701024D02*
X1108897Y714829D01*
G01X1122702Y698691D02*
X1106564Y714829D01*
G01X1122702Y696358D02*
X1104231Y714829D01*
G01X1122702Y694024D02*
X1104002Y712724D01*
G01X1122702Y691691D02*
X1104002Y710391D01*
G01X1122702Y689358D02*
X1104002Y708057D01*
G01X1122702Y687023D02*
X1104002Y705723D01*
G01X1122702Y684690D02*
X1104002Y703390D01*
G01X1122702Y682357D02*
X1104002Y701056D01*
G01X1122702Y680023D02*
X1104002Y698723D01*
G01Y714829D02*
X1122702D01*
G01X1104002Y660559D02*
X1122702Y679259D01*
G01X1104002Y662892D02*
X1122702Y681592D01*
G01X1104002Y665225D02*
X1122702Y683925D01*
G01X1104002Y667559D02*
X1122702Y686258D01*
G01X1104002Y669892D02*
X1122702Y688592D01*
G01X1104002Y672225D02*
X1122702Y690925D01*
G01X1104002Y674559D02*
X1122702Y693258D01*
G01X1104002Y676892D02*
X1122702Y695592D01*
G01X1104002Y679226D02*
X1122702Y697926D01*
G01X1104002Y681560D02*
X1122702Y700259D01*
G01X1104002Y683893D02*
X1122702Y702593D01*
G01X1104002Y686226D02*
X1122702Y704926D01*
G01X1104002Y688560D02*
X1122702Y707259D01*
G01Y677690D02*
X1104002Y696390D01*
G01X1122702Y675357D02*
X1104002Y694057D01*
G01X1122702Y673023D02*
X1104002Y691723D01*
G01X1122702Y670690D02*
X1104002Y689390D01*
G01X1122702Y668356D02*
X1104002Y687056D01*
G01X1122702Y666022D02*
X1104002Y684722D01*
G01X1122702Y663689D02*
X1104002Y682389D01*
G01X1122702Y661356D02*
X1104002Y680056D01*
G01X1181002Y658221D02*
X1199702Y676921D01*
G01Y659026D02*
X1181002Y677726D01*
G01X1197662Y632879D02*
X1199702Y634919D01*
G01X1195328Y632879D02*
X1199702Y637252D01*
G01X1192995Y632879D02*
X1199702Y639586D01*
G01X1190662Y632879D02*
X1199702Y641919D01*
G01X1188328Y632879D02*
X1199702Y644252D01*
G01X1185995Y632879D02*
X1199702Y646585D01*
G01X1183662Y632879D02*
X1199702Y648919D01*
G01X1181327Y632879D02*
X1199702Y651253D01*
G01X1181002Y634887D02*
X1199702Y653586D01*
G01X1181002Y637220D02*
X1199702Y655920D01*
G01X1181002Y639553D02*
X1199702Y658253D01*
G01X1181002Y641887D02*
X1199702Y660586D01*
G01X1181002Y644220D02*
X1199702Y662920D01*
G01X1181002Y646553D02*
X1199702Y665253D01*
G01X1181002Y648888D02*
X1199702Y667586D01*
G01X1181002Y651221D02*
X1199702Y669921D01*
G01X1181002Y653554D02*
X1199702Y672254D01*
G01X1181002Y655888D02*
X1199702Y674587D01*
G01Y656693D02*
X1181002Y675393D01*
G01X1199702Y654359D02*
X1181002Y673059D01*
G01X1199702Y652026D02*
X1181002Y670726D01*
G01X1199702Y649693D02*
X1181002Y668393D01*
G01X1199702Y647360D02*
X1181002Y666059D01*
G01X1199702Y645025D02*
X1181002Y663725D01*
G01X1199702Y642692D02*
X1181002Y661392D01*
G01X1199702Y640359D02*
X1181002Y659058D01*
G01X1199702Y638025D02*
X1181002Y656725D01*
G01X1199702Y635692D02*
X1181002Y654392D01*
G01X1199702Y633359D02*
X1181002Y652058D01*
G01X1197847Y632879D02*
X1181002Y649725D01*
G01X1195514Y632879D02*
X1181002Y647392D01*
G01X1193181Y632879D02*
X1181002Y645057D01*
G01X1190847Y632879D02*
X1181002Y642724D01*
G01X1188514Y632879D02*
X1181002Y640391D01*
G01X1186181Y632879D02*
X1181002Y638057D01*
G01X1183846Y632879D02*
X1181002Y635724D01*
G01X1181513Y632879D02*
X1181002Y633391D01*
G01X1199702Y632879D02*
X1181002D01*
G01X1199702Y714829D02*
Y632879D01*
G01X1181002D02*
Y714829D01*
G01Y658221D02*
X1199702Y676921D01*
G01Y659026D02*
X1181002Y677726D01*
G01X1197662Y632879D02*
X1199702Y634919D01*
G01X1195328Y632879D02*
X1199702Y637252D01*
G01X1192995Y632879D02*
X1199702Y639586D01*
G01X1190662Y632879D02*
X1199702Y641919D01*
G01X1188328Y632879D02*
X1199702Y644252D01*
G01X1185995Y632879D02*
X1199702Y646585D01*
G01X1183662Y632879D02*
X1199702Y648919D01*
G01X1181327Y632879D02*
X1199702Y651253D01*
G01X1181002Y634887D02*
X1199702Y653586D01*
G01X1181002Y637220D02*
X1199702Y655920D01*
G01X1181002Y639553D02*
X1199702Y658253D01*
G01X1181002Y641887D02*
X1199702Y660586D01*
G01X1181002Y644220D02*
X1199702Y662920D01*
G01X1181002Y646553D02*
X1199702Y665253D01*
G01X1181002Y648888D02*
X1199702Y667586D01*
G01X1181002Y651221D02*
X1199702Y669921D01*
G01X1181002Y653554D02*
X1199702Y672254D01*
G01X1181002Y655888D02*
X1199702Y674587D01*
G01Y656693D02*
X1181002Y675393D01*
G01X1199702Y654359D02*
X1181002Y673059D01*
G01X1199702Y652026D02*
X1181002Y670726D01*
G01X1199702Y649693D02*
X1181002Y668393D01*
G01X1199702Y647360D02*
X1181002Y666059D01*
G01X1199702Y645025D02*
X1181002Y663725D01*
G01X1199702Y642692D02*
X1181002Y661392D01*
G01X1199702Y640359D02*
X1181002Y659058D01*
G01X1199702Y638025D02*
X1181002Y656725D01*
G01X1199702Y635692D02*
X1181002Y654392D01*
G01X1199702Y633359D02*
X1181002Y652058D01*
G01X1197847Y632879D02*
X1181002Y649725D01*
G01X1195514Y632879D02*
X1181002Y647392D01*
G01X1193181Y632879D02*
X1181002Y645057D01*
G01X1190847Y632879D02*
X1181002Y642724D01*
G01X1188514Y632879D02*
X1181002Y640391D01*
G01X1186181Y632879D02*
X1181002Y638057D01*
G01X1183846Y632879D02*
X1181002Y635724D01*
G01X1181513Y632879D02*
X1181002Y633391D01*
G01X1199702Y632879D02*
X1181002D01*
G01X1199702Y714829D02*
Y632879D01*
G01X1181002D02*
Y714829D01*
G01Y690889D02*
X1199702Y709589D01*
G01X1181002Y693223D02*
X1199702Y711922D01*
G01X1181002Y695556D02*
X1199702Y714256D01*
G01X1181002Y697889D02*
X1197941Y714829D01*
G01X1181002Y700223D02*
X1195608Y714829D01*
G01X1181002Y702557D02*
X1193275Y714829D01*
G01X1181002Y704890D02*
X1190940Y714829D01*
G01X1181002Y707224D02*
X1188607Y714829D01*
G01X1181002Y709557D02*
X1186274Y714829D01*
G01X1181002Y711890D02*
X1183940Y714829D01*
G01X1181002Y714224D02*
X1181607Y714829D01*
G01X1199702Y712695D02*
X1197568Y714829D01*
G01X1199702Y710362D02*
X1195235Y714829D01*
G01X1199702Y708029D02*
X1192902Y714829D01*
G01X1199702Y705696D02*
X1190569Y714829D01*
G01X1199702Y703362D02*
X1188234Y714829D01*
G01X1199702Y701029D02*
X1185901Y714829D01*
G01X1199702Y698696D02*
X1183568Y714829D01*
G01X1199702Y696361D02*
X1181234Y714829D01*
G01X1199702Y694028D02*
X1181002Y712728D01*
G01X1199702Y691695D02*
X1181002Y710394D01*
G01Y714829D02*
X1199702D01*
G01X1181002Y660554D02*
X1199702Y679254D01*
G01X1181002Y662888D02*
X1199702Y681587D01*
G01X1181002Y665221D02*
X1199702Y683921D01*
G01X1181002Y667555D02*
X1199702Y686255D01*
G01X1181002Y669888D02*
X1199702Y688588D01*
G01X1181002Y672222D02*
X1199702Y690922D01*
G01X1181002Y674555D02*
X1199702Y693255D01*
G01X1181002Y676888D02*
X1199702Y695588D01*
G01X1181002Y679222D02*
X1199702Y697922D01*
G01X1181002Y681555D02*
X1199702Y700255D01*
G01X1181002Y683888D02*
X1199702Y702588D01*
G01X1181002Y686223D02*
X1199702Y704922D01*
G01X1181002Y688556D02*
X1199702Y707256D01*
G01Y689361D02*
X1181002Y708061D01*
G01X1199702Y687028D02*
X1181002Y705728D01*
G01X1199702Y684695D02*
X1181002Y703394D01*
G01X1199702Y682361D02*
X1181002Y701061D01*
G01X1199702Y680027D02*
X1181002Y698727D01*
G01X1199702Y677694D02*
X1181002Y696393D01*
G01X1199702Y675360D02*
X1181002Y694060D01*
G01X1199702Y673027D02*
X1181002Y691727D01*
G01X1199702Y670694D02*
X1181002Y689393D01*
G01X1199702Y668360D02*
X1181002Y687060D01*
G01X1199702Y666027D02*
X1181002Y684727D01*
G01X1199702Y663694D02*
X1181002Y682392D01*
G01X1199702Y661359D02*
X1181002Y680059D01*
G01Y690889D02*
X1199702Y709589D01*
G01X1181002Y693223D02*
X1199702Y711922D01*
G01X1181002Y695556D02*
X1199702Y714256D01*
G01X1181002Y697889D02*
X1197941Y714829D01*
G01X1181002Y700223D02*
X1195608Y714829D01*
G01X1181002Y702557D02*
X1193275Y714829D01*
G01X1181002Y704890D02*
X1190940Y714829D01*
G01X1181002Y707224D02*
X1188607Y714829D01*
G01X1181002Y709557D02*
X1186274Y714829D01*
G01X1181002Y711890D02*
X1183940Y714829D01*
G01X1181002Y714224D02*
X1181607Y714829D01*
G01X1199702Y712695D02*
X1197568Y714829D01*
G01X1199702Y710362D02*
X1195235Y714829D01*
G01X1199702Y708029D02*
X1192902Y714829D01*
G01X1199702Y705696D02*
X1190569Y714829D01*
G01X1199702Y703362D02*
X1188234Y714829D01*
G01X1199702Y701029D02*
X1185901Y714829D01*
G01X1199702Y698696D02*
X1183568Y714829D01*
G01X1199702Y696361D02*
X1181234Y714829D01*
G01X1199702Y694028D02*
X1181002Y712728D01*
G01X1199702Y691695D02*
X1181002Y710394D01*
G01Y714829D02*
X1199702D01*
G01X1181002Y660554D02*
X1199702Y679254D01*
G01X1181002Y662888D02*
X1199702Y681587D01*
G01X1181002Y665221D02*
X1199702Y683921D01*
G01X1181002Y667555D02*
X1199702Y686255D01*
G01X1181002Y669888D02*
X1199702Y688588D01*
G01X1181002Y672222D02*
X1199702Y690922D01*
G01X1181002Y674555D02*
X1199702Y693255D01*
G01X1181002Y676888D02*
X1199702Y695588D01*
G01X1181002Y679222D02*
X1199702Y697922D01*
G01X1181002Y681555D02*
X1199702Y700255D01*
G01X1181002Y683888D02*
X1199702Y702588D01*
G01X1181002Y686223D02*
X1199702Y704922D01*
G01X1181002Y688556D02*
X1199702Y707256D01*
G01Y689361D02*
X1181002Y708061D01*
G01X1199702Y687028D02*
X1181002Y705728D01*
G01X1199702Y684695D02*
X1181002Y703394D01*
G01X1199702Y682361D02*
X1181002Y701061D01*
G01X1199702Y680027D02*
X1181002Y698727D01*
G01X1199702Y677694D02*
X1181002Y696393D01*
G01X1199702Y675360D02*
X1181002Y694060D01*
G01X1199702Y673027D02*
X1181002Y691727D01*
G01X1199702Y670694D02*
X1181002Y689393D01*
G01X1199702Y668360D02*
X1181002Y687060D01*
G01X1199702Y666027D02*
X1181002Y684727D01*
G01X1199702Y663694D02*
X1181002Y682392D01*
G01X1199702Y661359D02*
X1181002Y680059D01*
M02*
